G04 ================== begin FILE IDENTIFICATION RECORD ==================*
G04 Layout Name:  D:/<user>/Wistron_project/16315-1/gbr/16315-1.brd*
G04 Film Name:    16315-1_X_Y*
G04 File Format:  Gerber RS274X*
G04 File Origin:  Cadence Allegro 16.5-S056*
G04 Origin Date:  Fri Jun 09 15:30:00 2017*
G04 *
G04 Layer:  BOARD GEOMETRY/PANEL_DRAWING*
G04 *
G04 Offset:    (0.00 0.00)*
G04 Mirror:    No*
G04 Mode:      Positive*
G04 Rotation:  0*
G04 FullContactRelief:  No*
G04 UndefLineWidth:     6.00*
G04 ================== end FILE IDENTIFICATION RECORD ====================*
%FSLAX35Y35*MOIN*%
%IR0*IPPOS*OFA0.00000B0.00000*MIA0B0*SFA1.00000B1.00000*%
%ADD10C,.006*%
G75*
%LPD*%
G75*
G54D10*
G01X-136283Y-231392D02*
X-135570Y-232533D01*
X-134715Y-233293D01*
X-133716Y-233673D01*
X-132575Y-233293D01*
X-131720Y-232533D01*
X-130864Y-231392D01*
X-130579Y-229871D01*
Y-222266D01*
G01X-135142Y-6384D02*
X-131720D01*
G01X-133431D02*
Y-17791D01*
G01X-135142D02*
X-131720D01*
G01X-136426Y197901D02*
Y209308D01*
G01X-130436D02*
Y197901D01*
G01Y203604D02*
X-136426D01*
G01X-132575Y419486D02*
X-129723D01*
Y416064D01*
X-130579Y414923D01*
X-131577Y414163D01*
X-133003Y413783D01*
X-134429Y414163D01*
X-135427Y414923D01*
X-136283Y416064D01*
X-136854Y417395D01*
X-137139Y418916D01*
Y420247D01*
X-136854Y421387D01*
X-136283Y422719D01*
X-135427Y423859D01*
X-134572Y424619D01*
X-133431Y425190D01*
X-132433D01*
X-131292Y424810D01*
X-130436Y424049D01*
G01X-136518Y629855D02*
Y641262D01*
X-131100D01*
G01X-133096Y635749D02*
X-136518D01*
G01X-130579Y845926D02*
X-136283D01*
Y857333D01*
X-130579D01*
G01X-132861Y851820D02*
X-136283D01*
G01X-136568Y1061618D02*
Y1073025D01*
X-133716D01*
X-132575Y1072454D01*
X-131720Y1071694D01*
X-131007Y1070554D01*
X-130436Y1069222D01*
X-130294Y1067321D01*
X-130436Y1065420D01*
X-131007Y1064089D01*
X-131720Y1062949D01*
X-132575Y1062188D01*
X-133716Y1061618D01*
X-136568D01*
G01X-130294Y1288146D02*
X-131149Y1288717D01*
X-132147Y1289097D01*
X-133288D01*
X-134572Y1288526D01*
X-135570Y1287576D01*
X-136283Y1286435D01*
X-136854Y1284534D01*
X-136996Y1282823D01*
X-136711Y1281112D01*
X-136283Y1279971D01*
X-135427Y1278830D01*
X-134429Y1278070D01*
X-133431Y1277690D01*
X-132433D01*
X-131435Y1278070D01*
X-130579Y1278640D01*
X-129866Y1279401D01*
G01X-132290Y1499466D02*
X-131720Y1500036D01*
X-131292Y1500986D01*
X-131007Y1502318D01*
X-131292Y1503458D01*
X-131862Y1504218D01*
X-132861Y1504789D01*
X-136711D01*
Y1493382D01*
X-132005D01*
X-131007Y1494142D01*
X-130436Y1495283D01*
X-130151Y1496614D01*
X-130436Y1497945D01*
X-131292Y1499085D01*
X-132290Y1499466D01*
X-136711D01*
G01X-136996Y1709264D02*
X-133431Y1720671D01*
X-129866Y1709264D01*
G01X-131149Y1713256D02*
X-135713D01*
G01X-49173Y-148819D02*
X-49961Y-149081D01*
X-50551Y-149738D01*
X-50945Y-150525D01*
X-51240Y-151575D01*
X-51339Y-152756D01*
X-51240Y-153937D01*
X-50945Y-154987D01*
X-50551Y-155775D01*
X-49961Y-156431D01*
X-49173Y-156693D01*
X-48386Y-156431D01*
X-47795Y-155775D01*
X-47401Y-154987D01*
X-47106Y-153937D01*
X-47007Y-152756D01*
X-47106Y-151575D01*
X-47401Y-150525D01*
X-47795Y-149738D01*
X-48386Y-149081D01*
X-49173Y-148819D01*
G01X-41298Y-156955D02*
X-41495Y-156824D01*
Y-156562D01*
X-41298Y-156431D01*
X-41101Y-156562D01*
Y-156824D01*
X-41298Y-156955D01*
G01X-33423Y-148819D02*
X-34211Y-149081D01*
X-34801Y-149738D01*
X-35195Y-150525D01*
X-35490Y-151575D01*
X-35589Y-152756D01*
X-35490Y-153937D01*
X-35195Y-154987D01*
X-34801Y-155775D01*
X-34211Y-156431D01*
X-33423Y-156693D01*
X-32636Y-156431D01*
X-32045Y-155775D01*
X-31651Y-154987D01*
X-31356Y-153937D01*
X-31257Y-152756D01*
X-31356Y-151575D01*
X-31651Y-150525D01*
X-32045Y-149738D01*
X-32636Y-149081D01*
X-33423Y-148819D01*
G01X-25548D02*
X-26336Y-149081D01*
X-26926Y-149738D01*
X-27320Y-150525D01*
X-27615Y-151575D01*
X-27714Y-152756D01*
X-27615Y-153937D01*
X-27320Y-154987D01*
X-26926Y-155775D01*
X-26336Y-156431D01*
X-25548Y-156693D01*
X-24761Y-156431D01*
X-24170Y-155775D01*
X-23776Y-154987D01*
X-23481Y-153937D01*
X-23382Y-152756D01*
X-23481Y-151575D01*
X-23776Y-150525D01*
X-24170Y-149738D01*
X-24761Y-149081D01*
X-25548Y-148819D01*
G01X-62166Y1654331D02*
Y1662205D01*
X-65808Y1656562D01*
X-60886D01*
G01X-57342Y1657612D02*
X-56653Y1658531D01*
X-56063Y1659055D01*
X-55275Y1659318D01*
X-54586Y1659055D01*
X-54094Y1658531D01*
X-53700Y1657743D01*
X-53602Y1656824D01*
X-53700Y1656037D01*
X-54094Y1655249D01*
X-54685Y1654593D01*
X-55373Y1654331D01*
X-56161Y1654593D01*
X-56850Y1655381D01*
X-57244Y1656562D01*
X-57342Y1657874D01*
X-57145Y1659580D01*
X-56850Y1660499D01*
X-56358Y1661418D01*
X-55669Y1662074D01*
X-54980Y1662205D01*
X-54291Y1661943D01*
X-53799Y1661286D01*
G01X-47597Y1662205D02*
X-48385Y1661943D01*
X-48975Y1661286D01*
X-49369Y1660499D01*
X-49664Y1659449D01*
X-49763Y1658268D01*
X-49664Y1657087D01*
X-49369Y1656037D01*
X-48975Y1655249D01*
X-48385Y1654593D01*
X-47597Y1654331D01*
X-46810Y1654593D01*
X-46219Y1655249D01*
X-45825Y1656037D01*
X-45530Y1657087D01*
X-45431Y1658268D01*
X-45530Y1659449D01*
X-45825Y1660499D01*
X-46219Y1661286D01*
X-46810Y1661943D01*
X-47597Y1662205D01*
G01X-39722Y1654069D02*
X-39919Y1654200D01*
Y1654462D01*
X-39722Y1654593D01*
X-39525Y1654462D01*
Y1654200D01*
X-39722Y1654069D01*
G01X-31847Y1662205D02*
X-32635Y1661943D01*
X-33225Y1661286D01*
X-33619Y1660499D01*
X-33914Y1659449D01*
X-34013Y1658268D01*
X-33914Y1657087D01*
X-33619Y1656037D01*
X-33225Y1655249D01*
X-32635Y1654593D01*
X-31847Y1654331D01*
X-31060Y1654593D01*
X-30469Y1655249D01*
X-30075Y1656037D01*
X-29780Y1657087D01*
X-29681Y1658268D01*
X-29780Y1659449D01*
X-30075Y1660499D01*
X-30469Y1661286D01*
X-31060Y1661943D01*
X-31847Y1662205D01*
G01X-23972D02*
X-24760Y1661943D01*
X-25350Y1661286D01*
X-25744Y1660499D01*
X-26039Y1659449D01*
X-26138Y1658268D01*
X-26039Y1657087D01*
X-25744Y1656037D01*
X-25350Y1655249D01*
X-24760Y1654593D01*
X-23972Y1654331D01*
X-23185Y1654593D01*
X-22594Y1655249D01*
X-22200Y1656037D01*
X-21905Y1657087D01*
X-21806Y1658268D01*
X-21905Y1659449D01*
X-22200Y1660499D01*
X-22594Y1661286D01*
X-23185Y1661943D01*
X-23972Y1662205D01*
G01X-6553Y-351083D02*
Y-339676D01*
X-8264Y-341957D01*
G01Y-351083D02*
X-4842D01*
G01X-3937Y1730971D02*
X-3675Y1730183D01*
X-3018Y1729593D01*
X-2231Y1729199D01*
X-1181Y1728904D01*
X0Y1728805D01*
X1181Y1728904D01*
X2231Y1729199D01*
X3019Y1729593D01*
X3675Y1730183D01*
X3937Y1730971D01*
X3675Y1731758D01*
X3019Y1732349D01*
X2231Y1732743D01*
X1181Y1733038D01*
X0Y1733137D01*
X-1181Y1733038D01*
X-2231Y1732743D01*
X-3018Y1732349D01*
X-3675Y1731758D01*
X-3937Y1730971D01*
G01X4199Y1738846D02*
X4068Y1738649D01*
X3806D01*
X3675Y1738846D01*
X3806Y1739043D01*
X4068D01*
X4199Y1738846D01*
G01X-3937Y1746721D02*
X-3675Y1745933D01*
X-3018Y1745343D01*
X-2231Y1744949D01*
X-1181Y1744654D01*
X0Y1744555D01*
X1181Y1744654D01*
X2231Y1744949D01*
X3019Y1745343D01*
X3675Y1745933D01*
X3937Y1746721D01*
X3675Y1747508D01*
X3019Y1748099D01*
X2231Y1748493D01*
X1181Y1748788D01*
X0Y1748887D01*
X-1181Y1748788D01*
X-2231Y1748493D01*
X-3018Y1748099D01*
X-3675Y1747508D01*
X-3937Y1746721D01*
G01Y1754596D02*
X-3675Y1753808D01*
X-3018Y1753218D01*
X-2231Y1752824D01*
X-1181Y1752529D01*
X0Y1752430D01*
X1181Y1752529D01*
X2231Y1752824D01*
X3019Y1753218D01*
X3675Y1753808D01*
X3937Y1754596D01*
X3675Y1755383D01*
X3019Y1755974D01*
X2231Y1756368D01*
X1181Y1756663D01*
X0Y1756762D01*
X-1181Y1756663D01*
X-2231Y1756368D01*
X-3018Y1755974D01*
X-3675Y1755383D01*
X-3937Y1754596D01*
G01X-6553Y1826673D02*
Y1838080D01*
X-8264Y1835799D01*
G01Y1826673D02*
X-4842D01*
G01X208514Y-341577D02*
X209369Y-340437D01*
X210367Y-339866D01*
X211508Y-339676D01*
X212934Y-340056D01*
X213932Y-341007D01*
X214218Y-342147D01*
X214075Y-343288D01*
X213505Y-344239D01*
X210653Y-346140D01*
X209369Y-347471D01*
X208514Y-349372D01*
X208228Y-351083D01*
X214218D01*
G01X208514Y1836179D02*
X209369Y1837319D01*
X210367Y1837890D01*
X211508Y1838080D01*
X212934Y1837700D01*
X213932Y1836749D01*
X214218Y1835609D01*
X214075Y1834468D01*
X213505Y1833517D01*
X210653Y1831616D01*
X209369Y1830285D01*
X208514Y1828384D01*
X208228Y1826673D01*
X214218D01*
G01X427755Y-348802D02*
X428610Y-350133D01*
X429751Y-350893D01*
X431035Y-351083D01*
X432176Y-350893D01*
X433316Y-349943D01*
X434029Y-348802D01*
X434172Y-347661D01*
X433887Y-346330D01*
X432888Y-345380D01*
X431890Y-344999D01*
X430607D01*
G01X431890D02*
X432746Y-344429D01*
X433459Y-343479D01*
X433744Y-342338D01*
X433459Y-341197D01*
X432746Y-340247D01*
X431462Y-339676D01*
X430179Y-339866D01*
X428896Y-340627D01*
G01X427755Y1828954D02*
X428610Y1827623D01*
X429751Y1826863D01*
X431035Y1826673D01*
X432176Y1826863D01*
X433316Y1827813D01*
X434029Y1828954D01*
X434172Y1830095D01*
X433887Y1831426D01*
X432888Y1832376D01*
X431890Y1832757D01*
X430607D01*
G01X431890D02*
X432746Y1833327D01*
X433459Y1834277D01*
X433744Y1835418D01*
X433459Y1836559D01*
X432746Y1837509D01*
X431462Y1838080D01*
X430179Y1837890D01*
X428896Y1837129D01*
G01X652272Y-351083D02*
Y-339676D01*
X646996Y-347851D01*
X654126D01*
G01X652272Y1826673D02*
Y1838080D01*
X646996Y1829905D01*
X654126D01*
G01X867094Y-349372D02*
X867949Y-350323D01*
X868947Y-350893D01*
X870231Y-351083D01*
X871515Y-350703D01*
X872513Y-349943D01*
X873226Y-348612D01*
X873368Y-347091D01*
X873083Y-345570D01*
X872370Y-344619D01*
X871372Y-343859D01*
X870374Y-343669D01*
X869375Y-343859D01*
X868092Y-344619D01*
X868520Y-339676D01*
X872370D01*
G01X867094Y1828384D02*
X867949Y1827433D01*
X868947Y1826863D01*
X870231Y1826673D01*
X871515Y1827053D01*
X872513Y1827813D01*
X873226Y1829144D01*
X873368Y1830665D01*
X873083Y1832186D01*
X872370Y1833137D01*
X871372Y1833897D01*
X870374Y1834087D01*
X869375Y1833897D01*
X868092Y1833137D01*
X868520Y1838080D01*
X872370D01*
G01X1014742Y853040D02*
Y837440D01*
G01X1010257Y853040D02*
X1019227D01*
G01X1087191Y-346330D02*
X1088189Y-344999D01*
X1089044Y-344239D01*
X1090185Y-343859D01*
X1091184Y-344239D01*
X1091896Y-344999D01*
X1092467Y-346140D01*
X1092609Y-347471D01*
X1092467Y-348612D01*
X1091896Y-349752D01*
X1091041Y-350703D01*
X1090043Y-351083D01*
X1088902Y-350703D01*
X1087904Y-349562D01*
X1087333Y-347851D01*
X1087191Y-345950D01*
X1087476Y-343479D01*
X1087904Y-342147D01*
X1088616Y-340817D01*
X1089615Y-339866D01*
X1090613Y-339676D01*
X1091611Y-340056D01*
X1092324Y-341007D01*
G01X1087191Y1831426D02*
X1088189Y1832757D01*
X1089044Y1833517D01*
X1090185Y1833897D01*
X1091184Y1833517D01*
X1091896Y1832757D01*
X1092467Y1831616D01*
X1092609Y1830285D01*
X1092467Y1829144D01*
X1091896Y1828004D01*
X1091041Y1827053D01*
X1090043Y1826673D01*
X1088902Y1827053D01*
X1087904Y1828194D01*
X1087333Y1829905D01*
X1087191Y1831806D01*
X1087476Y1834277D01*
X1087904Y1835609D01*
X1088616Y1836939D01*
X1089615Y1837890D01*
X1090613Y1838080D01*
X1091611Y1837700D01*
X1092324Y1836749D01*
G01X1309284Y-351083D02*
X1309569Y-348612D01*
X1309997Y-346520D01*
X1310567Y-344619D01*
X1311280Y-342528D01*
X1312421Y-339676D01*
X1306717D01*
G01X1309284Y1826673D02*
X1309569Y1829144D01*
X1309997Y1831236D01*
X1310567Y1833137D01*
X1311280Y1835228D01*
X1312421Y1838080D01*
X1306717D01*
G01X1529239Y-351083D02*
X1530237Y-350893D01*
X1531378Y-350323D01*
X1532091Y-349372D01*
X1532376Y-348041D01*
X1532091Y-346711D01*
X1531235Y-345570D01*
X1529952Y-344999D01*
X1528526D01*
X1527670Y-344619D01*
X1526957Y-343669D01*
X1526672Y-342338D01*
X1527100Y-341007D01*
X1528098Y-340056D01*
X1529239Y-339676D01*
X1530380Y-340056D01*
X1531378Y-341007D01*
X1531806Y-342338D01*
X1531521Y-343669D01*
X1530808Y-344619D01*
X1529952Y-344999D01*
X1528526D01*
X1527243Y-345570D01*
X1526387Y-346711D01*
X1526102Y-348041D01*
X1526387Y-349372D01*
X1527100Y-350323D01*
X1528241Y-350893D01*
X1529239Y-351083D01*
G01Y1826673D02*
X1530237Y1826863D01*
X1531378Y1827433D01*
X1532091Y1828384D01*
X1532376Y1829715D01*
X1532091Y1831045D01*
X1531235Y1832186D01*
X1529952Y1832757D01*
X1528526D01*
X1527670Y1833137D01*
X1526957Y1834087D01*
X1526672Y1835418D01*
X1527100Y1836749D01*
X1528098Y1837700D01*
X1529239Y1838080D01*
X1530380Y1837700D01*
X1531378Y1836749D01*
X1531806Y1835418D01*
X1531521Y1834087D01*
X1530808Y1833137D01*
X1529952Y1832757D01*
X1528526D01*
X1527243Y1832186D01*
X1526387Y1831045D01*
X1526102Y1829715D01*
X1526387Y1828384D01*
X1527100Y1827433D01*
X1528241Y1826863D01*
X1529239Y1826673D01*
G01X1746484Y-349752D02*
X1747482Y-350703D01*
X1748623Y-351083D01*
X1749764Y-350703D01*
X1750762Y-349562D01*
X1751475Y-347851D01*
X1751760Y-346140D01*
Y-344049D01*
X1751475Y-342338D01*
X1750762Y-340817D01*
X1749906Y-340056D01*
X1748908Y-339676D01*
X1747767Y-340056D01*
X1746912Y-340817D01*
X1746341Y-341957D01*
X1746056Y-343479D01*
X1746341Y-344809D01*
X1747054Y-346140D01*
X1747910Y-346901D01*
X1748908Y-347091D01*
X1750049Y-346711D01*
X1750904Y-345760D01*
X1751760Y-344049D01*
G01X1746484Y1828004D02*
X1747482Y1827053D01*
X1748623Y1826673D01*
X1749764Y1827053D01*
X1750762Y1828194D01*
X1751475Y1829905D01*
X1751760Y1831616D01*
Y1833707D01*
X1751475Y1835418D01*
X1750762Y1836939D01*
X1749906Y1837700D01*
X1748908Y1838080D01*
X1747767Y1837700D01*
X1746912Y1836939D01*
X1746341Y1835799D01*
X1746056Y1834277D01*
X1746341Y1832947D01*
X1747054Y1831616D01*
X1747910Y1830855D01*
X1748908Y1830665D01*
X1750049Y1831045D01*
X1750904Y1831996D01*
X1751760Y1833707D01*
G01X1938780Y1732152D02*
X1930906D01*
X1936549Y1728510D01*
Y1733432D01*
G01X1937862Y1737173D02*
X1938518Y1737862D01*
X1938780Y1738649D01*
X1938518Y1739437D01*
X1937730Y1740126D01*
X1936549Y1740618D01*
X1935368Y1740815D01*
X1933924D01*
X1932743Y1740618D01*
X1931693Y1740126D01*
X1931168Y1739535D01*
X1930906Y1738846D01*
X1931168Y1738058D01*
X1931693Y1737468D01*
X1932481Y1737074D01*
X1933531Y1736877D01*
X1934449Y1737074D01*
X1935368Y1737566D01*
X1935893Y1738157D01*
X1936024Y1738846D01*
X1935762Y1739633D01*
X1935106Y1740224D01*
X1933924Y1740815D01*
G01X1938780Y1746721D02*
X1930906D01*
X1932481Y1745540D01*
G01X1938780D02*
Y1747902D01*
G01X1939042Y1754596D02*
X1938911Y1754399D01*
X1938649D01*
X1938518Y1754596D01*
X1938649Y1754793D01*
X1938911D01*
X1939042Y1754596D01*
G01X1938780Y1763652D02*
X1930906D01*
X1936549Y1760010D01*
Y1764932D01*
G01X1937599Y1768180D02*
X1938255Y1768771D01*
X1938649Y1769460D01*
X1938780Y1770346D01*
X1938518Y1771232D01*
X1937993Y1771921D01*
X1937074Y1772413D01*
X1936024Y1772512D01*
X1934974Y1772315D01*
X1934318Y1771822D01*
X1933793Y1771133D01*
X1933662Y1770445D01*
X1933793Y1769755D01*
X1934318Y1768870D01*
X1930906Y1769165D01*
Y1771822D01*
G01X1965926Y-351083D02*
Y-339676D01*
X1964215Y-341957D01*
G01Y-351083D02*
X1967637D01*
G01X1977334Y-339676D02*
X1976193Y-340056D01*
X1975338Y-341007D01*
X1974767Y-342147D01*
X1974339Y-343669D01*
X1974197Y-345380D01*
X1974339Y-347091D01*
X1974767Y-348612D01*
X1975338Y-349752D01*
X1976193Y-350703D01*
X1977334Y-351083D01*
X1978475Y-350703D01*
X1979330Y-349752D01*
X1979901Y-348612D01*
X1980329Y-347091D01*
X1980471Y-345380D01*
X1980329Y-343669D01*
X1979901Y-342147D01*
X1979330Y-341007D01*
X1978475Y-340056D01*
X1977334Y-339676D01*
G01X1965926Y1826673D02*
Y1838080D01*
X1964215Y1835799D01*
G01Y1826673D02*
X1967637D01*
G01X1977334Y1838080D02*
X1976193Y1837700D01*
X1975338Y1836749D01*
X1974767Y1835609D01*
X1974339Y1834087D01*
X1974197Y1832376D01*
X1974339Y1830665D01*
X1974767Y1829144D01*
X1975338Y1828004D01*
X1976193Y1827053D01*
X1977334Y1826673D01*
X1978475Y1827053D01*
X1979330Y1828004D01*
X1979901Y1829144D01*
X1980329Y1830665D01*
X1980471Y1832376D01*
X1980329Y1834087D01*
X1979901Y1835609D01*
X1979330Y1836749D01*
X1978475Y1837700D01*
X1977334Y1838080D01*
G01X2035647Y-234875D02*
X2034147Y-233875D01*
X2032397Y-233208D01*
X2030397D01*
X2028147Y-234208D01*
X2026397Y-235875D01*
X2025147Y-237875D01*
X2024147Y-241208D01*
X2023897Y-244208D01*
X2024397Y-247208D01*
X2025147Y-249208D01*
X2026647Y-251208D01*
X2028397Y-252541D01*
X2030147Y-253208D01*
X2031897D01*
X2033647Y-252541D01*
X2035147Y-251542D01*
X2036397Y-250209D01*
G01X2046647Y-253208D02*
Y-239875D01*
G01Y-242541D02*
X2047897Y-241208D01*
X2049147Y-240208D01*
X2050897Y-239875D01*
X2052147Y-240208D01*
X2053647Y-241208D01*
G01X2066397Y-244208D02*
X2074397D01*
X2073647Y-241875D01*
X2072397Y-240542D01*
X2070647Y-239875D01*
X2068897Y-240208D01*
X2067397Y-241208D01*
X2066397Y-243542D01*
X2065897Y-245542D01*
Y-247541D01*
X2066397Y-249542D01*
X2067647Y-251542D01*
X2069147Y-252875D01*
X2070897Y-253208D01*
X2072647Y-252541D01*
X2074397Y-250542D01*
G01X2094647Y-253208D02*
Y-239875D01*
G01Y-242208D02*
X2093647Y-240875D01*
X2092147Y-240208D01*
X2090397Y-239875D01*
X2088647Y-240542D01*
X2087147Y-241875D01*
X2086147Y-243875D01*
X2085647Y-246542D01*
X2086147Y-249208D01*
X2087147Y-251208D01*
X2088647Y-252541D01*
X2090397Y-253208D01*
X2092147Y-252875D01*
X2093647Y-251875D01*
X2094647Y-250542D01*
G01X2110147Y-233208D02*
Y-253208D01*
G01X2106647Y-239875D02*
X2113647D01*
G01X2126397Y-244208D02*
X2134397D01*
X2133647Y-241875D01*
X2132397Y-240542D01*
X2130647Y-239875D01*
X2128897Y-240208D01*
X2127397Y-241208D01*
X2126397Y-243542D01*
X2125897Y-245542D01*
Y-247541D01*
X2126397Y-249542D01*
X2127647Y-251542D01*
X2129147Y-252875D01*
X2130897Y-253208D01*
X2132647Y-252541D01*
X2134397Y-250542D01*
G01X2154647Y-233208D02*
Y-253208D01*
G01Y-250209D02*
X2153647Y-251875D01*
X2152147Y-252875D01*
X2150397Y-253208D01*
X2148397Y-252541D01*
X2146897Y-250875D01*
X2145897Y-248875D01*
X2145647Y-246542D01*
X2145897Y-244208D01*
X2146897Y-242208D01*
X2148397Y-240542D01*
X2150397Y-239875D01*
X2152147Y-240208D01*
X2153397Y-240875D01*
X2154647Y-242208D01*
G01X2021195Y-184300D02*
X2027445Y-204300D01*
X2033695Y-184300D01*
G01X2043695Y-195300D02*
X2051695D01*
X2050945Y-192967D01*
X2049695Y-191634D01*
X2047945Y-190967D01*
X2046195Y-191300D01*
X2044695Y-192300D01*
X2043695Y-194634D01*
X2043195Y-196634D01*
Y-198633D01*
X2043695Y-200634D01*
X2044945Y-202634D01*
X2046445Y-203967D01*
X2048195Y-204300D01*
X2049945Y-203633D01*
X2051695Y-201634D01*
G01X2063945Y-204300D02*
Y-190967D01*
G01Y-193633D02*
X2065195Y-192300D01*
X2066445Y-191300D01*
X2068195Y-190967D01*
X2069445Y-191300D01*
X2070945Y-192300D01*
G01X2083695Y-201967D02*
X2084945Y-203300D01*
X2086695Y-204300D01*
X2088195D01*
X2089695Y-203633D01*
X2090695Y-202634D01*
X2091195Y-201301D01*
X2090945Y-199300D01*
X2089945Y-198300D01*
X2085445Y-196300D01*
X2084445Y-193966D01*
X2084945Y-192300D01*
X2085945Y-191300D01*
X2087445Y-190967D01*
X2088945Y-191300D01*
X2090445Y-192300D01*
G01X2107445Y-190967D02*
Y-204300D01*
G01Y-185634D02*
X2106945Y-185300D01*
Y-184633D01*
X2107445Y-184300D01*
X2107945Y-184633D01*
Y-185300D01*
X2107445Y-185634D01*
G01X2127445Y-204300D02*
X2125945Y-203967D01*
X2124445Y-202634D01*
X2123445Y-200300D01*
X2122945Y-197634D01*
X2123445Y-194967D01*
X2124445Y-192633D01*
X2125945Y-191300D01*
X2127445Y-190967D01*
X2128945Y-191300D01*
X2130445Y-192633D01*
X2131445Y-194967D01*
X2131695Y-197634D01*
X2131445Y-200300D01*
X2130445Y-202634D01*
X2128945Y-203967D01*
X2127445Y-204300D01*
G01X2143195D02*
Y-190967D01*
G01Y-194300D02*
X2144195Y-192633D01*
X2145695Y-191300D01*
X2147695Y-190967D01*
X2149445Y-191300D01*
X2150945Y-192633D01*
X2151695Y-194967D01*
Y-204300D01*
G01X2025147Y-160287D02*
Y-140287D01*
X2031147D01*
X2033147Y-141287D01*
X2034647Y-143620D01*
X2035147Y-146287D01*
X2034647Y-148954D01*
X2033397Y-150954D01*
X2031147Y-151954D01*
X2025147D01*
G01X2055647Y-141954D02*
X2054147Y-140954D01*
X2052397Y-140287D01*
X2050397D01*
X2048147Y-141287D01*
X2046397Y-142954D01*
X2045147Y-144954D01*
X2044147Y-148287D01*
X2043897Y-151287D01*
X2044397Y-154287D01*
X2045147Y-156287D01*
X2046647Y-158287D01*
X2048397Y-159620D01*
X2050147Y-160287D01*
X2051897D01*
X2053647Y-159620D01*
X2055147Y-158621D01*
X2056397Y-157288D01*
G01X2072147Y-149620D02*
X2073147Y-148620D01*
X2073897Y-146954D01*
X2074397Y-144620D01*
X2073897Y-142620D01*
X2072897Y-141287D01*
X2071147Y-140287D01*
X2064397D01*
Y-160287D01*
X2072647D01*
X2074397Y-158954D01*
X2075397Y-156954D01*
X2075897Y-154620D01*
X2075397Y-152287D01*
X2073897Y-150287D01*
X2072147Y-149620D01*
X2064397D01*
G01X2104397Y-160287D02*
Y-140287D01*
X2115897Y-160287D01*
Y-140287D01*
G01X2130147Y-160287D02*
X2128647Y-159954D01*
X2127147Y-158621D01*
X2126147Y-156287D01*
X2125647Y-153621D01*
X2126147Y-150954D01*
X2127147Y-148620D01*
X2128647Y-147287D01*
X2130147Y-146954D01*
X2131647Y-147287D01*
X2133147Y-148620D01*
X2134147Y-150954D01*
X2134397Y-153621D01*
X2134147Y-156287D01*
X2133147Y-158621D01*
X2131647Y-159954D01*
X2130147Y-160287D01*
G01X2150147Y-160954D02*
X2149647Y-160620D01*
Y-159954D01*
X2150147Y-159620D01*
X2150647Y-159954D01*
Y-160620D01*
X2150147Y-160954D01*
G01X2033591Y-116074D02*
Y-91074D01*
X2041781Y-111907D01*
X2049971Y-91074D01*
Y-116074D01*
G01X2066981D02*
X2065091Y-115657D01*
X2063201Y-113991D01*
X2061941Y-111074D01*
X2061311Y-107741D01*
X2061941Y-104408D01*
X2063201Y-101491D01*
X2065091Y-99824D01*
X2066981Y-99408D01*
X2068871Y-99824D01*
X2070761Y-101491D01*
X2072021Y-104408D01*
X2072336Y-107741D01*
X2072021Y-111074D01*
X2070761Y-113991D01*
X2068871Y-115657D01*
X2066981Y-116074D01*
G01X2097851Y-91074D02*
Y-116074D01*
G01Y-112325D02*
X2096591Y-114408D01*
X2094701Y-115657D01*
X2092496Y-116074D01*
X2089976Y-115241D01*
X2088086Y-113158D01*
X2086826Y-110658D01*
X2086511Y-107741D01*
X2086826Y-104824D01*
X2088086Y-102324D01*
X2089976Y-100241D01*
X2092496Y-99408D01*
X2094701Y-99824D01*
X2096276Y-100658D01*
X2097851Y-102324D01*
G01X2112656Y-104824D02*
X2122736D01*
X2121791Y-101907D01*
X2120216Y-100241D01*
X2118011Y-99408D01*
X2115806Y-99824D01*
X2113916Y-101074D01*
X2112656Y-103991D01*
X2112026Y-106491D01*
Y-108991D01*
X2112656Y-111491D01*
X2114231Y-113991D01*
X2116121Y-115657D01*
X2118326Y-116074D01*
X2120531Y-115241D01*
X2122736Y-112741D01*
G01X2142581Y-116074D02*
Y-91074D01*
G01X2186353Y-351083D02*
Y-339676D01*
X2184642Y-341957D01*
G01Y-351083D02*
X2188064D01*
G01X2197761D02*
Y-339676D01*
X2196050Y-341957D01*
G01Y-351083D02*
X2199472D01*
G01X2186353Y1826673D02*
Y1838080D01*
X2184642Y1835799D01*
G01Y1826673D02*
X2188064D01*
G01X2197761D02*
Y1838080D01*
X2196050Y1835799D01*
G01Y1826673D02*
X2199472D01*
G01X2203326Y-284743D02*
X2207736Y-309743D01*
X2212776Y-284743D01*
X2217816Y-309743D01*
X2222226Y-284743D01*
G01X2237976Y-293077D02*
Y-309743D01*
G01Y-286410D02*
X2237346Y-285993D01*
Y-285160D01*
X2237976Y-284743D01*
X2238606Y-285160D01*
Y-285993D01*
X2237976Y-286410D01*
G01X2258451Y-306827D02*
X2260026Y-308493D01*
X2262231Y-309743D01*
X2264121D01*
X2266011Y-308910D01*
X2267271Y-307660D01*
X2267901Y-305994D01*
X2267586Y-303493D01*
X2266326Y-302243D01*
X2260656Y-299744D01*
X2259396Y-296826D01*
X2260026Y-294743D01*
X2261286Y-293493D01*
X2263176Y-293077D01*
X2265066Y-293493D01*
X2266956Y-294743D01*
G01X2288376Y-284743D02*
Y-309743D01*
G01X2283966Y-293077D02*
X2292786D01*
G01X2309166Y-309743D02*
Y-293077D01*
G01Y-296409D02*
X2310741Y-294743D01*
X2312316Y-293493D01*
X2314521Y-293077D01*
X2316096Y-293493D01*
X2317986Y-294743D01*
G01X2338776Y-309743D02*
X2336886Y-309326D01*
X2334996Y-307660D01*
X2333736Y-304743D01*
X2333106Y-301410D01*
X2333736Y-298077D01*
X2334996Y-295160D01*
X2336886Y-293493D01*
X2338776Y-293077D01*
X2340666Y-293493D01*
X2342556Y-295160D01*
X2343816Y-298077D01*
X2344131Y-301410D01*
X2343816Y-304743D01*
X2342556Y-307660D01*
X2340666Y-309326D01*
X2338776Y-309743D01*
G01X2358621D02*
Y-293077D01*
G01Y-297243D02*
X2359881Y-295160D01*
X2361771Y-293493D01*
X2364291Y-293077D01*
X2366496Y-293493D01*
X2368386Y-295160D01*
X2369331Y-298077D01*
Y-309743D01*
G01X2421306Y-286827D02*
X2419416Y-285576D01*
X2417211Y-284743D01*
X2414691D01*
X2411856Y-285993D01*
X2409651Y-288076D01*
X2408076Y-290577D01*
X2406816Y-294743D01*
X2406501Y-298493D01*
X2407131Y-302243D01*
X2408076Y-304743D01*
X2409966Y-307244D01*
X2412171Y-308910D01*
X2414376Y-309743D01*
X2416581D01*
X2418786Y-308910D01*
X2420676Y-307660D01*
X2422251Y-305994D01*
G01X2439576Y-309743D02*
X2437686Y-309326D01*
X2435796Y-307660D01*
X2434536Y-304743D01*
X2433906Y-301410D01*
X2434536Y-298077D01*
X2435796Y-295160D01*
X2437686Y-293493D01*
X2439576Y-293077D01*
X2441466Y-293493D01*
X2443356Y-295160D01*
X2444616Y-298077D01*
X2444931Y-301410D01*
X2444616Y-304743D01*
X2443356Y-307660D01*
X2441466Y-309326D01*
X2439576Y-309743D01*
G01X2460366D02*
Y-293077D01*
G01Y-296409D02*
X2461941Y-294743D01*
X2463516Y-293493D01*
X2465721Y-293077D01*
X2467296Y-293493D01*
X2469186Y-294743D01*
G01X2484306Y-318076D02*
Y-293077D01*
G01Y-296826D02*
X2485881Y-294743D01*
X2487456Y-293493D01*
X2489976Y-293077D01*
X2492181Y-293493D01*
X2494386Y-295576D01*
X2495331Y-298493D01*
X2495646Y-301410D01*
X2495331Y-304327D01*
X2494386Y-307244D01*
X2492496Y-308910D01*
X2489976Y-309743D01*
X2487771Y-309326D01*
X2485566Y-308077D01*
X2484306Y-306410D01*
G01X2515176Y-309743D02*
X2513286Y-309326D01*
X2511396Y-307660D01*
X2510136Y-304743D01*
X2509506Y-301410D01*
X2510136Y-298077D01*
X2511396Y-295160D01*
X2513286Y-293493D01*
X2515176Y-293077D01*
X2517066Y-293493D01*
X2518956Y-295160D01*
X2520216Y-298077D01*
X2520531Y-301410D01*
X2520216Y-304743D01*
X2518956Y-307660D01*
X2517066Y-309326D01*
X2515176Y-309743D01*
G01X2535966D02*
Y-293077D01*
G01Y-296409D02*
X2537541Y-294743D01*
X2539116Y-293493D01*
X2541321Y-293077D01*
X2542896Y-293493D01*
X2544786Y-294743D01*
G01X2571246Y-309743D02*
Y-293077D01*
G01Y-295993D02*
X2569986Y-294327D01*
X2568096Y-293493D01*
X2565891Y-293077D01*
X2563686Y-293910D01*
X2561796Y-295576D01*
X2560536Y-298077D01*
X2559906Y-301410D01*
X2560536Y-304743D01*
X2561796Y-307244D01*
X2563686Y-308910D01*
X2565891Y-309743D01*
X2568096Y-309326D01*
X2569986Y-308077D01*
X2571246Y-306410D01*
G01X2590776Y-284743D02*
Y-309743D01*
G01X2586366Y-293077D02*
X2595186D01*
G01X2615976D02*
Y-309743D01*
G01Y-286410D02*
X2615346Y-285993D01*
Y-285160D01*
X2615976Y-284743D01*
X2616606Y-285160D01*
Y-285993D01*
X2615976Y-286410D01*
G01X2641176Y-309743D02*
X2639286Y-309326D01*
X2637396Y-307660D01*
X2636136Y-304743D01*
X2635506Y-301410D01*
X2636136Y-298077D01*
X2637396Y-295160D01*
X2639286Y-293493D01*
X2641176Y-293077D01*
X2643066Y-293493D01*
X2644956Y-295160D01*
X2646216Y-298077D01*
X2646531Y-301410D01*
X2646216Y-304743D01*
X2644956Y-307660D01*
X2643066Y-309326D01*
X2641176Y-309743D01*
G01X2661021D02*
Y-293077D01*
G01Y-297243D02*
X2662281Y-295160D01*
X2664171Y-293493D01*
X2666691Y-293077D01*
X2668896Y-293493D01*
X2670786Y-295160D01*
X2671731Y-298077D01*
Y-309743D01*
G01X2226351Y-231233D02*
X2232601Y-251233D01*
X2238851Y-231233D01*
G01X2252601Y-237900D02*
Y-251233D01*
G01Y-232567D02*
X2252101Y-232233D01*
Y-231566D01*
X2252601Y-231233D01*
X2253101Y-231566D01*
Y-232233D01*
X2252601Y-232567D01*
G01X2272601Y-251233D02*
Y-231233D01*
G01X2288851Y-242233D02*
X2296851D01*
X2296101Y-239900D01*
X2294851Y-238567D01*
X2293101Y-237900D01*
X2291351Y-238233D01*
X2289851Y-239233D01*
X2288851Y-241567D01*
X2288351Y-243567D01*
Y-245566D01*
X2288851Y-247567D01*
X2290101Y-249567D01*
X2291601Y-250900D01*
X2293351Y-251233D01*
X2295101Y-250566D01*
X2296851Y-248567D01*
G01X2317101Y-251233D02*
Y-237900D01*
G01Y-240233D02*
X2316101Y-238900D01*
X2314601Y-238233D01*
X2312851Y-237900D01*
X2311101Y-238567D01*
X2309601Y-239900D01*
X2308601Y-241900D01*
X2308101Y-244567D01*
X2308601Y-247233D01*
X2309601Y-249233D01*
X2311101Y-250566D01*
X2312851Y-251233D01*
X2314601Y-250900D01*
X2316101Y-249900D01*
X2317101Y-248567D01*
G01X2328351Y-251233D02*
Y-237900D01*
G01Y-241233D02*
X2329351Y-239566D01*
X2330851Y-238233D01*
X2332851Y-237900D01*
X2334601Y-238233D01*
X2336101Y-239566D01*
X2336851Y-241900D01*
Y-251233D01*
G01X2367601Y-231233D02*
Y-251233D01*
X2377601D01*
G01X2392601Y-237900D02*
Y-251233D01*
G01Y-232567D02*
X2392101Y-232233D01*
Y-231566D01*
X2392601Y-231233D01*
X2393101Y-231566D01*
Y-232233D01*
X2392601Y-232567D01*
G01X2247128Y-206528D02*
X2249128Y-208194D01*
X2251378Y-209194D01*
X2253378D01*
X2255378Y-208194D01*
X2256878Y-206528D01*
X2257628Y-204194D01*
X2257128Y-201861D01*
X2255878Y-199861D01*
X2253628Y-198527D01*
X2250628Y-197861D01*
X2248878Y-196528D01*
X2248128Y-194194D01*
X2248628Y-191861D01*
X2249878Y-190194D01*
X2251628Y-189194D01*
X2253378D01*
X2255128Y-189861D01*
X2256628Y-191527D01*
G01X2266878Y-209194D02*
Y-189194D01*
X2271878D01*
X2273878Y-190194D01*
X2275378Y-191527D01*
X2276628Y-193527D01*
X2277628Y-195861D01*
X2277878Y-199194D01*
X2277628Y-202528D01*
X2276628Y-204861D01*
X2275378Y-206861D01*
X2273878Y-208194D01*
X2271878Y-209194D01*
X2266878D01*
G01X2238348Y-158313D02*
Y-138313D01*
X2235348Y-142313D01*
G01Y-158313D02*
X2241348D01*
G01X2253598Y-149980D02*
X2255348Y-147646D01*
X2256848Y-146313D01*
X2258848Y-145647D01*
X2260598Y-146313D01*
X2261848Y-147646D01*
X2262848Y-149646D01*
X2263098Y-151980D01*
X2262848Y-153980D01*
X2261848Y-155980D01*
X2260348Y-157646D01*
X2258598Y-158313D01*
X2256598Y-157646D01*
X2254848Y-155647D01*
X2253848Y-152646D01*
X2253598Y-149313D01*
X2254098Y-144980D01*
X2254848Y-142646D01*
X2256098Y-140313D01*
X2257848Y-138646D01*
X2259598Y-138313D01*
X2261348Y-138980D01*
X2262598Y-140646D01*
G01X2272848Y-154313D02*
X2274348Y-156647D01*
X2276348Y-157980D01*
X2278598Y-158313D01*
X2280598Y-157980D01*
X2282598Y-156313D01*
X2283848Y-154313D01*
X2284098Y-152313D01*
X2283598Y-149980D01*
X2281848Y-148313D01*
X2280098Y-147646D01*
X2277848D01*
G01X2280098D02*
X2281598Y-146646D01*
X2282848Y-144980D01*
X2283348Y-142980D01*
X2282848Y-140980D01*
X2281598Y-139313D01*
X2279348Y-138313D01*
X2277098Y-138646D01*
X2274848Y-139980D01*
G01X2298348Y-158313D02*
Y-138313D01*
X2295348Y-142313D01*
G01Y-158313D02*
X2301348D01*
G01X2312848Y-155314D02*
X2314348Y-156980D01*
X2316098Y-157980D01*
X2318348Y-158313D01*
X2320598Y-157646D01*
X2322348Y-156313D01*
X2323598Y-153980D01*
X2323848Y-151313D01*
X2323348Y-148647D01*
X2322098Y-146980D01*
X2320348Y-145647D01*
X2318598Y-145313D01*
X2316848Y-145647D01*
X2314598Y-146980D01*
X2315348Y-138313D01*
X2322098D01*
G01X2230667Y-99033D02*
X2231927Y-97784D01*
X2232872Y-95701D01*
X2233502Y-92783D01*
X2232872Y-90284D01*
X2231612Y-88617D01*
X2229407Y-87367D01*
X2220902D01*
Y-112367D01*
X2231297D01*
X2233502Y-110701D01*
X2234762Y-108200D01*
X2235392Y-105284D01*
X2234762Y-102368D01*
X2232872Y-99867D01*
X2230667Y-99033D01*
X2220902D01*
G01X2248937Y-112367D02*
Y-95701D01*
G01Y-99033D02*
X2250512Y-97367D01*
X2252087Y-96117D01*
X2254292Y-95701D01*
X2255867Y-96117D01*
X2257757Y-97367D01*
G01X2271932Y-119867D02*
X2273822Y-120700D01*
X2276342Y-119867D01*
X2277917Y-118201D01*
X2279177Y-116117D01*
X2281067Y-109451D01*
X2285162Y-95701D01*
G01X2275082D02*
X2281067Y-109451D01*
G01X2308787Y-97784D02*
X2306582Y-96117D01*
X2304692Y-95701D01*
X2302172Y-96534D01*
X2300282Y-98200D01*
X2299022Y-101117D01*
X2298707Y-104034D01*
X2299022Y-106951D01*
X2300282Y-109451D01*
X2302172Y-111534D01*
X2304692Y-112367D01*
X2306897Y-111534D01*
X2308787Y-109868D01*
G01X2324222Y-101117D02*
X2334302D01*
X2333357Y-98200D01*
X2331782Y-96534D01*
X2329577Y-95701D01*
X2327372Y-96117D01*
X2325482Y-97367D01*
X2324222Y-100284D01*
X2323592Y-102784D01*
Y-105284D01*
X2324222Y-107784D01*
X2325797Y-110284D01*
X2327687Y-111950D01*
X2329892Y-112367D01*
X2332097Y-111534D01*
X2334302Y-109034D01*
G01X2386277Y-89451D02*
X2384387Y-88200D01*
X2382182Y-87367D01*
X2379662D01*
X2376827Y-88617D01*
X2374622Y-90700D01*
X2373047Y-93201D01*
X2371787Y-97367D01*
X2371472Y-101117D01*
X2372102Y-104867D01*
X2373047Y-107367D01*
X2374937Y-109868D01*
X2377142Y-111534D01*
X2379347Y-112367D01*
X2381552D01*
X2383757Y-111534D01*
X2385647Y-110284D01*
X2387222Y-108618D01*
G01X2410217Y-112367D02*
Y-95701D01*
G01Y-98617D02*
X2408957Y-96951D01*
X2407067Y-96117D01*
X2404862Y-95701D01*
X2402657Y-96534D01*
X2400767Y-98200D01*
X2399507Y-100701D01*
X2398877Y-104034D01*
X2399507Y-107367D01*
X2400767Y-109868D01*
X2402657Y-111534D01*
X2404862Y-112367D01*
X2407067Y-111950D01*
X2408957Y-110701D01*
X2410217Y-109034D01*
G01X2424392Y-112367D02*
Y-95701D01*
G01Y-99867D02*
X2425652Y-97784D01*
X2427542Y-96117D01*
X2430062Y-95701D01*
X2432267Y-96117D01*
X2434157Y-97784D01*
X2435102Y-100701D01*
Y-112367D01*
G01X2448332Y-119867D02*
X2450222Y-120700D01*
X2452742Y-119867D01*
X2454317Y-118201D01*
X2455577Y-116117D01*
X2457467Y-109451D01*
X2461562Y-95701D01*
G01X2451482D02*
X2457467Y-109451D01*
G01X2480147Y-112367D02*
X2478257Y-111950D01*
X2476367Y-110284D01*
X2475107Y-107367D01*
X2474477Y-104034D01*
X2475107Y-100701D01*
X2476367Y-97784D01*
X2478257Y-96117D01*
X2480147Y-95701D01*
X2482037Y-96117D01*
X2483927Y-97784D01*
X2485187Y-100701D01*
X2485502Y-104034D01*
X2485187Y-107367D01*
X2483927Y-110284D01*
X2482037Y-111950D01*
X2480147Y-112367D01*
G01X2499992D02*
Y-95701D01*
G01Y-99867D02*
X2501252Y-97784D01*
X2503142Y-96117D01*
X2505662Y-95701D01*
X2507867Y-96117D01*
X2509757Y-97784D01*
X2510702Y-100701D01*
Y-112367D01*
G01X2549762D02*
Y-87367D01*
X2561732D01*
G01X2557322Y-99450D02*
X2549762D01*
G01X2580947Y-113200D02*
X2580317Y-112784D01*
Y-111950D01*
X2580947Y-111534D01*
X2581577Y-111950D01*
Y-112784D01*
X2580947Y-113200D01*
G01X2599217Y-112367D02*
Y-87367D01*
X2605517D01*
X2608037Y-88617D01*
X2609927Y-90284D01*
X2611502Y-92783D01*
X2612762Y-95701D01*
X2613077Y-99867D01*
X2612762Y-104034D01*
X2611502Y-106951D01*
X2609927Y-109451D01*
X2608037Y-111117D01*
X2605517Y-112367D01*
X2599217D01*
G01X2625047D02*
Y-87367D01*
X2632607D01*
X2635127Y-88617D01*
X2637017Y-91534D01*
X2637647Y-94867D01*
X2637017Y-98200D01*
X2635442Y-100701D01*
X2632607Y-101951D01*
X2625047D01*
G01X2659067Y-99033D02*
X2660327Y-97784D01*
X2661272Y-95701D01*
X2661902Y-92783D01*
X2661272Y-90284D01*
X2660012Y-88617D01*
X2657807Y-87367D01*
X2649302D01*
Y-112367D01*
X2659697D01*
X2661902Y-110701D01*
X2663162Y-108200D01*
X2663792Y-105284D01*
X2663162Y-102368D01*
X2661272Y-99867D01*
X2659067Y-99033D01*
X2649302D01*
G01X2404128Y-351083D02*
Y-339676D01*
X2402417Y-341957D01*
G01Y-351083D02*
X2405839D01*
G01X2412827Y-341577D02*
X2413682Y-340437D01*
X2414680Y-339866D01*
X2415821Y-339676D01*
X2417247Y-340056D01*
X2418245Y-341007D01*
X2418531Y-342147D01*
X2418388Y-343288D01*
X2417818Y-344239D01*
X2414966Y-346140D01*
X2413682Y-347471D01*
X2412827Y-349372D01*
X2412541Y-351083D01*
X2418531D01*
G01X2404128Y1826673D02*
Y1838080D01*
X2402417Y1835799D01*
G01Y1826673D02*
X2405839D01*
G01X2412827Y1836179D02*
X2413682Y1837319D01*
X2414680Y1837890D01*
X2415821Y1838080D01*
X2417247Y1837700D01*
X2418245Y1836749D01*
X2418531Y1835609D01*
X2418388Y1834468D01*
X2417818Y1833517D01*
X2414966Y1831616D01*
X2413682Y1830285D01*
X2412827Y1828384D01*
X2412541Y1826673D01*
X2418531D01*
G01X2544309Y-184729D02*
Y-204729D01*
G01X2538559Y-184729D02*
X2550059D01*
G01X2560059Y-204729D02*
Y-184729D01*
G01Y-194395D02*
X2561309Y-192729D01*
X2562559Y-191729D01*
X2564559Y-191396D01*
X2566059Y-191729D01*
X2567809Y-193062D01*
X2568559Y-195063D01*
Y-204729D01*
G01X2584309Y-191396D02*
Y-204729D01*
G01Y-186063D02*
X2583809Y-185729D01*
Y-185062D01*
X2584309Y-184729D01*
X2584809Y-185062D01*
Y-185729D01*
X2584309Y-186063D01*
G01X2608309Y-193062D02*
X2606559Y-191729D01*
X2605059Y-191396D01*
X2603059Y-192063D01*
X2601559Y-193396D01*
X2600559Y-195729D01*
X2600309Y-198063D01*
X2600559Y-200396D01*
X2601559Y-202396D01*
X2603059Y-204062D01*
X2605059Y-204729D01*
X2606809Y-204062D01*
X2608309Y-202729D01*
G01X2620059Y-204729D02*
Y-184729D01*
G01X2628059Y-191396D02*
X2620059Y-199062D01*
G01X2623309Y-196062D02*
X2628559Y-204729D01*
G01X2640059D02*
Y-191396D01*
G01Y-194729D02*
X2641059Y-193062D01*
X2642559Y-191729D01*
X2644559Y-191396D01*
X2646309Y-191729D01*
X2647809Y-193062D01*
X2648559Y-195396D01*
Y-204729D01*
G01X2660559Y-195729D02*
X2668559D01*
X2667809Y-193396D01*
X2666559Y-192063D01*
X2664809Y-191396D01*
X2663059Y-191729D01*
X2661559Y-192729D01*
X2660559Y-195063D01*
X2660059Y-197063D01*
Y-199062D01*
X2660559Y-201063D01*
X2661809Y-203063D01*
X2663309Y-204396D01*
X2665059Y-204729D01*
X2666809Y-204062D01*
X2668559Y-202063D01*
G01X2680559Y-202396D02*
X2681809Y-203729D01*
X2683559Y-204729D01*
X2685059D01*
X2686559Y-204062D01*
X2687559Y-203063D01*
X2688059Y-201730D01*
X2687809Y-199729D01*
X2686809Y-198729D01*
X2682309Y-196729D01*
X2681309Y-194395D01*
X2681809Y-192729D01*
X2682809Y-191729D01*
X2684309Y-191396D01*
X2685809Y-191729D01*
X2687309Y-192729D01*
G01X2700559Y-202396D02*
X2701809Y-203729D01*
X2703559Y-204729D01*
X2705059D01*
X2706559Y-204062D01*
X2707559Y-203063D01*
X2708059Y-201730D01*
X2707809Y-199729D01*
X2706809Y-198729D01*
X2702309Y-196729D01*
X2701309Y-194395D01*
X2701809Y-192729D01*
X2702809Y-191729D01*
X2704309Y-191396D01*
X2705809Y-191729D01*
X2707309Y-192729D01*
G01X2587884Y-253208D02*
Y-233208D01*
X2592884D01*
X2594884Y-234208D01*
X2596384Y-235541D01*
X2597634Y-237541D01*
X2598634Y-239875D01*
X2598884Y-243208D01*
X2598634Y-246542D01*
X2597634Y-248875D01*
X2596384Y-250875D01*
X2594884Y-252208D01*
X2592884Y-253208D01*
X2587884D01*
G01X2617884D02*
Y-239875D01*
G01Y-242208D02*
X2616884Y-240875D01*
X2615384Y-240208D01*
X2613634Y-239875D01*
X2611884Y-240542D01*
X2610384Y-241875D01*
X2609384Y-243875D01*
X2608884Y-246542D01*
X2609384Y-249208D01*
X2610384Y-251208D01*
X2611884Y-252541D01*
X2613634Y-253208D01*
X2615384Y-252875D01*
X2616884Y-251875D01*
X2617884Y-250542D01*
G01X2633384Y-233208D02*
Y-253208D01*
G01X2629884Y-239875D02*
X2636884D01*
G01X2649634Y-244208D02*
X2657634D01*
X2656884Y-241875D01*
X2655634Y-240542D01*
X2653884Y-239875D01*
X2652134Y-240208D01*
X2650634Y-241208D01*
X2649634Y-243542D01*
X2649134Y-245542D01*
Y-247541D01*
X2649634Y-249542D01*
X2650884Y-251542D01*
X2652384Y-252875D01*
X2654134Y-253208D01*
X2655884Y-252541D01*
X2657634Y-250542D01*
G01X2623798Y-351083D02*
Y-339676D01*
X2622087Y-341957D01*
G01Y-351083D02*
X2625509D01*
G01X2632069Y-348802D02*
X2632924Y-350133D01*
X2634065Y-350893D01*
X2635349Y-351083D01*
X2636490Y-350893D01*
X2637630Y-349943D01*
X2638343Y-348802D01*
X2638486Y-347661D01*
X2638201Y-346330D01*
X2637202Y-345380D01*
X2636204Y-344999D01*
X2634921D01*
G01X2636204D02*
X2637060Y-344429D01*
X2637773Y-343479D01*
X2638058Y-342338D01*
X2637773Y-341197D01*
X2637060Y-340247D01*
X2635776Y-339676D01*
X2634493Y-339866D01*
X2633210Y-340627D01*
G01X2623798Y1826673D02*
Y1838080D01*
X2622087Y1835799D01*
G01Y1826673D02*
X2625509D01*
G01X2632069Y1828954D02*
X2632924Y1827623D01*
X2634065Y1826863D01*
X2635349Y1826673D01*
X2636490Y1826863D01*
X2637630Y1827813D01*
X2638343Y1828954D01*
X2638486Y1830095D01*
X2638201Y1831426D01*
X2637202Y1832376D01*
X2636204Y1832757D01*
X2634921D01*
G01X2636204D02*
X2637060Y1833327D01*
X2637773Y1834277D01*
X2638058Y1835418D01*
X2637773Y1836559D01*
X2637060Y1837509D01*
X2635776Y1838080D01*
X2634493Y1837890D01*
X2633210Y1837129D01*
G01X2738671Y-234167D02*
X2740171Y-232168D01*
X2741921Y-231167D01*
X2743921Y-230834D01*
X2746421Y-231501D01*
X2748171Y-233167D01*
X2748671Y-235167D01*
X2748421Y-237168D01*
X2747421Y-238834D01*
X2742421Y-242167D01*
X2740171Y-244501D01*
X2738671Y-247835D01*
X2738171Y-250834D01*
X2748671D01*
G01X2763421Y-230834D02*
X2761421Y-231501D01*
X2759921Y-233167D01*
X2758921Y-235167D01*
X2758171Y-237834D01*
X2757921Y-240834D01*
X2758171Y-243834D01*
X2758921Y-246501D01*
X2759921Y-248501D01*
X2761421Y-250167D01*
X2763421Y-250834D01*
X2765421Y-250167D01*
X2766921Y-248501D01*
X2767921Y-246501D01*
X2768671Y-243834D01*
X2768921Y-240834D01*
X2768671Y-237834D01*
X2767921Y-235167D01*
X2766921Y-233167D01*
X2765421Y-231501D01*
X2763421Y-230834D01*
G01X2783421Y-250834D02*
Y-230834D01*
X2780421Y-234834D01*
G01Y-250834D02*
X2786421D01*
G01X2802921D02*
X2803421Y-246501D01*
X2804171Y-242834D01*
X2805171Y-239501D01*
X2806421Y-235834D01*
X2808421Y-230834D01*
X2798421D01*
G01X2820171Y-244168D02*
X2826671D01*
G01X2843421Y-230834D02*
X2841421Y-231501D01*
X2839921Y-233167D01*
X2838921Y-235167D01*
X2838171Y-237834D01*
X2837921Y-240834D01*
X2838171Y-243834D01*
X2838921Y-246501D01*
X2839921Y-248501D01*
X2841421Y-250167D01*
X2843421Y-250834D01*
X2845421Y-250167D01*
X2846921Y-248501D01*
X2847921Y-246501D01*
X2848671Y-243834D01*
X2848921Y-240834D01*
X2848671Y-237834D01*
X2847921Y-235167D01*
X2846921Y-233167D01*
X2845421Y-231501D01*
X2843421Y-230834D01*
G01X2857921Y-246834D02*
X2859421Y-249168D01*
X2861421Y-250501D01*
X2863671Y-250834D01*
X2865671Y-250501D01*
X2867671Y-248834D01*
X2868921Y-246834D01*
X2869171Y-244834D01*
X2868671Y-242501D01*
X2866921Y-240834D01*
X2865171Y-240167D01*
X2862921D01*
G01X2865171D02*
X2866671Y-239167D01*
X2867921Y-237501D01*
X2868421Y-235501D01*
X2867921Y-233501D01*
X2866671Y-231834D01*
X2864421Y-230834D01*
X2862171Y-231167D01*
X2859921Y-232501D01*
G01X2880171Y-244168D02*
X2886671D01*
G01X2903421Y-230834D02*
X2901421Y-231501D01*
X2899921Y-233167D01*
X2898921Y-235167D01*
X2898171Y-237834D01*
X2897921Y-240834D01*
X2898171Y-243834D01*
X2898921Y-246501D01*
X2899921Y-248501D01*
X2901421Y-250167D01*
X2903421Y-250834D01*
X2905421Y-250167D01*
X2906921Y-248501D01*
X2907921Y-246501D01*
X2908671Y-243834D01*
X2908921Y-240834D01*
X2908671Y-237834D01*
X2907921Y-235167D01*
X2906921Y-233167D01*
X2905421Y-231501D01*
X2903421Y-230834D01*
G01X2918671Y-234167D02*
X2920171Y-232168D01*
X2921921Y-231167D01*
X2923921Y-230834D01*
X2926421Y-231501D01*
X2928171Y-233167D01*
X2928671Y-235167D01*
X2928421Y-237168D01*
X2927421Y-238834D01*
X2922421Y-242167D01*
X2920171Y-244501D01*
X2918671Y-247835D01*
X2918171Y-250834D01*
X2928671D01*
G01X2763946Y-185859D02*
X2765446Y-183860D01*
X2767196Y-182859D01*
X2769196Y-182526D01*
X2771696Y-183193D01*
X2773446Y-184859D01*
X2773946Y-186859D01*
X2773696Y-188860D01*
X2772696Y-190526D01*
X2767696Y-193859D01*
X2765446Y-196193D01*
X2763946Y-199527D01*
X2763446Y-202526D01*
X2773946D01*
G01X2788696Y-203193D02*
X2788196Y-202859D01*
Y-202193D01*
X2788696Y-201859D01*
X2789196Y-202193D01*
Y-202859D01*
X2788696Y-203193D01*
G01X2803196Y-198526D02*
X2804696Y-200860D01*
X2806696Y-202193D01*
X2808946Y-202526D01*
X2810946Y-202193D01*
X2812946Y-200526D01*
X2814196Y-198526D01*
X2814446Y-196526D01*
X2813946Y-194193D01*
X2812196Y-192526D01*
X2810446Y-191859D01*
X2808196D01*
G01X2810446D02*
X2811946Y-190859D01*
X2813196Y-189193D01*
X2813696Y-187193D01*
X2813196Y-185193D01*
X2811946Y-183526D01*
X2809696Y-182526D01*
X2807446Y-182859D01*
X2805196Y-184193D01*
G01X2823946Y-194193D02*
X2825696Y-191859D01*
X2827196Y-190526D01*
X2829196Y-189860D01*
X2830946Y-190526D01*
X2832196Y-191859D01*
X2833196Y-193859D01*
X2833446Y-196193D01*
X2833196Y-198193D01*
X2832196Y-200193D01*
X2830696Y-201859D01*
X2828946Y-202526D01*
X2826946Y-201859D01*
X2825196Y-199860D01*
X2824196Y-196859D01*
X2823946Y-193526D01*
X2824446Y-189193D01*
X2825196Y-186859D01*
X2826446Y-184526D01*
X2828196Y-182859D01*
X2829946Y-182526D01*
X2831696Y-183193D01*
X2832946Y-184859D01*
G01X2841196Y-202526D02*
Y-189193D01*
G01Y-192860D02*
X2841946Y-191193D01*
X2843196Y-189860D01*
X2844946Y-189193D01*
X2846696Y-189860D01*
X2847946Y-191193D01*
X2848696Y-192860D01*
Y-202526D01*
G01Y-192860D02*
X2849446Y-191193D01*
X2850696Y-189860D01*
X2852446Y-189193D01*
X2854196Y-189860D01*
X2855446Y-191193D01*
X2856196Y-193193D01*
Y-202526D01*
G01X2861196D02*
Y-189193D01*
G01Y-192860D02*
X2861946Y-191193D01*
X2863196Y-189860D01*
X2864946Y-189193D01*
X2866696Y-189860D01*
X2867946Y-191193D01*
X2868696Y-192860D01*
Y-202526D01*
G01Y-192860D02*
X2869446Y-191193D01*
X2870696Y-189860D01*
X2872446Y-189193D01*
X2874196Y-189860D01*
X2875446Y-191193D01*
X2876196Y-193193D01*
Y-202526D01*
G01X2843467Y-351083D02*
Y-339676D01*
X2841756Y-341957D01*
G01Y-351083D02*
X2845178D01*
G01X2856586D02*
Y-339676D01*
X2851310Y-347851D01*
X2858440D01*
G01X2843467Y1826673D02*
Y1838080D01*
X2841756Y1835799D01*
G01Y1826673D02*
X2845178D01*
G01X2856586D02*
Y1838080D01*
X2851310Y1829905D01*
X2858440D01*
G01X2969197Y-231392D02*
X2969910Y-232533D01*
X2970765Y-233293D01*
X2971764Y-233673D01*
X2972905Y-233293D01*
X2973760Y-232533D01*
X2974616Y-231392D01*
X2974901Y-229871D01*
Y-222266D01*
G01X2970338Y-6384D02*
X2973760D01*
G01X2972049D02*
Y-17791D01*
G01X2970338D02*
X2973760D01*
G01X2969054Y197901D02*
Y209308D01*
G01X2975044D02*
Y197901D01*
G01Y203604D02*
X2969054D01*
G01X2972905Y419486D02*
X2975757D01*
Y416064D01*
X2974901Y414923D01*
X2973903Y414163D01*
X2972477Y413783D01*
X2971051Y414163D01*
X2970053Y414923D01*
X2969197Y416064D01*
X2968626Y417395D01*
X2968341Y418916D01*
Y420247D01*
X2968626Y421387D01*
X2969197Y422719D01*
X2970053Y423859D01*
X2970908Y424619D01*
X2972049Y425190D01*
X2973047D01*
X2974188Y424810D01*
X2975044Y424049D01*
G01X2968961Y629855D02*
Y641262D01*
X2974379D01*
G01X2972383Y635749D02*
X2968961D01*
G01X2974901Y845926D02*
X2969197D01*
Y857333D01*
X2974901D01*
G01X2972619Y851820D02*
X2969197D01*
G01X2968912Y1061618D02*
Y1073025D01*
X2971764D01*
X2972905Y1072454D01*
X2973760Y1071694D01*
X2974473Y1070554D01*
X2975044Y1069222D01*
X2975186Y1067321D01*
X2975044Y1065420D01*
X2974473Y1064089D01*
X2973760Y1062949D01*
X2972905Y1062188D01*
X2971764Y1061618D01*
X2968912D01*
G01X2975186Y1288146D02*
X2974331Y1288717D01*
X2973333Y1289097D01*
X2972192D01*
X2970908Y1288526D01*
X2969910Y1287576D01*
X2969197Y1286435D01*
X2968626Y1284534D01*
X2968484Y1282823D01*
X2968769Y1281112D01*
X2969197Y1279971D01*
X2970053Y1278830D01*
X2971051Y1278070D01*
X2972049Y1277690D01*
X2973047D01*
X2974045Y1278070D01*
X2974901Y1278640D01*
X2975614Y1279401D01*
G01X2973190Y1499466D02*
X2973760Y1500036D01*
X2974188Y1500986D01*
X2974473Y1502318D01*
X2974188Y1503458D01*
X2973618Y1504218D01*
X2972619Y1504789D01*
X2968769D01*
Y1493382D01*
X2973475D01*
X2974473Y1494142D01*
X2975044Y1495283D01*
X2975329Y1496614D01*
X2975044Y1497945D01*
X2974188Y1499085D01*
X2973190Y1499466D01*
X2968769D01*
G01X2968484Y1709264D02*
X2972049Y1720671D01*
X2975614Y1709264D01*
G01X2974331Y1713256D02*
X2969767D01*
G01X-143390Y-354870D02*
Y1841823D01*
G01X2981216Y-354870D02*
X-143390D01*
G01X-124453Y-335933D02*
Y1822886D01*
G01X2962279Y-335933D02*
X-124453D01*
G01X-143390Y-120051D02*
X-124453D01*
G01X-143390Y95831D02*
X-124453D01*
G01X-143390D02*
X-124453D01*
G01X-143390Y311713D02*
X-124453D01*
G01X-143390D02*
X-124453D01*
G01X-143390Y527595D02*
X-124453D01*
G01X-143390D02*
X-124453D01*
G01X-143390Y743477D02*
X-124453D01*
G01X-143390D02*
X-124453D01*
G01X-143390D02*
X-124453D01*
G01X-143390Y959358D02*
X-124453D01*
G01X-143390D02*
X-124453D01*
G01X-143390Y1175240D02*
X-124453D01*
G01X-143390D02*
X-124453D01*
G01X-143390Y1391122D02*
X-124453D01*
G01X-143390D02*
X-124453D01*
G01X-143390Y1607004D02*
X-124453D01*
G01X-143390Y1841823D02*
X2981216D01*
G01X-124453Y1822886D02*
X2962279D01*
G01X-54734Y-126911D02*
Y-121911D01*
X-52200D01*
G01X-53134Y-124328D02*
X-54734D01*
G01X-48867Y-123578D02*
Y-126911D01*
G01Y-122244D02*
X-49000Y-122161D01*
Y-121994D01*
X-48867Y-121911D01*
X-48734Y-121994D01*
Y-122161D01*
X-48867Y-122244D01*
G01X-43067Y-121911D02*
Y-126911D01*
G01Y-126161D02*
X-43334Y-126578D01*
X-43734Y-126828D01*
X-44200Y-126911D01*
X-44734Y-126744D01*
X-45134Y-126328D01*
X-45400Y-125828D01*
X-45467Y-125244D01*
X-45400Y-124661D01*
X-45134Y-124161D01*
X-44734Y-123744D01*
X-44200Y-123578D01*
X-43734Y-123661D01*
X-43400Y-123828D01*
X-43067Y-124161D01*
G01X-40800Y-123578D02*
Y-125911D01*
X-40534Y-126494D01*
X-40134Y-126828D01*
X-39667Y-126911D01*
X-39200Y-126828D01*
X-38800Y-126494D01*
X-38534Y-125911D01*
G01Y-126911D02*
Y-123578D01*
G01X-34000Y-123994D02*
X-34467Y-123661D01*
X-34867Y-123578D01*
X-35400Y-123744D01*
X-35800Y-124078D01*
X-36067Y-124661D01*
X-36134Y-125244D01*
X-36067Y-125828D01*
X-35800Y-126328D01*
X-35400Y-126744D01*
X-34867Y-126911D01*
X-34400Y-126744D01*
X-34000Y-126411D01*
G01X-30467Y-123578D02*
Y-126911D01*
G01Y-122244D02*
X-30600Y-122161D01*
Y-121994D01*
X-30467Y-121911D01*
X-30334Y-121994D01*
Y-122161D01*
X-30467Y-122244D01*
G01X-24667Y-126911D02*
Y-123578D01*
G01Y-124161D02*
X-24934Y-123828D01*
X-25334Y-123661D01*
X-25800Y-123578D01*
X-26267Y-123744D01*
X-26667Y-124078D01*
X-26934Y-124578D01*
X-27067Y-125244D01*
X-26934Y-125911D01*
X-26667Y-126411D01*
X-26267Y-126744D01*
X-25800Y-126911D01*
X-25334Y-126828D01*
X-24934Y-126578D01*
X-24667Y-126244D01*
G01X-21267Y-126911D02*
Y-121911D01*
G01X-13800Y-126911D02*
Y-121911D01*
X-12067Y-126078D01*
X-10334Y-121911D01*
Y-126911D01*
G01X-6267D02*
Y-123578D01*
G01Y-124161D02*
X-6534Y-123828D01*
X-6934Y-123661D01*
X-7400Y-123578D01*
X-7867Y-123744D01*
X-8267Y-124078D01*
X-8534Y-124578D01*
X-8667Y-125244D01*
X-8534Y-125911D01*
X-8267Y-126411D01*
X-7867Y-126744D01*
X-7400Y-126911D01*
X-6934Y-126828D01*
X-6534Y-126578D01*
X-6267Y-126244D01*
G01X-3800Y-126911D02*
Y-123578D01*
G01Y-124244D02*
X-3467Y-123911D01*
X-3134Y-123661D01*
X-2667Y-123578D01*
X-2334Y-123661D01*
X-1934Y-123911D01*
G01X600Y-126911D02*
Y-121911D01*
G01X2733Y-123578D02*
X600Y-125494D01*
G01X1466Y-124744D02*
X2866Y-126911D01*
G01X9933Y-123578D02*
X11933Y-126911D01*
G01Y-123578D02*
X9933Y-126911D01*
G01X18666Y-125911D02*
X19066Y-126494D01*
X19600Y-126828D01*
X20200Y-126911D01*
X20733Y-126828D01*
X21266Y-126411D01*
X21600Y-125911D01*
X21666Y-125411D01*
X21533Y-124828D01*
X21066Y-124411D01*
X20600Y-124244D01*
X20000D01*
G01X20600D02*
X21000Y-123994D01*
X21333Y-123578D01*
X21466Y-123078D01*
X21333Y-122578D01*
X21000Y-122161D01*
X20400Y-121911D01*
X19800Y-121994D01*
X19200Y-122328D01*
G01X11063Y-152756D02*
X-34056D01*
G01X11063Y1658268D02*
X-34056D01*
G01X0Y-137756D02*
G03X15000Y-152756I15000J0D01*
G01X0Y-11811D02*
Y-137756D01*
G01X854331Y-152756D02*
X15000D01*
G01X0Y-137756D02*
G03X15000Y-152756I15000J0D01*
G01X0Y-11811D02*
Y-137756D01*
G01X854331Y-152756D02*
X15000D01*
G01X20291Y-129902D02*
X-15909D01*
G01X35506Y-114687D02*
X20291Y-129902D01*
G01X3937Y-7874D02*
G03X0Y-11811I0J-3937D01*
G01X23622Y-7874D02*
G03Y0I0J3937D01*
G01X3937Y-7874D02*
X23622D01*
G01X6890Y21654D02*
G03X23426I8268J0D01*
G01X3937Y0D02*
X397638D01*
G01X0Y3937D02*
G03X3937Y0I3937J0D01*
G01X0Y1370866D02*
Y3937D01*
G01X3937Y-7874D02*
G03X0Y-11811I0J-3937D01*
G01X23622Y-7874D02*
G03Y0I0J3937D01*
G01X3937Y-7874D02*
X23622D01*
G01X0Y3937D02*
G03X3937Y0I3937J0D01*
G01X23425Y21654D02*
G03I-8267J0D01*
G01X3937Y0D02*
X397638D01*
G01X0Y1370866D02*
Y3937D01*
G01X23426Y21654D02*
G03X6890I-8268J0D01*
G01X23426Y478346D02*
G03X6890I-8268J0D01*
G01Y470472D02*
Y478346D01*
G01Y470472D02*
G03X23426I8268J0D01*
G01X23425Y478346D02*
Y470472D01*
G01X6890D02*
G03X23425I8267J1D01*
G01Y478346D02*
G03X6890I-8268J1D01*
G01X23425D02*
Y470472D01*
G01X6890Y478346D02*
Y470472D01*
G01X39764Y882677D02*
G03I-8268J0D01*
G01X3937Y1374803D02*
G03X0Y1370866I0J-3937D01*
G01X3937Y1374803D02*
G03X0Y1370866I0J-3937D01*
G01Y1386614D02*
G03X3937Y1382677I3937J0D01*
G01X23622Y1374803D02*
G03Y1382677I0J3937D01*
G01X0Y1386614D02*
Y1643268D01*
G01X3937Y1382677D02*
X23622D01*
G01X746850Y1374803D02*
X3937D01*
G01X0Y1386614D02*
G03X3937Y1382677I3937J0D01*
G01X23622Y1374803D02*
G03Y1382677I0J3937D01*
G01X3937D02*
X23622D01*
G01X0Y1386614D02*
Y1643268D01*
G01X3937Y1374803D02*
X746850D01*
G01X0Y1647205D02*
Y1727663D01*
G01X15000Y1658268D02*
G03X0Y1643268I0J-15000D01*
G01X775591Y1658268D02*
X15000D01*
G01D02*
G03X0Y1643268I0J-15000D01*
G01X775591Y1658268D02*
X15000D01*
G01X64831Y-85109D02*
G03I-4291J0D01*
G01X39506Y-110687D02*
G03I-4000J0D01*
G01X37506D02*
G03I-2000J0D01*
G01X28436Y-118222D02*
X35506Y-114687D01*
G01D02*
X31971Y-121757D01*
G01D02*
X28436Y-118222D01*
G01X64831Y-85109D02*
G03I-4291J0D01*
G01X54331Y0D02*
G03Y-7874I0J-3937D01*
G01D02*
X323228D01*
G01X54331D02*
X323228D01*
G01X54331Y0D02*
G03Y-7874I0J-3937D01*
G01X71063Y374803D02*
G03X72244I591J0D01*
G01Y368504D02*
G03X71063I-591J0D01*
G01X69094D02*
G03X67913I-591J0D01*
G01Y374803D02*
G03X69094I590J0D01*
G01X71063D02*
G03X72244I591J0D01*
G01Y368504D02*
G03X71063I-591J0D01*
G01X69094D02*
G03X67913I-591J0D01*
G01Y374803D02*
G03X69094I590J0D01*
G01X67913D02*
X67126D01*
G01X67913D02*
X67126D01*
G01X71063D02*
X69094D01*
G01X73031D02*
X72244D01*
G01X71063D02*
X69094D01*
G01X73031D02*
X72244D01*
G01X73031Y373819D02*
X67126D01*
G01Y373622D02*
X73031D01*
G01X67126Y369685D02*
X73031D01*
G01Y369488D02*
X67126D01*
G01X72244Y368504D02*
X73031D01*
G01X69094D02*
X71063D01*
G01X72244D02*
X73031D01*
G01X69094D02*
X71063D01*
G01X67126D02*
X67913D01*
G01X67126D02*
X67913D01*
G01X67126D02*
Y374803D01*
G01D02*
Y368504D01*
G01X71063Y827559D02*
G03X72244I591J0D01*
G01Y821260D02*
G03X71063I-591J0D01*
G01X69094D02*
G03X67913I-591J0D01*
G01Y827559D02*
G03X69094I590J0D01*
G01X71063D02*
G03X72244I591J0D01*
G01Y821260D02*
G03X71063I-591J0D01*
G01X69094D02*
G03X67913I-591J0D01*
G01Y827559D02*
G03X69094I590J0D01*
G01X67913D02*
X67126D01*
G01X67913D02*
X67126D01*
G01X71063D02*
X69094D01*
G01X73031D02*
X72244D01*
G01X71063D02*
X69094D01*
G01X73031D02*
X72244D01*
G01X73031Y826575D02*
X67126D01*
G01Y826378D02*
X73031D01*
G01X67126Y822441D02*
X73031D01*
G01Y822244D02*
X67126D01*
G01X72244Y821260D02*
X73031D01*
G01X69094D02*
X71063D01*
G01X72244D02*
X73031D01*
G01X69094D02*
X71063D01*
G01X67126D02*
X67913D01*
G01X67126D02*
X67913D01*
G01X67126D02*
Y827559D01*
G01D02*
Y821260D01*
G01X72244Y1274016D02*
G03X71063I-591J0D01*
G01X69094D02*
G03X67913I-591J0D01*
G01X72244D02*
G03X71063I-591J0D01*
G01X69094D02*
G03X67913I-591J0D01*
G01X67126Y1275197D02*
X73031D01*
G01Y1275000D02*
X67126D01*
G01X72244Y1274016D02*
X73031D01*
G01X69094D02*
X71063D01*
G01X72244D02*
X73031D01*
G01X69094D02*
X71063D01*
G01X67126D02*
X67913D01*
G01X67126D02*
X67913D01*
G01X67126D02*
Y1280315D01*
G01D02*
Y1274016D01*
G01X71063Y1280315D02*
G03X72244I591J0D01*
G01X67913D02*
G03X69094I590J0D01*
G01X71063D02*
G03X72244I591J0D01*
G01X67913D02*
G03X69094I590J0D01*
G01X67913D02*
X67126D01*
G01X67913D02*
X67126D01*
G01X71063D02*
X69094D01*
G01X73031D02*
X72244D01*
G01X71063D02*
X69094D01*
G01X73031D02*
X72244D01*
G01X73031Y1279331D02*
X67126D01*
G01Y1279134D02*
X73031D01*
G01X54331Y1382677D02*
G03Y1374803I0J-3937D01*
G01Y1382677D02*
X353740D01*
G01X54331D02*
X353740D01*
G01X54331D02*
G03Y1374803I0J-3937D01*
G01X63828Y1573374D02*
G03I-4292J0D01*
G01X76380Y1596505D02*
G03I-4001J0D01*
G01X74380D02*
G03I-2001J0D01*
G01X63828Y1573374D02*
G03I-4292J0D01*
G01X100898Y-335933D02*
Y-354870D01*
G01X75689Y51969D02*
G03X84350I4331J0D01*
G01D02*
G03X75689I-4330J0D01*
G01X92421Y36220D02*
G03X114862I11220J0D01*
G01D02*
G03X92421I-11220J0D01*
G01X84350Y51969D02*
G03I-4330J0D01*
G01X114862Y36221D02*
G03I-11220J0D01*
G01X107087Y139311D02*
G03X107677Y138720I591J0D01*
G01X114370D02*
G03X114961Y139311I0J591D01*
G01X112205Y140492D02*
G03Y142461I0J984D01*
G01X109843D02*
G03Y140492I0J-984D01*
G01X112126Y153681D02*
G03I-1102J0D01*
G01X113583Y148406D02*
G03X114764Y149587I0J1181D01*
G01X107283D02*
G03X108465Y148406I1181J0D01*
G01X112598Y153681D02*
G03I-1574J0D01*
G01X100197Y139902D02*
G03X102165Y137933I1969J0D01*
G01X119882D02*
G03X121850Y139902I0J1968D01*
G01X106496Y161673D02*
X105315Y160492D01*
G01X103543Y158996D02*
X100197Y155650D01*
G01X113508Y156752D02*
X112205Y154783D01*
G01X107532Y148861D02*
X109843Y153091D01*
G01X112008Y161673D02*
X106496D01*
G01X113189Y160492D02*
X105315D01*
G01X118504Y158996D02*
X103543D01*
G01X114764Y158130D02*
X117913D01*
G01X107283D02*
X103543D01*
G01Y156752D02*
X117913D01*
G01X112205Y154783D02*
X109843D01*
G01X112205Y153091D02*
X109843D01*
G01X113583Y148406D02*
X108465D01*
G01X121850Y148366D02*
X100197D01*
G01X114961Y145413D02*
X107087D01*
G01Y143839D02*
X114961D01*
G01X112205Y142461D02*
X109843D01*
G01Y140492D02*
X112205D01*
G01X114370Y138720D02*
X107677D01*
G01X119882Y137933D02*
X102165D01*
G01X118504Y296988D02*
Y158996D01*
G01X117913Y299232D02*
Y156752D01*
G01X114961Y145413D02*
Y139311D01*
G01X114764Y158130D02*
Y149587D01*
G01X113189Y196949D02*
Y160492D01*
G01X112205Y154783D02*
Y153091D01*
G01X112008Y198130D02*
Y161673D01*
G01X109843Y153091D02*
Y154783D01*
G01X107283Y149587D02*
Y158130D01*
G01X107087Y145413D02*
Y139311D01*
G01X106496Y161673D02*
Y294311D01*
G01X105315Y160492D02*
Y295492D01*
G01X103543Y195787D02*
Y156752D01*
G01X100197Y155650D02*
Y139902D01*
G01X112205Y153091D02*
X114515Y148861D01*
G01X109843Y154783D02*
X108539Y156752D01*
G01X118504Y158996D02*
X121850Y155650D01*
G01X112008Y161673D02*
X113189Y160492D01*
G01X102145Y197948D02*
X102146Y197942D01*
G01X102144Y197952D02*
X102145Y197948D01*
G01X102143Y197953D02*
X102144Y197952D01*
G01X102145Y201098D02*
X102146Y201091D01*
G01X102144Y201101D02*
X102145Y201098D01*
G01X102143Y201102D02*
X102144Y201101D01*
G01X102145Y204247D02*
X102146Y204241D01*
G01X102144Y204251D02*
X102145Y204247D01*
G01X102143Y204252D02*
X102144Y204251D01*
G01X102145Y207397D02*
X102146Y207391D01*
G01X102144Y207400D02*
X102145Y207397D01*
G01X102143Y207402D02*
X102144Y207400D01*
G01X102145Y210546D02*
X102146Y210540D01*
G01X102144Y210550D02*
X102145Y210546D01*
G01X102143Y210551D02*
X102144Y210550D01*
G01X116516Y166148D02*
Y166156D01*
G01X116517Y166144D02*
X116516Y166148D01*
G01X116518Y166142D02*
X116517Y166144D01*
G01X116516Y171148D02*
Y171156D01*
G01X116517Y171144D02*
X116516Y171148D01*
G01X116518Y171142D02*
X116517Y171144D01*
G01X116516Y176148D02*
Y176156D01*
G01X116517Y176144D02*
X116516Y176148D01*
G01X116518Y176142D02*
X116517Y176144D01*
G01X116516Y181148D02*
Y181156D01*
G01X116517Y181144D02*
X116516Y181148D01*
G01X116518Y181142D02*
X116517Y181144D01*
G01X116516Y186148D02*
Y186156D01*
G01X116517Y186144D02*
X116516Y186148D01*
G01X116518Y186142D02*
X116517Y186144D01*
G01X116516Y191148D02*
Y191156D01*
G01X116517Y191144D02*
X116516Y191148D01*
G01X116518Y191142D02*
X116517Y191144D01*
G01X116516Y196148D02*
Y196156D01*
G01X116517Y196144D02*
X116516Y196148D01*
G01X116518Y196142D02*
X116517Y196144D01*
G01X102129Y201105D02*
X102143Y201102D01*
G01X102118Y201112D02*
X102129Y201105D01*
G01X102106Y201131D02*
X102118Y201112D01*
G01X102129Y210554D02*
X102143Y210551D01*
G01X102117Y210561D02*
X102129Y210554D01*
G01X102106Y210580D02*
X102117Y210561D01*
G01X102129Y204255D02*
X102143Y204252D01*
G01X102117Y204263D02*
X102129Y204255D01*
G01X102105Y204283D02*
X102117Y204263D01*
G01X103091Y197986D02*
Y197979D01*
G01X103090Y197991D02*
X103091Y197986D01*
G01X103089Y197992D02*
X103090Y197991D01*
G01X103091Y201136D02*
Y201128D01*
G01X103090Y201141D02*
X103091Y201136D01*
G01X103089Y201142D02*
X103090Y201141D01*
G01X103091Y204285D02*
Y204278D01*
G01X103090Y204290D02*
X103091Y204285D01*
G01X103089Y204291D02*
X103090Y204290D01*
G01X103091Y207435D02*
Y207428D01*
G01X103090Y207440D02*
X103091Y207435D01*
G01X103089Y207441D02*
X103090Y207440D01*
G01X103091Y210585D02*
Y210577D01*
G01X103090Y210589D02*
X103091Y210585D01*
G01X103089Y210591D02*
X103090Y210589D01*
G01X102128Y197956D02*
X102143Y197953D01*
G01X102115Y197964D02*
X102128Y197956D01*
G01X102105Y197985D02*
X102115Y197964D01*
G01X103090Y199115D02*
X103091Y199108D01*
G01X103088Y199121D02*
X103090Y199115D01*
G01X103085Y199127D02*
X103088Y199121D01*
G01X103090Y202265D02*
X103091Y202258D01*
G01X103088Y202271D02*
X103090Y202265D01*
G01X103085Y202277D02*
X103088Y202271D01*
G01X103090Y205414D02*
X103091Y205407D01*
G01X103088Y205420D02*
X103090Y205414D01*
G01X103085Y205426D02*
X103088Y205420D01*
G01X103090Y208564D02*
X103091Y208557D01*
G01X103088Y208570D02*
X103090Y208564D01*
G01X103085Y208576D02*
X103088Y208570D01*
G01X103090Y211713D02*
X103091Y211707D01*
G01X103088Y211720D02*
X103090Y211713D01*
G01X103085Y211726D02*
X103088Y211720D01*
G01X103052Y197948D02*
Y197942D01*
G01X103050Y197952D02*
X103052Y197948D01*
G01X103050Y197953D02*
Y197952D01*
G01X103052Y201097D02*
Y201091D01*
G01X103050Y201101D02*
X103052Y201097D01*
G01X103050Y201102D02*
Y201101D01*
G01X103052Y204247D02*
Y204241D01*
G01X103050Y204251D02*
X103052Y204247D01*
G01X103050Y204252D02*
Y204251D01*
G01X103052Y207396D02*
Y207391D01*
G01X103050Y207400D02*
X103052Y207396D01*
G01X103050Y207402D02*
Y207400D01*
G01X103052Y210546D02*
Y210540D01*
G01X103050Y210550D02*
X103052Y210546D01*
G01X103050Y210551D02*
Y210550D01*
G01X115531Y166189D02*
Y166198D01*
G01X115532Y166183D02*
X115531Y166189D01*
G01X115533Y166181D02*
X115532Y166183D01*
G01X115531Y171189D02*
Y171198D01*
G01X115532Y171183D02*
X115531Y171189D01*
G01X115533Y171181D02*
X115532Y171183D01*
G01X115531Y176189D02*
Y176198D01*
G01X115532Y176183D02*
X115531Y176189D01*
G01X115533Y176181D02*
X115532Y176183D01*
G01X115531Y181189D02*
Y181198D01*
G01X115532Y181183D02*
X115531Y181189D01*
G01X115533Y181181D02*
X115532Y181183D01*
G01X115531Y186189D02*
Y186198D01*
G01X115532Y186183D02*
X115531Y186189D01*
G01X115533Y186181D02*
X115532Y186183D01*
G01X115531Y191189D02*
Y191198D01*
G01X115532Y191183D02*
X115531Y191189D01*
G01X115533Y191181D02*
X115532Y191183D01*
G01X115531Y196189D02*
Y196198D01*
G01X115532Y196183D02*
X115531Y196189D01*
G01X115533Y196181D02*
X115532Y196183D01*
G01X116508Y166325D02*
X116516Y166299D01*
G01X116498Y166352D02*
X116508Y166325D01*
G01X116487Y166378D02*
X116498Y166352D01*
G01X116508Y171325D02*
X116516Y171299D01*
G01X116498Y171352D02*
X116508Y171325D01*
G01X116487Y171378D02*
X116498Y171352D01*
G01X116508Y176325D02*
X116516Y176299D01*
G01X116498Y176352D02*
X116508Y176325D01*
G01X116487Y176378D02*
X116498Y176352D01*
G01X116508Y181325D02*
X116516Y181299D01*
G01X116498Y181352D02*
X116508Y181325D01*
G01X116487Y181378D02*
X116498Y181352D01*
G01X116508Y186325D02*
X116516Y186299D01*
G01X116498Y186352D02*
X116508Y186325D01*
G01X116487Y186378D02*
X116498Y186352D01*
G01X116508Y191325D02*
X116516Y191299D01*
G01X116498Y191352D02*
X116508Y191325D01*
G01X116487Y191378D02*
X116498Y191352D01*
G01X116508Y196325D02*
X116516Y196299D01*
G01X116498Y196352D02*
X116508Y196325D01*
G01X116487Y196378D02*
X116498Y196352D01*
G01X102124Y207407D02*
X102143Y207402D01*
G01X102111Y207419D02*
X102124Y207407D01*
G01X102104Y207437D02*
X102111Y207419D01*
G01X116498Y166176D02*
X116479Y166181D01*
G01X116513Y166162D02*
X116498Y166176D01*
G01X116518Y166142D02*
X116513Y166162D01*
G01X116498Y171176D02*
X116479Y171181D01*
G01X116513Y171162D02*
X116498Y171176D01*
G01X116518Y171142D02*
X116513Y171162D01*
G01X116498Y176176D02*
X116479Y176181D01*
G01X116513Y176162D02*
X116498Y176176D01*
G01X116518Y176142D02*
X116513Y176162D01*
G01X116498Y181176D02*
X116479Y181181D01*
G01X116513Y181162D02*
X116498Y181176D01*
G01X116518Y181142D02*
X116513Y181162D01*
G01X116498Y186176D02*
X116479Y186181D01*
G01X116513Y186162D02*
X116498Y186176D01*
G01X116518Y186142D02*
X116513Y186162D01*
G01X116483Y166279D02*
X116487Y166378D01*
G01X116477Y166207D02*
X116483Y166279D01*
G01X116479Y166181D02*
X116477Y166207D01*
G01X116483Y171279D02*
X116487Y171378D01*
G01X116477Y171207D02*
X116483Y171279D01*
G01X116479Y171181D02*
X116477Y171207D01*
G01X116483Y176279D02*
X116487Y176378D01*
G01X116477Y176207D02*
X116483Y176279D01*
G01X116479Y176181D02*
X116477Y176207D01*
G01X116483Y181279D02*
X116487Y181378D01*
G01X116477Y181207D02*
X116483Y181279D01*
G01X116479Y181181D02*
X116477Y181207D01*
G01X116483Y186279D02*
X116487Y186378D01*
G01X116477Y186207D02*
X116483Y186279D01*
G01X116479Y186181D02*
X116477Y186207D01*
G01X116483Y191279D02*
X116487Y191378D01*
G01X116477Y191207D02*
X116483Y191279D01*
G01X116479Y191181D02*
X116477Y191207D01*
G01X116483Y196279D02*
X116487Y196378D01*
G01X116477Y196207D02*
X116483Y196279D01*
G01X116479Y196181D02*
X116477Y196207D01*
G01X103059Y205432D02*
X103050Y205433D01*
G01X103068Y205429D02*
X103059Y205432D01*
G01X103076Y205424D02*
X103068Y205429D01*
G01X103059Y199133D02*
X103050Y199134D01*
G01X103068Y199130D02*
X103059Y199133D01*
G01X103076Y199124D02*
X103068Y199130D01*
G01X103059Y202282D02*
X103050Y202283D01*
G01X103068Y202279D02*
X103059Y202282D01*
G01X103076Y202274D02*
X103068Y202279D01*
G01X103059Y208581D02*
X103050Y208583D01*
G01X103068Y208578D02*
X103059Y208581D01*
G01X103076Y208573D02*
X103068Y208578D01*
G01X103059Y211731D02*
X103050Y211732D01*
G01X103068Y211728D02*
X103059Y211731D01*
G01X103076Y211723D02*
X103068Y211728D01*
G01X116498Y191176D02*
X116479Y191181D01*
G01X116513Y191162D02*
X116498Y191176D01*
G01X116518Y191142D02*
X116513Y191162D01*
G01X116498Y196176D02*
X116479Y196181D01*
G01X116513Y196162D02*
X116498Y196176D01*
G01X116518Y196142D02*
X116513Y196162D01*
G01X103083Y205415D02*
X103076Y205424D01*
G01X103087Y205405D02*
X103083Y205415D01*
G01X103089Y205394D02*
X103087Y205405D01*
G01X103083Y199116D02*
X103076Y199124D01*
G01X103088Y199106D02*
X103083Y199116D01*
G01X103089Y199094D02*
X103088Y199106D01*
G01X103083Y202265D02*
X103076Y202274D01*
G01X103088Y202255D02*
X103083Y202265D01*
G01X103089Y202244D02*
X103088Y202255D01*
G01X103083Y208565D02*
X103076Y208573D01*
G01X103088Y208554D02*
X103083Y208565D01*
G01X103089Y208543D02*
X103088Y208554D01*
G01X103083Y211714D02*
X103076Y211723D01*
G01X103088Y211704D02*
X103083Y211714D01*
G01X103089Y211693D02*
X103088Y211704D01*
G01X102106Y210585D02*
Y210577D01*
G01X102105Y210589D02*
X102106Y210585D01*
G01Y210580D02*
X102105Y210589D01*
G01X102146Y211917D02*
Y211929D01*
G01X102143Y211904D02*
X102146Y211917D01*
G01X102143Y211890D02*
Y211904D01*
G01X102146Y208767D02*
Y208780D01*
G01X102143Y208754D02*
X102146Y208767D01*
G01X102143Y208741D02*
Y208754D01*
G01X102146Y205618D02*
Y205630D01*
G01X102143Y205605D02*
X102146Y205618D01*
G01X102143Y205591D02*
Y205605D01*
G01X102146Y202468D02*
Y202480D01*
G01X102143Y202455D02*
X102146Y202468D01*
G01X102143Y202441D02*
Y202455D01*
G01X102146Y199319D02*
Y199331D01*
G01X102143Y199306D02*
X102146Y199319D01*
G01X102143Y199292D02*
Y199306D01*
G01X115532Y194802D02*
X115533Y194803D01*
G01X115531Y194796D02*
X115532Y194802D01*
G01X115531Y194787D02*
Y194796D01*
G01X115532Y189802D02*
X115533Y189803D01*
G01X115531Y189796D02*
X115532Y189802D01*
G01X115531Y189787D02*
Y189796D01*
G01X115532Y184802D02*
X115533Y184803D01*
G01X115531Y184796D02*
X115532Y184802D01*
G01X115531Y184787D02*
Y184796D01*
G01X115532Y179802D02*
X115533Y179803D01*
G01X115531Y179796D02*
X115532Y179802D01*
G01X115531Y179787D02*
Y179796D01*
G01X115532Y174802D02*
X115533Y174803D01*
G01X115531Y174796D02*
X115532Y174802D01*
G01X115531Y174787D02*
Y174796D01*
G01X115532Y169802D02*
X115533Y169803D01*
G01X115531Y169796D02*
X115532Y169802D01*
G01X115531Y169787D02*
Y169796D01*
G01X115532Y164802D02*
X115533Y164803D01*
G01X115531Y164796D02*
X115532Y164802D01*
G01X115531Y164787D02*
Y164796D01*
G01X102143Y210380D02*
X102142Y210393D01*
G01X102146Y210367D02*
X102143Y210380D01*
G01X102146Y210354D02*
Y210367D01*
G01X102143Y207230D02*
X102142Y207244D01*
G01X102146Y207217D02*
X102143Y207230D01*
G01X102146Y207205D02*
Y207217D01*
G01X102143Y204081D02*
X102142Y204094D01*
G01X102146Y204068D02*
X102143Y204081D01*
G01X102146Y204055D02*
Y204068D01*
G01X102143Y200931D02*
X102142Y200944D01*
G01X102146Y200918D02*
X102143Y200931D01*
G01X102146Y200906D02*
Y200918D01*
G01X102143Y197781D02*
X102142Y197795D01*
G01X102146Y197769D02*
X102143Y197781D01*
G01X102146Y197756D02*
Y197769D01*
G01X103054Y211904D02*
X103055Y211890D01*
G01X103050Y211917D02*
X103054Y211904D01*
G01X103051Y211929D02*
X103050Y211917D01*
G01X103054Y208754D02*
X103055Y208741D01*
G01X103050Y208767D02*
X103054Y208754D01*
G01X103051Y208780D02*
X103050Y208767D01*
G01X103054Y205604D02*
X103055Y205591D01*
G01X103050Y205617D02*
X103054Y205604D01*
G01X103051Y205630D02*
X103050Y205617D01*
G01X103054Y202455D02*
X103055Y202441D01*
G01X103050Y202468D02*
X103054Y202455D01*
G01X103051Y202480D02*
X103050Y202468D01*
G01X103054Y199305D02*
X103055Y199292D01*
G01X103050Y199318D02*
X103054Y199305D01*
G01X103051Y199331D02*
X103050Y199318D01*
G01X102106Y204285D02*
Y204278D01*
G01X102105Y204290D02*
X102106Y204285D01*
G01X102105Y204283D02*
Y204290D01*
G01X103050Y210367D02*
X103051Y210354D01*
G01X103053Y210380D02*
X103050Y210367D01*
G01X103054Y210393D02*
X103053Y210380D01*
G01X103050Y207217D02*
X103051Y207205D01*
G01X103053Y207230D02*
X103050Y207217D01*
G01X103054Y207244D02*
X103053Y207230D01*
G01X103050Y204068D02*
X103051Y204055D01*
G01X103053Y204081D02*
X103050Y204068D01*
G01X103054Y204094D02*
X103053Y204081D01*
G01X103050Y200918D02*
X103051Y200906D01*
G01X103053Y200931D02*
X103050Y200918D01*
G01X103054Y200944D02*
X103053Y200931D01*
G01X103050Y197769D02*
X103051Y197756D01*
G01X103053Y197781D02*
X103050Y197769D01*
G01X103054Y197795D02*
X103053Y197781D01*
G01X102106Y197987D02*
Y197979D01*
G01X102105Y197991D02*
X102106Y197987D01*
G01X102105Y197985D02*
Y197991D01*
G01X102106Y201132D02*
Y201128D01*
G01X102108Y201126D02*
X102106Y201132D01*
G01X102120Y201111D02*
X102108Y201126D01*
G01X102144Y201102D02*
X102120Y201111D01*
G01X102106Y204282D02*
Y204278D01*
G01X102108Y204276D02*
X102106Y204282D01*
G01X102119Y204260D02*
X102108Y204276D01*
G01X102144Y204252D02*
X102119Y204260D01*
G01X102106Y210581D02*
Y210577D01*
G01X102108Y210575D02*
X102106Y210581D01*
G01X102119Y210559D02*
X102108Y210575D01*
G01X102144Y210551D02*
X102119Y210559D01*
G01X102106Y197983D02*
Y197979D01*
G01X102108Y197976D02*
X102106Y197983D01*
G01X102119Y197961D02*
X102108Y197976D01*
G01X102144Y197953D02*
X102119Y197961D01*
G01X116503Y166173D02*
X116514Y166157D01*
G01X116479Y166181D02*
X116503Y166173D01*
G01Y171173D02*
X116514Y171157D01*
G01X116479Y171181D02*
X116503Y171173D01*
G01Y176173D02*
X116514Y176157D01*
G01X116479Y176181D02*
X116503Y176173D01*
G01Y181173D02*
X116514Y181157D01*
G01X116479Y181181D02*
X116503Y181173D01*
G01Y186173D02*
X116514Y186157D01*
G01X116479Y186181D02*
X116503Y186173D01*
G01X116514Y191157D02*
X116516Y191152D01*
G01X116503Y191173D02*
X116514Y191157D01*
G01X116479Y191181D02*
X116503Y191173D01*
G01Y196173D02*
X116514Y196157D01*
G01X116479Y196181D02*
X116503Y196173D01*
G01X102106Y207431D02*
Y207428D01*
G01X102107Y207426D02*
X102106Y207431D01*
G01X102118Y207411D02*
X102107Y207426D01*
G01X102141Y207402D02*
X102118Y207411D01*
G01X102119Y211724D02*
X102143Y211732D01*
G01X102108Y211709D02*
X102119Y211724D01*
G01X102106Y211703D02*
X102108Y211709D01*
G01X102119Y208574D02*
X102143Y208583D01*
G01X102108Y208560D02*
X102119Y208574D01*
G01X102106Y208553D02*
X102108Y208560D01*
G01X102119Y205425D02*
X102143Y205433D01*
G01X102108Y205410D02*
X102119Y205425D01*
G01X102106Y205404D02*
X102108Y205410D01*
G01X102119Y202275D02*
X102143Y202283D01*
G01X102108Y202261D02*
X102119Y202275D01*
G01X102106Y202254D02*
X102108Y202261D01*
G01X102119Y199126D02*
X102143Y199134D01*
G01X102108Y199111D02*
X102119Y199126D01*
G01X102106Y199104D02*
X102108Y199111D01*
G01X103081Y199132D02*
X103085Y199127D01*
G01X103076Y199137D02*
X103081Y199132D01*
G01X103070Y199141D02*
X103076Y199137D01*
G01X103065Y199143D02*
X103070Y199141D01*
G01X103058Y199145D02*
X103065Y199143D01*
G01X103051Y199145D02*
X103058D01*
G01X103081Y202282D02*
X103085Y202277D01*
G01X103076Y202286D02*
X103081Y202282D01*
G01X103070Y202290D02*
X103076Y202286D01*
G01X103065Y202293D02*
X103070Y202290D01*
G01X103058Y202294D02*
X103065Y202293D01*
G01X103051Y202295D02*
X103058Y202294D01*
G01X103081Y205431D02*
X103085Y205426D01*
G01X103076Y205436D02*
X103081Y205431D01*
G01X103070Y205440D02*
X103076Y205436D01*
G01X103065Y205442D02*
X103070Y205440D01*
G01X103058Y205444D02*
X103065Y205442D01*
G01X103051Y205444D02*
X103058D01*
G01X103081Y208581D02*
X103085Y208576D01*
G01X103076Y208585D02*
X103081Y208581D01*
G01X103070Y208589D02*
X103076Y208585D01*
G01X103065Y208592D02*
X103070Y208589D01*
G01X103058Y208594D02*
X103065Y208592D01*
G01X103051Y208594D02*
X103058D01*
G01X103081Y211731D02*
X103085Y211726D01*
G01X103076Y211735D02*
X103081Y211731D01*
G01X103070Y211739D02*
X103076Y211735D01*
G01X103065Y211741D02*
X103070Y211739D01*
G01X103058Y211743D02*
X103065Y211741D01*
G01X103051Y211744D02*
X103058Y211743D01*
G01X102107Y197971D02*
X102106Y197979D01*
G01X102109Y197965D02*
X102107Y197971D01*
G01X102113Y197958D02*
X102109Y197965D01*
G01X102118Y197952D02*
X102113Y197958D01*
G01X102124Y197948D02*
X102118Y197952D01*
G01X102131Y197944D02*
X102124Y197948D01*
G01X102138Y197943D02*
X102131Y197944D01*
G01X102146Y197942D02*
X102138Y197943D01*
G01X102107Y201121D02*
X102106Y201128D01*
G01X102109Y201114D02*
X102107Y201121D01*
G01X102113Y201108D02*
X102109Y201114D01*
G01X102118Y201102D02*
X102113Y201108D01*
G01X102124Y201097D02*
X102118Y201102D01*
G01X102131Y201094D02*
X102124Y201097D01*
G01X102138Y201092D02*
X102131Y201094D01*
G01X102146Y201091D02*
X102138Y201092D01*
G01X102107Y204270D02*
X102106Y204278D01*
G01X102109Y204264D02*
X102107Y204270D01*
G01X102113Y204257D02*
X102109Y204264D01*
G01X102118Y204252D02*
X102113Y204257D01*
G01X102124Y204247D02*
X102118Y204252D01*
G01X102131Y204244D02*
X102124Y204247D01*
G01X102138Y204242D02*
X102131Y204244D01*
G01X102146Y204241D02*
X102138Y204242D01*
G01X102107Y207420D02*
X102106Y207428D01*
G01X102109Y207413D02*
X102107Y207420D01*
G01X102113Y207407D02*
X102109Y207413D01*
G01X102118Y207401D02*
X102113Y207407D01*
G01X102124Y207396D02*
X102118Y207401D01*
G01X102131Y207393D02*
X102124Y207396D01*
G01X102138Y207391D02*
X102131Y207393D01*
G01X102146Y207391D02*
X102138D01*
G01X102107Y210570D02*
X102106Y210577D01*
G01X102109Y210563D02*
X102107Y210570D01*
G01X102113Y210557D02*
X102109Y210563D01*
G01X102118Y210551D02*
X102113Y210557D01*
G01X102124Y210546D02*
X102118Y210551D01*
G01X102131Y210543D02*
X102124Y210546D01*
G01X102138Y210541D02*
X102131Y210543D01*
G01X102146Y210540D02*
X102138Y210541D01*
G01X103060Y199133D02*
X103070Y199128D01*
G01X103050Y199134D02*
X103060Y199133D01*
G01Y202282D02*
X103070Y202278D01*
G01X103050Y202283D02*
X103060Y202282D01*
G01Y205432D02*
X103070Y205428D01*
G01X103050Y205433D02*
X103060Y205432D01*
G01Y208581D02*
X103070Y208577D01*
G01X103050Y208583D02*
X103060Y208581D01*
G01Y211731D02*
X103070Y211727D01*
G01X103050Y211732D02*
X103060Y211731D01*
G01X103091Y211699D02*
Y211706D01*
G01X103090Y211695D02*
X103091Y211699D01*
G01X103089Y211693D02*
X103090Y211695D01*
G01X103091Y208550D02*
Y208557D01*
G01X103090Y208545D02*
X103091Y208550D01*
G01X103089Y208543D02*
X103090Y208545D01*
G01X103091Y205400D02*
Y205407D01*
G01X103090Y205396D02*
X103091Y205400D01*
G01X103089Y205394D02*
X103090Y205396D01*
G01X103091Y202250D02*
Y202257D01*
G01X103090Y202246D02*
X103091Y202250D01*
G01X103089Y202244D02*
X103090Y202246D01*
G01X103091Y199101D02*
Y199108D01*
G01X103090Y199096D02*
X103091Y199101D01*
G01X103089Y199094D02*
X103090Y199096D01*
G01X102106Y207435D02*
Y207428D01*
G01X102105Y207440D02*
X102106Y207435D01*
G01X102104Y207437D02*
X102105Y207440D01*
G01X103068Y197945D02*
X103071Y197947D01*
G01X103065Y197944D02*
X103068Y197945D01*
G01X103062Y197943D02*
X103065Y197944D01*
G01X103058Y197942D02*
X103062Y197943D01*
G01X103055Y197942D02*
X103058D01*
G01X103051D02*
X103055D01*
G01X102129Y199142D02*
X102126Y199140D01*
G01X102132Y199143D02*
X102129Y199142D01*
G01X102135Y199144D02*
X102132Y199143D01*
G01X102139Y199144D02*
X102135D01*
G01X102142Y199145D02*
X102139Y199144D01*
G01X102146Y199145D02*
X102142D01*
G01X103068Y201095D02*
X103071Y201096D01*
G01X103065Y201094D02*
X103068Y201095D01*
G01X103062Y201093D02*
X103065Y201094D01*
G01X103058Y201092D02*
X103062Y201093D01*
G01X103055Y201091D02*
X103058Y201092D01*
G01X103051Y201091D02*
X103055D01*
G01X102129Y202291D02*
X102126Y202290D01*
G01X102132Y202293D02*
X102129Y202291D01*
G01X102135Y202294D02*
X102132Y202293D01*
G01X102139Y202294D02*
X102135D01*
G01X102142Y202295D02*
X102139Y202294D01*
G01X102146Y202295D02*
X102142D01*
G01X103068Y204244D02*
X103071Y204246D01*
G01X103065Y204243D02*
X103068Y204244D01*
G01X103062Y204242D02*
X103065Y204243D01*
G01X103058Y204241D02*
X103062Y204242D01*
G01X103055Y204241D02*
X103058D01*
G01X103051D02*
X103055D01*
G01X102129Y205441D02*
X102126Y205439D01*
G01X102132Y205442D02*
X102129Y205441D01*
G01X102135Y205443D02*
X102132Y205442D01*
G01X102139Y205444D02*
X102135Y205443D01*
G01X102142Y205444D02*
X102139D01*
G01X102146D02*
X102142D01*
G01X103068Y207394D02*
X103071Y207396D01*
G01X103065Y207393D02*
X103068Y207394D01*
G01X103062Y207392D02*
X103065Y207393D01*
G01X103058Y207391D02*
X103062Y207392D01*
G01X103055Y207391D02*
X103058D01*
G01X103051D02*
X103055D01*
G01X102129Y208591D02*
X102126Y208589D01*
G01X102132Y208592D02*
X102129Y208591D01*
G01X102135Y208593D02*
X102132Y208592D01*
G01X102139Y208593D02*
X102135D01*
G01X102142Y208594D02*
X102139Y208593D01*
G01X102146Y208594D02*
X102142D01*
G01X103068Y210544D02*
X103071Y210545D01*
G01X103065Y210543D02*
X103068Y210544D01*
G01X103062Y210541D02*
X103065Y210543D01*
G01X103058Y210541D02*
X103062D01*
G01X103055Y210540D02*
X103058Y210541D01*
G01X103051Y210540D02*
X103055D01*
G01X102129Y211740D02*
X102126Y211739D01*
G01X102132Y211741D02*
X102129Y211740D01*
G01X102135Y211743D02*
X102132Y211741D01*
G01X102139Y211743D02*
X102135D01*
G01X102142Y211744D02*
X102139Y211743D01*
G01X102146Y211744D02*
X102142D01*
G01X101359Y201142D02*
X100925D01*
G01X101733D02*
X101359D01*
G01Y207441D02*
X100925D01*
G01X101733D02*
X101359D01*
G01Y210591D02*
X100925D01*
G01X101732D02*
X101359D01*
G01X102106Y201136D02*
Y201128D01*
G01X102105Y201141D02*
X102106Y201136D01*
G01X102104Y201138D02*
X102105Y201141D01*
G01X103051Y211737D02*
Y211744D01*
G01X103050Y211734D02*
X103051Y211737D01*
G01X103050Y211732D02*
Y211734D01*
G01X103051Y208588D02*
Y208594D01*
G01X103050Y208584D02*
X103051Y208588D01*
G01X103050Y208583D02*
Y208584D01*
G01X103051Y205438D02*
Y205444D01*
G01X103050Y205435D02*
X103051Y205438D01*
G01X103050Y205433D02*
Y205435D01*
G01X103051Y202289D02*
Y202295D01*
G01X103050Y202285D02*
X103051Y202289D01*
G01X103050Y202283D02*
Y202285D01*
G01X103051Y199139D02*
Y199145D01*
G01X103050Y199135D02*
X103051Y199139D01*
G01X103050Y199134D02*
Y199135D01*
G01X116516Y194796D02*
Y194787D01*
G01X116517Y194802D02*
X116516Y194796D01*
G01X116519Y194803D02*
X116517Y194802D01*
G01X116516Y189796D02*
Y189787D01*
G01X116517Y189802D02*
X116516Y189796D01*
G01X116519Y189803D02*
X116517Y189802D01*
G01X116516Y184796D02*
Y184787D01*
G01X116517Y184802D02*
X116516Y184796D01*
G01X116519Y184803D02*
X116517Y184802D01*
G01X116516Y179796D02*
Y179787D01*
G01X116517Y179802D02*
X116516Y179796D01*
G01X116519Y179803D02*
X116517Y179802D01*
G01X116516Y174796D02*
Y174787D01*
G01X116517Y174802D02*
X116516Y174796D01*
G01X116519Y174803D02*
X116517Y174802D01*
G01X116516Y169796D02*
Y169787D01*
G01X116517Y169802D02*
X116516Y169796D01*
G01X116519Y169803D02*
X116517Y169802D01*
G01X116516Y164796D02*
Y164787D01*
G01X116517Y164802D02*
X116516Y164796D01*
G01X116519Y164803D02*
X116517Y164802D01*
G01X102109Y199114D02*
X102104Y199094D01*
G01X102124Y199129D02*
X102109Y199114D01*
G01X102143Y199134D02*
X102124Y199129D01*
G01X102109Y202264D02*
X102104Y202244D01*
G01X102124Y202278D02*
X102109Y202264D01*
G01X102143Y202283D02*
X102124Y202278D01*
G01X102109Y205413D02*
X102104Y205394D01*
G01X102124Y205428D02*
X102109Y205413D01*
G01X102143Y205433D02*
X102124Y205428D01*
G01X102109Y208563D02*
X102104Y208543D01*
G01X102124Y208578D02*
X102109Y208563D01*
G01X102143Y208583D02*
X102124Y208578D01*
G01X102109Y211713D02*
X102104Y211693D01*
G01X102124Y211727D02*
X102109Y211713D01*
G01X102143Y211732D02*
X102124Y211727D01*
G01X103084Y197972D02*
X103089Y197992D01*
G01X103069Y197958D02*
X103084Y197972D01*
G01X103050Y197953D02*
X103069Y197958D01*
G01X103084Y201122D02*
X103089Y201142D01*
G01X103069Y201108D02*
X103084Y201122D01*
G01X103050Y201102D02*
X103069Y201108D01*
G01X103084Y204272D02*
X103089Y204291D01*
G01X103069Y204257D02*
X103084Y204272D01*
G01X103050Y204252D02*
X103069Y204257D01*
G01X103084Y207421D02*
X103089Y207441D01*
G01X103069Y207407D02*
X103084Y207421D01*
G01X103050Y207402D02*
X103069Y207407D01*
G01X103084Y210571D02*
X103089Y210591D01*
G01X103069Y210557D02*
X103084Y210571D01*
G01X103050Y210551D02*
X103069Y210557D01*
G01X102106Y211699D02*
Y211707D01*
G01X102105Y211694D02*
X102106Y211699D01*
G01X102104Y211693D02*
X102105Y211694D01*
G01X102106Y208550D02*
Y208557D01*
G01X102105Y208545D02*
X102106Y208550D01*
G01X102104Y208543D02*
X102105Y208545D01*
G01X102106Y205400D02*
Y205407D01*
G01X102105Y205395D02*
X102106Y205400D01*
G01X102104Y205394D02*
X102105Y205395D01*
G01X102106Y202250D02*
Y202258D01*
G01X102105Y202246D02*
X102106Y202250D01*
G01X102104Y202244D02*
X102105Y202246D01*
G01X102106Y199101D02*
Y199108D01*
G01X102105Y199096D02*
X102106Y199101D01*
G01X102104Y199094D02*
X102105Y199096D01*
G01X103088Y210565D02*
X103091Y210577D01*
G01X103081Y210554D02*
X103088Y210565D01*
G01X103071Y210545D02*
X103081Y210554D01*
G01X103088Y207415D02*
X103091Y207428D01*
G01X103081Y207404D02*
X103088Y207415D01*
G01X103071Y207396D02*
X103081Y207404D01*
G01X103088Y204265D02*
X103091Y204278D01*
G01X103081Y204254D02*
X103088Y204265D01*
G01X103071Y204246D02*
X103081Y204254D01*
G01X103088Y201116D02*
X103091Y201128D01*
G01X103081Y201105D02*
X103088Y201116D01*
G01X103071Y201096D02*
X103081Y201105D01*
G01X103088Y197966D02*
X103091Y197979D01*
G01X103081Y197955D02*
X103088Y197966D01*
G01X103071Y197947D02*
X103081Y197955D01*
G01X102145Y211737D02*
Y211744D01*
G01Y211733D02*
Y211737D01*
G01X102143Y211732D02*
X102145Y211733D01*
G01Y208588D02*
Y208594D01*
G01Y208584D02*
Y208588D01*
G01X102143Y208583D02*
X102145Y208584D01*
G01Y205438D02*
Y205444D01*
G01Y205434D02*
Y205438D01*
G01X102143Y205433D02*
X102145Y205434D01*
G01Y202289D02*
Y202295D01*
G01Y202285D02*
Y202289D01*
G01X102143Y202283D02*
X102145Y202285D01*
G01Y199139D02*
Y199145D01*
G01Y199135D02*
Y199139D01*
G01X102143Y199134D02*
X102145Y199135D01*
G01X102107Y211713D02*
X102106Y211707D01*
G01X102109Y211719D02*
X102107Y211713D01*
G01X102111Y211725D02*
X102109Y211719D01*
G01X102115Y211730D02*
X102111Y211725D01*
G01X102120Y211735D02*
X102115Y211730D01*
G01X102126Y211739D02*
X102120Y211735D01*
G01X102107Y208563D02*
X102106Y208557D01*
G01X102109Y208570D02*
X102107Y208563D01*
G01X102111Y208575D02*
X102109Y208570D01*
G01X102115Y208581D02*
X102111Y208575D01*
G01X102120Y208585D02*
X102115Y208581D01*
G01X102126Y208589D02*
X102120Y208585D01*
G01X102107Y205414D02*
X102106Y205407D01*
G01X102109Y205420D02*
X102107Y205414D01*
G01X102111Y205426D02*
X102109Y205420D01*
G01X102115Y205431D02*
X102111Y205426D01*
G01X102120Y205435D02*
X102115Y205431D01*
G01X102126Y205439D02*
X102120Y205435D01*
G01X102107Y202264D02*
X102106Y202258D01*
G01X102109Y202270D02*
X102107Y202264D01*
G01X102111Y202276D02*
X102109Y202270D01*
G01X102115Y202281D02*
X102111Y202276D01*
G01X102120Y202286D02*
X102115Y202281D01*
G01X102126Y202290D02*
X102120Y202286D01*
G01X102107Y199115D02*
X102106Y199108D01*
G01X102109Y199121D02*
X102107Y199115D01*
G01X102111Y199126D02*
X102109Y199121D01*
G01X102115Y199132D02*
X102111Y199126D01*
G01X102120Y199136D02*
X102115Y199132D01*
G01X102126Y199140D02*
X102120Y199136D01*
G01X103062Y210553D02*
X103050Y210551D01*
G01X103072Y210558D02*
X103062Y210553D01*
G01Y207404D02*
X103050Y207402D01*
G01X103072Y207409D02*
X103062Y207404D01*
G01Y204254D02*
X103050Y204252D01*
G01X103072Y204259D02*
X103062Y204254D01*
G01Y201104D02*
X103050Y201102D01*
G01X103072Y201109D02*
X103062Y201104D01*
G01Y197955D02*
X103050Y197953D01*
G01X103072Y197960D02*
X103062Y197955D01*
G01X102104Y207437D02*
X101993Y207441D01*
G01X102104Y201138D02*
X101993Y201142D01*
G01X102104Y210587D02*
X101993Y210591D01*
G01X103051Y211929D02*
X102146D01*
G01X103091Y211890D02*
X102106D01*
G01X103050Y211732D02*
X97165D01*
G01Y211693D02*
X103089D01*
G01Y210591D02*
X97165D01*
G01X103050Y210551D02*
X97165D01*
G01X102106Y210394D02*
X103091D01*
G01X102146Y210354D02*
X103051D01*
G01Y208780D02*
X102146D01*
G01X103091Y208740D02*
X102106D01*
G01X103050Y208583D02*
X97165D01*
G01Y208543D02*
X103089D01*
G01Y207441D02*
X97165D01*
G01X103050Y207402D02*
X97165D01*
G01X102106Y207244D02*
X103091D01*
G01X102146Y207205D02*
X103051D01*
G01Y205630D02*
X102146D01*
G01X103091Y205591D02*
X102106D01*
G01X103050Y205433D02*
X97165D01*
G01Y205394D02*
X103089D01*
G01Y204291D02*
X97165D01*
G01X103050Y204252D02*
X97165D01*
G01X102106Y204094D02*
X103091D01*
G01X102146Y204055D02*
X103051D01*
G01Y202480D02*
X102146D01*
G01X103091Y202441D02*
X102106D01*
G01X103050Y202283D02*
X97165D01*
G01Y202244D02*
X103089D01*
G01Y201142D02*
X97165D01*
G01X103050Y201102D02*
X97165D01*
G01X102106Y200945D02*
X103091D01*
G01X102146Y200906D02*
X103051D01*
G01Y199331D02*
X102146D01*
G01X103091Y199291D02*
X102106D01*
G01X103050Y199134D02*
X97165D01*
G01Y199094D02*
X103089D01*
G01X115945Y198130D02*
X112008D01*
G01X103089Y197992D02*
X97165D01*
G01X103050Y197953D02*
X97165D01*
G01X102106Y197795D02*
X103091D01*
G01X102146Y197756D02*
X103051D01*
G01X117126Y196949D02*
X113189D01*
G01X116516Y196673D02*
X115531D01*
G01X115533Y196181D02*
X120866D01*
G01Y196142D02*
X116518D01*
G01X103543Y195787D02*
X100197D01*
G01X120866Y194803D02*
X115533D01*
G01X115531Y194311D02*
X116516D01*
G01Y191673D02*
X115531D01*
G01X115533Y191181D02*
X120866D01*
G01Y191142D02*
X116518D01*
G01X120866Y189803D02*
X115533D01*
G01X115531Y189311D02*
X116516D01*
G01Y186673D02*
X115531D01*
G01X115533Y186181D02*
X120866D01*
G01Y186142D02*
X116518D01*
G01X120866Y184803D02*
X115533D01*
G01X115531Y184311D02*
X116516D01*
G01Y181673D02*
X115531D01*
G01X115533Y181181D02*
X120866D01*
G01Y181142D02*
X116518D01*
G01X120866Y179803D02*
X115533D01*
G01X115531Y179311D02*
X116516D01*
G01Y176673D02*
X115531D01*
G01X115533Y176181D02*
X120866D01*
G01Y176142D02*
X116518D01*
G01X120866Y174803D02*
X115533D01*
G01X115531Y174311D02*
X116516D01*
G01Y171673D02*
X115531D01*
G01X115533Y171181D02*
X120866D01*
G01Y171142D02*
X116518D01*
G01X120866Y169803D02*
X115533D01*
G01X115531Y169311D02*
X116516D01*
G01X115531Y196377D02*
X116487Y196378D01*
G01X116516Y194607D02*
X115531Y194606D01*
G01Y191377D02*
X116487Y191378D01*
G01X116516Y189607D02*
X115531Y189606D01*
G01Y186377D02*
X116487Y186378D01*
G01X116516Y184607D02*
X115531Y184606D01*
G01Y181377D02*
X116487Y181378D01*
G01X116516Y179607D02*
X115531Y179606D01*
G01Y176377D02*
X116487Y176378D01*
G01X116516Y174607D02*
X115531Y174606D01*
G01Y171377D02*
X116487Y171378D01*
G01X116516Y169607D02*
X115531Y169606D01*
G01Y166377D02*
X116487Y166378D01*
G01X116516Y166673D02*
X115531D01*
G01X115533Y166181D02*
X120866D01*
G01Y166142D02*
X116518D01*
G01X120866Y164803D02*
X115533D01*
G01X115531Y164311D02*
X116516D01*
G01Y164607D02*
X115531Y164606D01*
G01X103090Y199097D02*
X103091Y199108D01*
G01X103090Y202246D02*
X103091Y202257D01*
G01X103090Y205396D02*
X103091Y205407D01*
G01X103090Y208546D02*
X103091Y208557D01*
G01X103090Y211695D02*
X103091Y211706D01*
G01X116516Y166155D02*
Y166164D01*
G01Y171155D02*
Y171164D01*
G01Y176155D02*
Y176164D01*
G01Y181155D02*
Y181164D01*
G01Y186155D02*
Y186164D01*
G01Y191155D02*
Y191164D01*
G01Y196155D02*
Y196164D01*
G01X117697Y166181D02*
Y164803D01*
G01Y171181D02*
Y169803D01*
G01Y176181D02*
Y174803D01*
G01Y181181D02*
Y179803D01*
G01Y186181D02*
Y184803D01*
G01Y191181D02*
Y189803D01*
G01Y196181D02*
Y194803D01*
G01X117126Y219035D02*
Y196949D01*
G01X116516Y166156D02*
Y166299D01*
G01Y176156D02*
Y176299D01*
G01Y171156D02*
Y171299D01*
G01Y186156D02*
Y186299D01*
G01Y181156D02*
Y181299D01*
G01Y196156D02*
Y196299D01*
G01Y191156D02*
Y191299D01*
G01Y194311D02*
Y196673D01*
G01Y189311D02*
Y191673D01*
G01Y184311D02*
Y186673D01*
G01Y179311D02*
Y181673D01*
G01Y174311D02*
Y176673D01*
G01Y169311D02*
Y171673D01*
G01Y164311D02*
Y166673D01*
G01X115945Y217854D02*
Y198130D01*
G01X115531Y166673D02*
Y164311D01*
G01Y171673D02*
Y169311D01*
G01Y176673D02*
Y174311D01*
G01Y181673D02*
Y179311D01*
G01Y186673D02*
Y184311D01*
G01Y191673D02*
Y189311D01*
G01Y196673D02*
Y194311D01*
G01X103091Y210394D02*
Y211890D01*
G01Y207244D02*
Y208740D01*
G01Y204094D02*
Y205591D01*
G01Y200945D02*
Y202441D01*
G01Y197795D02*
Y199291D01*
G01X103051Y197942D02*
Y197795D01*
G01Y201091D02*
Y200944D01*
G01Y202441D02*
Y202295D01*
G01Y199292D02*
Y199145D01*
G01Y207391D02*
Y207244D01*
G01Y204241D02*
Y204094D01*
G01Y205591D02*
Y205444D01*
G01Y210540D02*
Y210393D01*
G01Y211890D02*
Y211744D01*
G01Y208741D02*
Y208594D01*
G01X102146Y210393D02*
Y210540D01*
G01Y211744D02*
Y211891D01*
G01Y208594D02*
Y208741D01*
G01Y207243D02*
Y207391D01*
G01Y204094D02*
Y204241D01*
G01Y205444D02*
Y205591D01*
G01Y200944D02*
Y201091D01*
G01Y202295D02*
Y202442D01*
G01Y199145D02*
Y199292D01*
G01Y197794D02*
Y197942D01*
G01X102106Y202441D02*
Y200945D01*
G01Y199291D02*
Y197795D01*
G01Y205591D02*
Y204094D01*
G01Y211890D02*
Y210394D01*
G01Y208740D02*
Y207244D01*
G01X100925Y199134D02*
Y197953D01*
G01Y202283D02*
Y201102D01*
G01Y208583D02*
Y207402D01*
G01Y205433D02*
Y204252D01*
G01Y211732D02*
Y210551D01*
G01X100591Y220197D02*
Y195787D01*
G01X100197D02*
Y220197D01*
G01X97165Y210551D02*
Y211732D01*
G01Y207402D02*
Y208583D01*
G01Y204252D02*
Y205433D01*
G01Y201102D02*
Y202283D01*
G01Y197953D02*
Y199134D01*
G01X103091Y210577D02*
X103090Y210588D01*
G01X103091Y207428D02*
X103090Y207439D01*
G01X103091Y204278D02*
X103090Y204289D01*
G01X103091Y201128D02*
X103090Y201139D01*
G01X103091Y197979D02*
X103090Y197990D01*
G01X115945Y198130D02*
X117126Y196949D01*
G01X112008Y198130D02*
X113189Y196949D01*
G01X102145Y213696D02*
X102146Y213690D01*
G01X102144Y213700D02*
X102145Y213696D01*
G01X102143Y213701D02*
X102144Y213700D01*
G01X102145Y216846D02*
X102146Y216839D01*
G01X102144Y216849D02*
X102145Y216846D01*
G01X102143Y216850D02*
X102144Y216849D01*
G01X116516Y221148D02*
Y221156D01*
G01X116517Y221144D02*
X116516Y221148D01*
G01X116518Y221142D02*
X116517Y221144D01*
G01X116516Y226148D02*
Y226156D01*
G01X116517Y226144D02*
X116516Y226148D01*
G01X116518Y226142D02*
X116517Y226144D01*
G01X116516Y231148D02*
Y231156D01*
G01X116517Y231144D02*
X116516Y231148D01*
G01X116518Y231142D02*
X116517Y231144D01*
G01X116516Y236148D02*
Y236156D01*
G01X116517Y236144D02*
X116516Y236148D01*
G01X116518Y236142D02*
X116517Y236144D01*
G01X116516Y241148D02*
Y241156D01*
G01X116517Y241144D02*
X116516Y241148D01*
G01X116518Y241142D02*
X116517Y241144D01*
G01X116516Y246148D02*
Y246156D01*
G01X116517Y246144D02*
X116516Y246148D01*
G01X116518Y246142D02*
X116517Y246144D01*
G01X116516Y251148D02*
Y251156D01*
G01X116517Y251144D02*
X116516Y251148D01*
G01X116518Y251142D02*
X116517Y251144D01*
G01X116516Y256148D02*
Y256156D01*
G01X116517Y256144D02*
X116516Y256148D01*
G01X116518Y256142D02*
X116517Y256144D01*
G01X102129Y213704D02*
X102143Y213701D01*
G01X102117Y213711D02*
X102129Y213704D01*
G01X102105Y213731D02*
X102117Y213711D01*
G01X103091Y213734D02*
Y213727D01*
G01X103090Y213739D02*
X103091Y213734D01*
G01X103089Y213740D02*
X103090Y213739D01*
G01X103091Y216884D02*
Y216876D01*
G01X103090Y216889D02*
X103091Y216884D01*
G01X103089Y216890D02*
X103090Y216889D01*
G01X102129Y216853D02*
X102143Y216850D01*
G01X102116Y216861D02*
X102129Y216853D01*
G01X102105Y216881D02*
X102116Y216861D01*
G01X103090Y214863D02*
X103091Y214856D01*
G01X103088Y214869D02*
X103090Y214863D01*
G01X103085Y214875D02*
X103088Y214869D01*
G01X103090Y218013D02*
X103091Y218006D01*
G01X103088Y218019D02*
X103090Y218013D01*
G01X103085Y218025D02*
X103088Y218019D01*
G01X103052Y216845D02*
Y216839D01*
G01X103050Y216849D02*
X103052Y216845D01*
G01X103050Y216850D02*
Y216849D01*
G01X115531Y221189D02*
Y221198D01*
G01X115532Y221183D02*
X115531Y221189D01*
G01X115533Y221181D02*
X115532Y221183D01*
G01X115531Y226189D02*
Y226198D01*
G01X115532Y226183D02*
X115531Y226189D01*
G01X115533Y226181D02*
X115532Y226183D01*
G01X115531Y231189D02*
Y231198D01*
G01X115532Y231183D02*
X115531Y231189D01*
G01X115533Y231181D02*
X115532Y231183D01*
G01X115531Y236189D02*
Y236198D01*
G01X115532Y236183D02*
X115531Y236189D01*
G01X115533Y236181D02*
X115532Y236183D01*
G01X115531Y241189D02*
Y241198D01*
G01X115532Y241183D02*
X115531Y241189D01*
G01X115533Y241181D02*
X115532Y241183D01*
G01X115531Y246189D02*
Y246198D01*
G01X115532Y246183D02*
X115531Y246189D01*
G01X115533Y246181D02*
X115532Y246183D01*
G01X115531Y251189D02*
Y251198D01*
G01X115532Y251183D02*
X115531Y251189D01*
G01X115533Y251181D02*
X115532Y251183D01*
G01X115531Y256189D02*
Y256198D01*
G01X115532Y256183D02*
X115531Y256189D01*
G01X115533Y256181D02*
X115532Y256183D01*
G01X116508Y221325D02*
X116516Y221299D01*
G01X116498Y221352D02*
X116508Y221325D01*
G01X116487Y221378D02*
X116498Y221352D01*
G01X116508Y226325D02*
X116516Y226299D01*
G01X116498Y226352D02*
X116508Y226325D01*
G01X116487Y226378D02*
X116498Y226352D01*
G01X116508Y231325D02*
X116516Y231299D01*
G01X116498Y231352D02*
X116508Y231325D01*
G01X116487Y231378D02*
X116498Y231352D01*
G01X116508Y236325D02*
X116516Y236299D01*
G01X116498Y236352D02*
X116508Y236325D01*
G01X116487Y236378D02*
X116498Y236352D01*
G01X116508Y241325D02*
X116516Y241299D01*
G01X116498Y241352D02*
X116508Y241325D01*
G01X116487Y241378D02*
X116498Y241352D01*
G01X116508Y246325D02*
X116516Y246299D01*
G01X116498Y246352D02*
X116508Y246325D01*
G01X116487Y246378D02*
X116498Y246352D01*
G01X116508Y251325D02*
X116516Y251299D01*
G01X116498Y251352D02*
X116508Y251325D01*
G01X116487Y251378D02*
X116498Y251352D01*
G01X116508Y256325D02*
X116516Y256299D01*
G01X116498Y256352D02*
X116508Y256325D01*
G01X116487Y256378D02*
X116498Y256352D01*
G01X116483Y221279D02*
X116487Y221378D01*
G01X116477Y221207D02*
X116483Y221279D01*
G01X116479Y221181D02*
X116477Y221207D01*
G01X116483Y226279D02*
X116487Y226378D01*
G01X116477Y226207D02*
X116483Y226279D01*
G01X116479Y226181D02*
X116477Y226207D01*
G01X116483Y231279D02*
X116487Y231378D01*
G01X116477Y231207D02*
X116483Y231279D01*
G01X116479Y231181D02*
X116477Y231207D01*
G01X116483Y236279D02*
X116487Y236378D01*
G01X116477Y236207D02*
X116483Y236279D01*
G01X116479Y236181D02*
X116477Y236207D01*
G01X116483Y241279D02*
X116487Y241378D01*
G01X116477Y241207D02*
X116483Y241279D01*
G01X116479Y241181D02*
X116477Y241207D01*
G01X116483Y246279D02*
X116487Y246378D01*
G01X116477Y246207D02*
X116483Y246279D01*
G01X116479Y246181D02*
X116477Y246207D01*
G01X116483Y251279D02*
X116487Y251378D01*
G01X116477Y251207D02*
X116483Y251279D01*
G01X116479Y251181D02*
X116477Y251207D01*
G01X116483Y256279D02*
X116487Y256378D01*
G01X116477Y256207D02*
X116483Y256279D01*
G01X116479Y256181D02*
X116477Y256207D01*
G01X103059Y214881D02*
X103050Y214882D01*
G01X103068Y214878D02*
X103059Y214881D01*
G01X103076Y214872D02*
X103068Y214878D01*
G01X103059Y218030D02*
X103050Y218031D01*
G01X103068Y218027D02*
X103059Y218030D01*
G01X103076Y218022D02*
X103068Y218027D01*
G01X116498Y221176D02*
X116479Y221181D01*
G01X116513Y221162D02*
X116498Y221176D01*
G01X116518Y221142D02*
X116513Y221162D01*
G01X116498Y226176D02*
X116479Y226181D01*
G01X116513Y226162D02*
X116498Y226176D01*
G01X116518Y226142D02*
X116513Y226162D01*
G01X116498Y231176D02*
X116479Y231181D01*
G01X116513Y231162D02*
X116498Y231176D01*
G01X116518Y231142D02*
X116513Y231162D01*
G01X116498Y236176D02*
X116479Y236181D01*
G01X116513Y236162D02*
X116498Y236176D01*
G01X116518Y236142D02*
X116513Y236162D01*
G01X116498Y241176D02*
X116479Y241181D01*
G01X116513Y241162D02*
X116498Y241176D01*
G01X116518Y241142D02*
X116513Y241162D01*
G01X116498Y246176D02*
X116479Y246181D01*
G01X116513Y246162D02*
X116498Y246176D01*
G01X116518Y246142D02*
X116513Y246162D01*
G01X116498Y251176D02*
X116479Y251181D01*
G01X116513Y251162D02*
X116498Y251176D01*
G01X116518Y251142D02*
X116513Y251162D01*
G01X116498Y256176D02*
X116479Y256181D01*
G01X116513Y256162D02*
X116498Y256176D01*
G01X116518Y256142D02*
X116513Y256162D01*
G01X103083Y214864D02*
X103076Y214872D01*
G01X103088Y214854D02*
X103083Y214864D01*
G01X103089Y214843D02*
X103088Y214854D01*
G01X103083Y218013D02*
X103076Y218022D01*
G01X103088Y218003D02*
X103083Y218013D01*
G01X103089Y217992D02*
X103088Y218003D01*
G01X102146Y218216D02*
Y218228D01*
G01X102143Y218203D02*
X102146Y218216D01*
G01X102143Y218189D02*
Y218203D01*
G01X102146Y215067D02*
Y215079D01*
G01X102143Y215054D02*
X102146Y215067D01*
G01X102143Y215040D02*
Y215054D01*
G01X115532Y259802D02*
X115533Y259803D01*
G01X115531Y259796D02*
X115532Y259802D01*
G01X115531Y259787D02*
Y259796D01*
G01X115532Y254802D02*
X115533Y254803D01*
G01X115531Y254796D02*
X115532Y254802D01*
G01X115531Y254787D02*
Y254796D01*
G01X115532Y249802D02*
X115533Y249803D01*
G01X115531Y249796D02*
X115532Y249802D01*
G01X115531Y249787D02*
Y249796D01*
G01X115532Y244802D02*
X115533Y244803D01*
G01X115531Y244796D02*
X115532Y244802D01*
G01X115531Y244787D02*
Y244796D01*
G01X115532Y239802D02*
X115533Y239803D01*
G01X115531Y239796D02*
X115532Y239802D01*
G01X115531Y239787D02*
Y239796D01*
G01X115532Y234802D02*
X115533Y234803D01*
G01X115531Y234796D02*
X115532Y234802D01*
G01X115531Y234787D02*
Y234796D01*
G01X115532Y229802D02*
X115533Y229803D01*
G01X115531Y229796D02*
X115532Y229802D01*
G01X115531Y229787D02*
Y229796D01*
G01X115532Y224802D02*
X115533Y224803D01*
G01X115531Y224796D02*
X115532Y224802D01*
G01X115531Y224787D02*
Y224796D01*
G01X115532Y219802D02*
X115533Y219803D01*
G01X115531Y219796D02*
X115532Y219802D01*
G01X115531Y219787D02*
Y219796D01*
G01X102106Y216884D02*
Y216876D01*
G01X102105Y216889D02*
X102106Y216884D01*
G01X102105Y216881D02*
Y216889D01*
G01X102143Y216679D02*
X102142Y216693D01*
G01X102146Y216666D02*
X102143Y216679D01*
G01X102146Y216654D02*
Y216666D01*
G01X102143Y213530D02*
X102142Y213543D01*
G01X102146Y213517D02*
X102143Y213530D01*
G01X102146Y213504D02*
Y213517D01*
G01X103054Y218203D02*
X103055Y218189D01*
G01X103050Y218216D02*
X103054Y218203D01*
G01X103051Y218228D02*
X103050Y218216D01*
G01X103054Y215053D02*
X103055Y215040D01*
G01X103050Y215066D02*
X103054Y215053D01*
G01X103051Y215079D02*
X103050Y215066D01*
G01X102106Y213734D02*
Y213727D01*
G01X102105Y213739D02*
X102106Y213734D01*
G01X102105Y213732D02*
Y213739D01*
G01X103050Y216666D02*
X103051Y216654D01*
G01X103053Y216679D02*
X103050Y216666D01*
G01X103054Y216693D02*
X103053Y216679D01*
G01X103050Y213517D02*
X103051Y213504D01*
G01X103053Y213530D02*
X103050Y213517D01*
G01X103054Y213543D02*
X103053Y213530D01*
G01X102106Y213731D02*
Y213727D01*
G01X102108Y213724D02*
X102106Y213731D01*
G01X102119Y213709D02*
X102108Y213724D01*
G01X102144Y213701D02*
X102119Y213709D01*
G01X102106Y216880D02*
Y216876D01*
G01X102108Y216874D02*
X102106Y216880D01*
G01X102119Y216859D02*
X102108Y216874D01*
G01X102144Y216850D02*
X102119Y216859D01*
G01X116503Y221173D02*
X116514Y221157D01*
G01X116479Y221181D02*
X116503Y221173D01*
G01Y226173D02*
X116514Y226157D01*
G01X116479Y226181D02*
X116503Y226173D01*
G01Y231173D02*
X116514Y231157D01*
G01X116479Y231181D02*
X116503Y231173D01*
G01Y236173D02*
X116514Y236157D01*
G01X116479Y236181D02*
X116503Y236173D01*
G01Y241173D02*
X116514Y241157D01*
G01X116479Y241181D02*
X116503Y241173D01*
G01Y246173D02*
X116514Y246157D01*
G01X116479Y246181D02*
X116503Y246173D01*
G01Y251173D02*
X116514Y251157D01*
G01X116479Y251181D02*
X116503Y251173D01*
G01Y256173D02*
X116514Y256157D01*
G01X116479Y256181D02*
X116503Y256173D01*
G01X102119Y218023D02*
X102143Y218031D01*
G01X102108Y218009D02*
X102119Y218023D01*
G01X102106Y218002D02*
X102108Y218009D01*
G01X102119Y214874D02*
X102143Y214882D01*
G01X102108Y214859D02*
X102119Y214874D01*
G01X102106Y214852D02*
X102108Y214859D01*
G01X103081Y214880D02*
X103085Y214875D01*
G01X103076Y214885D02*
X103081Y214880D01*
G01X103070Y214889D02*
X103076Y214885D01*
G01X103065Y214891D02*
X103070Y214889D01*
G01X103058Y214893D02*
X103065Y214891D01*
G01X103051Y214893D02*
X103058D01*
G01X103081Y218030D02*
X103085Y218025D01*
G01X103076Y218034D02*
X103081Y218030D01*
G01X103070Y218038D02*
X103076Y218034D01*
G01X103065Y218041D02*
X103070Y218038D01*
G01X103058Y218043D02*
X103065Y218041D01*
G01X103051Y218043D02*
X103058D01*
G01X102107Y213719D02*
X102106Y213727D01*
G01X102109Y213713D02*
X102107Y213719D01*
G01X102113Y213706D02*
X102109Y213713D01*
G01X102118Y213700D02*
X102113Y213706D01*
G01X102124Y213696D02*
X102118Y213700D01*
G01X102131Y213693D02*
X102124Y213696D01*
G01X102138Y213691D02*
X102131Y213693D01*
G01X102146Y213690D02*
X102138Y213691D01*
G01X102107Y216869D02*
X102106Y216876D01*
G01X102109Y216862D02*
X102107Y216869D01*
G01X102113Y216856D02*
X102109Y216862D01*
G01X102118Y216850D02*
X102113Y216856D01*
G01X102124Y216845D02*
X102118Y216850D01*
G01X102131Y216842D02*
X102124Y216845D01*
G01X102138Y216840D02*
X102131Y216842D01*
G01X102146Y216839D02*
X102138Y216840D01*
G01X103060Y214881D02*
X103070Y214876D01*
G01X103050Y214882D02*
X103060Y214881D01*
G01Y218030D02*
X103070Y218026D01*
G01X103050Y218031D02*
X103060Y218030D01*
G01X103091Y217998D02*
Y218006D01*
G01X103090Y217994D02*
X103091Y217998D01*
G01X103089Y217992D02*
X103090Y217994D01*
G01X103091Y214849D02*
Y214856D01*
G01X103090Y214844D02*
X103091Y214849D01*
G01X103089Y214843D02*
X103090Y214844D01*
G01X102129Y214890D02*
X102126Y214888D01*
G01X102132Y214891D02*
X102129Y214890D01*
G01X102135Y214892D02*
X102132Y214891D01*
G01X102139Y214893D02*
X102135Y214892D01*
G01X102142Y214893D02*
X102139D01*
G01X102146D02*
X102142D01*
G01X103068Y216843D02*
X103071Y216844D01*
G01X103065Y216842D02*
X103068Y216843D01*
G01X103062Y216841D02*
X103065Y216842D01*
G01X103058Y216840D02*
X103062Y216841D01*
G01X103055Y216839D02*
X103058Y216840D01*
G01X103051Y216839D02*
X103055D01*
G01X102129Y218039D02*
X102126Y218038D01*
G01X102132Y218041D02*
X102129Y218039D01*
G01X102135Y218042D02*
X102132Y218041D01*
G01X102139Y218042D02*
X102135D01*
G01X102142Y218043D02*
X102139Y218042D01*
G01X102146Y218043D02*
X102142D01*
G01X103090Y213719D02*
X103091Y213727D01*
G01X103087Y213713D02*
X103090Y213719D01*
G01X103084Y213706D02*
X103087Y213713D01*
G01X103079Y213700D02*
X103084Y213706D01*
G01X103073Y213696D02*
X103079Y213700D01*
G01X103066Y213693D02*
X103073Y213696D01*
G01X103059Y213691D02*
X103066Y213693D01*
G01X103051Y213690D02*
X103059Y213691D01*
G01X103051Y218037D02*
Y218043D01*
G01X103050Y218033D02*
X103051Y218037D01*
G01X103050Y218031D02*
Y218033D01*
G01X103051Y214887D02*
Y214893D01*
G01X103050Y214883D02*
X103051Y214887D01*
G01X103050Y214882D02*
Y214883D01*
G01X116516Y259796D02*
Y259787D01*
G01X116517Y259802D02*
X116516Y259796D01*
G01X116519Y259803D02*
X116517Y259802D01*
G01X116516Y254796D02*
Y254787D01*
G01X116517Y254802D02*
X116516Y254796D01*
G01X116519Y254803D02*
X116517Y254802D01*
G01X116516Y249796D02*
Y249787D01*
G01X116517Y249802D02*
X116516Y249796D01*
G01X116519Y249803D02*
X116517Y249802D01*
G01X116516Y244796D02*
Y244787D01*
G01X116517Y244802D02*
X116516Y244796D01*
G01X116519Y244803D02*
X116517Y244802D01*
G01X116516Y239796D02*
Y239787D01*
G01X116517Y239802D02*
X116516Y239796D01*
G01X116519Y239803D02*
X116517Y239802D01*
G01X116516Y234796D02*
Y234787D01*
G01X116517Y234802D02*
X116516Y234796D01*
G01X116519Y234803D02*
X116517Y234802D01*
G01X116516Y229796D02*
Y229787D01*
G01X116517Y229802D02*
X116516Y229796D01*
G01X116519Y229803D02*
X116517Y229802D01*
G01X116516Y224796D02*
Y224787D01*
G01X116517Y224802D02*
X116516Y224796D01*
G01X116519Y224803D02*
X116517Y224802D01*
G01X116516Y219796D02*
Y219787D01*
G01X116517Y219802D02*
X116516Y219796D01*
G01X116519Y219803D02*
X116517Y219802D01*
G01X102109Y214862D02*
X102104Y214843D01*
G01X102124Y214877D02*
X102109Y214862D01*
G01X102143Y214882D02*
X102124Y214877D01*
G01X102109Y218012D02*
X102104Y217992D01*
G01X102124Y218026D02*
X102109Y218012D01*
G01X102143Y218031D02*
X102124Y218026D01*
G01X103084Y213720D02*
X103089Y213740D01*
G01X103069Y213706D02*
X103084Y213720D01*
G01X103050Y213701D02*
X103069Y213706D01*
G01X103084Y216870D02*
X103089Y216890D01*
G01X103069Y216856D02*
X103084Y216870D01*
G01X103050Y216850D02*
X103069Y216856D01*
G01X102106Y217998D02*
Y218006D01*
G01X102105Y217994D02*
X102106Y217998D01*
G01X102104Y217992D02*
X102105Y217994D01*
G01X102106Y214849D02*
Y214856D01*
G01X102105Y214844D02*
X102106Y214849D01*
G01X102104Y214843D02*
X102105Y214844D01*
G01X103088Y216864D02*
X103091Y216876D01*
G01X103081Y216853D02*
X103088Y216864D01*
G01X103071Y216844D02*
X103081Y216853D01*
G01X102145Y218037D02*
Y218043D01*
G01Y218033D02*
Y218037D01*
G01X102143Y218031D02*
X102145Y218033D01*
G01Y214887D02*
Y214893D01*
G01Y214883D02*
Y214887D01*
G01X102143Y214882D02*
X102145Y214883D01*
G01X102107Y218012D02*
X102106Y218006D01*
G01X102109Y218019D02*
X102107Y218012D01*
G01X102111Y218024D02*
X102109Y218019D01*
G01X102115Y218030D02*
X102111Y218024D01*
G01X102120Y218034D02*
X102115Y218030D01*
G01X102126Y218038D02*
X102120Y218034D01*
G01X102107Y214863D02*
X102106Y214856D01*
G01X102109Y214869D02*
X102107Y214863D01*
G01X102111Y214874D02*
X102109Y214869D01*
G01X102115Y214880D02*
X102111Y214874D01*
G01X102120Y214884D02*
X102115Y214880D01*
G01X102126Y214888D02*
X102120Y214884D01*
G01X103062Y216852D02*
X103050Y216850D01*
G01X103072Y216857D02*
X103062Y216852D01*
G01Y213703D02*
X103050Y213701D01*
G01X103072Y213708D02*
X103062Y213703D01*
G01X115945Y217854D02*
X117126Y219035D01*
G01X112008Y217854D02*
X113189Y219035D01*
G01X120866Y259803D02*
X115533D01*
G01X115531Y259311D02*
X116516D01*
G01Y256673D02*
X115531D01*
G01X116516Y259607D02*
X115531Y259606D01*
G01Y256377D02*
X116487Y256378D01*
G01X115533Y256181D02*
X120866D01*
G01Y256142D02*
X116518D01*
G01X120866Y254803D02*
X115533D01*
G01X115531Y254311D02*
X116516D01*
G01Y251673D02*
X115531D01*
G01X115533Y251181D02*
X120866D01*
G01Y251142D02*
X116518D01*
G01X120866Y249803D02*
X115533D01*
G01X115531Y249311D02*
X116516D01*
G01Y246673D02*
X115531D01*
G01X115533Y246181D02*
X120866D01*
G01Y246142D02*
X116518D01*
G01X120866Y244803D02*
X115533D01*
G01X115531Y244311D02*
X116516D01*
G01Y241673D02*
X115531D01*
G01X115533Y241181D02*
X120866D01*
G01Y241142D02*
X116518D01*
G01X120866Y239803D02*
X115533D01*
G01X115531Y239311D02*
X116516D01*
G01Y236673D02*
X115531D01*
G01X115533Y236181D02*
X120866D01*
G01Y236142D02*
X116518D01*
G01X120866Y234803D02*
X115533D01*
G01X115531Y234311D02*
X116516D01*
G01Y231673D02*
X115531D01*
G01X115533Y231181D02*
X120866D01*
G01Y231142D02*
X116518D01*
G01X120866Y229803D02*
X115533D01*
G01X115531Y229311D02*
X116516D01*
G01Y226673D02*
X115531D01*
G01X115533Y226181D02*
X120866D01*
G01Y226142D02*
X116518D01*
G01X120866Y224803D02*
X115533D01*
G01X115531Y224311D02*
X116516D01*
G01Y221673D02*
X115531D01*
G01X115533Y221181D02*
X120866D01*
G01Y221142D02*
X116518D01*
G01X103543Y220197D02*
X100197D01*
G01X120866Y219803D02*
X115533D01*
G01X115531Y219311D02*
X116516D01*
G01X113189Y219035D02*
X117126D01*
G01X103051Y218228D02*
X102146D01*
G01X103091Y218189D02*
X102106D01*
G01X103050Y218031D02*
X97165D01*
G01Y217992D02*
X103089D01*
G01X112008Y217854D02*
X115945D01*
G01X103089Y216890D02*
X97165D01*
G01X103050Y216850D02*
X97165D01*
G01X102106Y216693D02*
X103091D01*
G01X102146Y216654D02*
X103051D01*
G01Y215079D02*
X102146D01*
G01X103091Y215039D02*
X102106D01*
G01X103050Y214882D02*
X97165D01*
G01Y214843D02*
X103089D01*
G01Y213740D02*
X97165D01*
G01X103050Y213701D02*
X97165D01*
G01X102106Y213543D02*
X103091D01*
G01X102146Y213504D02*
X103051D01*
G01X116516Y254607D02*
X115531Y254606D01*
G01Y251377D02*
X116487Y251378D01*
G01X116516Y249607D02*
X115531Y249606D01*
G01Y246377D02*
X116487Y246378D01*
G01X116516Y244607D02*
X115531Y244606D01*
G01Y241377D02*
X116487Y241378D01*
G01X116516Y239607D02*
X115531Y239606D01*
G01Y236377D02*
X116487Y236378D01*
G01X116516Y234607D02*
X115531Y234606D01*
G01Y231377D02*
X116487Y231378D01*
G01X116516Y229607D02*
X115531Y229606D01*
G01Y226377D02*
X116487Y226378D01*
G01X116516Y224607D02*
X115531Y224606D01*
G01Y221377D02*
X116487Y221378D01*
G01X116516Y219607D02*
X115531Y219606D01*
G01X101993Y216890D02*
X102105Y216881D01*
G01X103090Y214845D02*
X103091Y214856D01*
G01X103090Y217994D02*
X103091Y218006D01*
G01X116516Y221155D02*
Y221164D01*
G01Y226155D02*
Y226164D01*
G01Y231155D02*
Y231164D01*
G01Y236155D02*
Y236164D01*
G01Y241155D02*
Y241164D01*
G01Y246155D02*
Y246164D01*
G01Y251155D02*
Y251164D01*
G01Y256155D02*
Y256164D01*
G01X117697Y221181D02*
Y219803D01*
G01Y226181D02*
Y224803D01*
G01Y231181D02*
Y229803D01*
G01Y236181D02*
Y234803D01*
G01Y241181D02*
Y239803D01*
G01Y246181D02*
Y244803D01*
G01Y251181D02*
Y249803D01*
G01Y256181D02*
Y254803D01*
G01Y261181D02*
Y259803D01*
G01X116516Y226156D02*
Y226299D01*
G01Y221156D02*
Y221299D01*
G01Y236156D02*
Y236299D01*
G01Y231156D02*
Y231299D01*
G01Y246156D02*
Y246299D01*
G01Y241156D02*
Y241299D01*
G01Y256156D02*
Y256299D01*
G01Y251156D02*
Y251299D01*
G01Y259311D02*
Y261673D01*
G01Y254311D02*
Y256673D01*
G01Y249311D02*
Y251673D01*
G01Y244311D02*
Y246673D01*
G01Y239311D02*
Y241673D01*
G01Y234311D02*
Y236673D01*
G01Y229311D02*
Y231673D01*
G01Y224311D02*
Y226673D01*
G01Y219311D02*
Y221673D01*
G01X115531D02*
Y219311D01*
G01Y226673D02*
Y224311D01*
G01Y231673D02*
Y229311D01*
G01Y236673D02*
Y234311D01*
G01Y241673D02*
Y239311D01*
G01Y246673D02*
Y244311D01*
G01Y251673D02*
Y249311D01*
G01Y256673D02*
Y254311D01*
G01Y261673D02*
Y259311D01*
G01X113189Y295492D02*
Y219035D01*
G01X112008Y294311D02*
Y217854D01*
G01X103543Y299232D02*
Y220197D01*
G01X103091Y216693D02*
Y218189D01*
G01Y213543D02*
Y215039D01*
G01X103051Y216839D02*
Y216693D01*
G01Y213690D02*
Y213543D01*
G01Y215040D02*
Y214893D01*
G01Y218189D02*
Y218043D01*
G01X102146D02*
Y218190D01*
G01Y216692D02*
Y216839D01*
G01Y213543D02*
Y213690D01*
G01Y214893D02*
Y215040D01*
G01X102106Y215039D02*
Y213543D01*
G01Y218189D02*
Y216693D01*
G01X100925Y218031D02*
Y216850D01*
G01Y214882D02*
Y213701D01*
G01X97165Y216850D02*
Y218031D01*
G01Y213701D02*
Y214882D01*
G01X103091Y216876D02*
X103090Y216887D01*
G01X103091Y213727D02*
X103090Y213738D01*
G01X103050Y213701D02*
X103053Y213690D01*
G01X116516Y261148D02*
Y261156D01*
G01X116517Y261144D02*
X116516Y261148D01*
G01X116518Y261142D02*
X116517Y261144D01*
G01X116516Y266148D02*
Y266156D01*
G01X116517Y266144D02*
X116516Y266148D01*
G01X116518Y266142D02*
X116517Y266144D01*
G01X116516Y271148D02*
Y271156D01*
G01X116517Y271144D02*
X116516Y271148D01*
G01X116518Y271142D02*
X116517Y271144D01*
G01X116516Y276148D02*
Y276156D01*
G01X116517Y276144D02*
X116516Y276148D01*
G01X116518Y276142D02*
X116517Y276144D01*
G01X116516Y281148D02*
Y281156D01*
G01X116517Y281144D02*
X116516Y281148D01*
G01X116518Y281142D02*
X116517Y281144D01*
G01X116516Y286148D02*
Y286156D01*
G01X116517Y286144D02*
X116516Y286148D01*
G01X116518Y286142D02*
X116517Y286144D01*
G01X115531Y261189D02*
Y261198D01*
G01X115532Y261183D02*
X115531Y261189D01*
G01X115533Y261181D02*
X115532Y261183D01*
G01X115531Y266189D02*
Y266198D01*
G01X115532Y266183D02*
X115531Y266189D01*
G01X115533Y266181D02*
X115532Y266183D01*
G01X115531Y271189D02*
Y271198D01*
G01X115532Y271183D02*
X115531Y271189D01*
G01X115533Y271181D02*
X115532Y271183D01*
G01X115531Y276189D02*
Y276198D01*
G01X115532Y276183D02*
X115531Y276189D01*
G01X115533Y276181D02*
X115532Y276183D01*
G01X115531Y281189D02*
Y281198D01*
G01X115532Y281183D02*
X115531Y281189D01*
G01X115533Y281181D02*
X115532Y281183D01*
G01X115531Y286189D02*
Y286198D01*
G01X115532Y286183D02*
X115531Y286189D01*
G01X115533Y286181D02*
X115532Y286183D01*
G01X115531Y291189D02*
Y291198D01*
G01X115532Y291183D02*
X115531Y291189D01*
G01X115533Y291181D02*
X115532Y291183D01*
G01X116508Y261325D02*
X116516Y261299D01*
G01X116498Y261352D02*
X116508Y261325D01*
G01X116487Y261378D02*
X116498Y261352D01*
G01X116508Y266325D02*
X116516Y266299D01*
G01X116498Y266352D02*
X116508Y266325D01*
G01X116487Y266378D02*
X116498Y266352D01*
G01X116508Y271325D02*
X116516Y271299D01*
G01X116498Y271352D02*
X116508Y271325D01*
G01X116487Y271378D02*
X116498Y271352D01*
G01X116508Y276325D02*
X116516Y276299D01*
G01X116498Y276352D02*
X116508Y276325D01*
G01X116487Y276378D02*
X116498Y276352D01*
G01X116508Y281325D02*
X116516Y281299D01*
G01X116498Y281352D02*
X116508Y281325D01*
G01X116487Y281378D02*
X116498Y281352D01*
G01X116508Y286325D02*
X116516Y286299D01*
G01X116498Y286352D02*
X116508Y286325D01*
G01X116487Y286378D02*
X116498Y286352D01*
G01X116508Y291325D02*
X116516Y291299D01*
G01X116498Y291352D02*
X116508Y291325D01*
G01X116487Y291378D02*
X116498Y291352D01*
G01X116516Y291148D02*
Y291156D01*
G01X116517Y291144D02*
X116516Y291148D01*
G01X116518Y291142D02*
X116517Y291144D01*
G01X116498Y261176D02*
X116479Y261181D01*
G01X116513Y261162D02*
X116498Y261176D01*
G01X116518Y261142D02*
X116513Y261162D01*
G01X116498Y266176D02*
X116479Y266181D01*
G01X116513Y266162D02*
X116498Y266176D01*
G01X116518Y266142D02*
X116513Y266162D01*
G01X116498Y271176D02*
X116479Y271181D01*
G01X116513Y271162D02*
X116498Y271176D01*
G01X116518Y271142D02*
X116513Y271162D01*
G01X116498Y276176D02*
X116479Y276181D01*
G01X116513Y276162D02*
X116498Y276176D01*
G01X116518Y276142D02*
X116513Y276162D01*
G01X116498Y281176D02*
X116479Y281181D01*
G01X116513Y281162D02*
X116498Y281176D01*
G01X116518Y281142D02*
X116513Y281162D01*
G01X116498Y286176D02*
X116479Y286181D01*
G01X116513Y286162D02*
X116498Y286176D01*
G01X116518Y286142D02*
X116513Y286162D01*
G01X116498Y291176D02*
X116479Y291181D01*
G01X116513Y291162D02*
X116498Y291176D01*
G01X116518Y291142D02*
X116513Y291162D01*
G01X116483Y261279D02*
X116487Y261378D01*
G01X116477Y261207D02*
X116483Y261279D01*
G01X116479Y261181D02*
X116477Y261207D01*
G01X116483Y266279D02*
X116487Y266378D01*
G01X116477Y266207D02*
X116483Y266279D01*
G01X116479Y266181D02*
X116477Y266207D01*
G01X116483Y271279D02*
X116487Y271378D01*
G01X116477Y271207D02*
X116483Y271279D01*
G01X116479Y271181D02*
X116477Y271207D01*
G01X116483Y276279D02*
X116487Y276378D01*
G01X116477Y276207D02*
X116483Y276279D01*
G01X116479Y276181D02*
X116477Y276207D01*
G01X116483Y281279D02*
X116487Y281378D01*
G01X116477Y281207D02*
X116483Y281279D01*
G01X116479Y281181D02*
X116477Y281207D01*
G01X116483Y286279D02*
X116487Y286378D01*
G01X116477Y286207D02*
X116483Y286279D01*
G01X116479Y286181D02*
X116477Y286207D01*
G01X116483Y291279D02*
X116487Y291378D01*
G01X116477Y291207D02*
X116483Y291279D01*
G01X116479Y291181D02*
X116477Y291207D01*
G01X115532Y289802D02*
X115533Y289803D01*
G01X115531Y289796D02*
X115532Y289802D01*
G01X115531Y289787D02*
Y289796D01*
G01X115532Y284802D02*
X115533Y284803D01*
G01X115531Y284796D02*
X115532Y284802D01*
G01X115531Y284787D02*
Y284796D01*
G01X115532Y279802D02*
X115533Y279803D01*
G01X115531Y279796D02*
X115532Y279802D01*
G01X115531Y279787D02*
Y279796D01*
G01X115532Y274802D02*
X115533Y274803D01*
G01X115531Y274796D02*
X115532Y274802D01*
G01X115531Y274787D02*
Y274796D01*
G01X115532Y269802D02*
X115533Y269803D01*
G01X115531Y269796D02*
X115532Y269802D01*
G01X115531Y269787D02*
Y269796D01*
G01X115532Y264802D02*
X115533Y264803D01*
G01X115531Y264796D02*
X115532Y264802D01*
G01X115531Y264787D02*
Y264796D01*
G01X116503Y261173D02*
X116514Y261157D01*
G01X116479Y261181D02*
X116503Y261173D01*
G01Y266173D02*
X116514Y266157D01*
G01X116479Y266181D02*
X116503Y266173D01*
G01Y271173D02*
X116514Y271157D01*
G01X116479Y271181D02*
X116503Y271173D01*
G01Y276173D02*
X116514Y276157D01*
G01X116479Y276181D02*
X116503Y276173D01*
G01Y281173D02*
X116514Y281157D01*
G01X116479Y281181D02*
X116503Y281173D01*
G01Y286173D02*
X116514Y286157D01*
G01X116479Y286181D02*
X116503Y286173D01*
G01Y291173D02*
X116514Y291157D01*
G01X116479Y291181D02*
X116503Y291173D01*
G01X116516Y289796D02*
Y289787D01*
G01X116517Y289802D02*
X116516Y289796D01*
G01X116519Y289803D02*
X116517Y289802D01*
G01X116516Y284796D02*
Y284787D01*
G01X116517Y284802D02*
X116516Y284796D01*
G01X116519Y284803D02*
X116517Y284802D01*
G01X116516Y279796D02*
Y279787D01*
G01X116517Y279802D02*
X116516Y279796D01*
G01X116519Y279803D02*
X116517Y279802D01*
G01X116516Y274796D02*
Y274787D01*
G01X116517Y274802D02*
X116516Y274796D01*
G01X116519Y274803D02*
X116517Y274802D01*
G01X116516Y269796D02*
Y269787D01*
G01X116517Y269802D02*
X116516Y269796D01*
G01X116519Y269803D02*
X116517Y269802D01*
G01X116516Y264796D02*
Y264787D01*
G01X116517Y264802D02*
X116516Y264796D01*
G01X116519Y264803D02*
X116517Y264802D01*
G01X108465Y307579D02*
G03X107283Y306398I-1J-1181D01*
G01X114764D02*
G03X113583Y307579I-1181J0D01*
G01X112913Y302303D02*
G03I-1889J0D01*
G01X113386D02*
G03I-2362J0D01*
G01X121850Y300335D02*
X118504Y296988D01*
G01X112008Y294311D02*
X113189Y295492D01*
G01X121850Y307618D02*
X100197D01*
G01X108465Y307579D02*
X113583D01*
G01X109843Y302894D02*
X112205D01*
G01X109843Y301201D02*
X112205D01*
G01X103543Y299232D02*
X117913D01*
G01X103543Y297854D02*
X107283D01*
G01X117913D02*
X114764D01*
G01X103543Y296988D02*
X118504D01*
G01X105315Y295492D02*
X113189D01*
G01X106496Y294311D02*
X112008D01*
G01X116516Y291673D02*
X115531D01*
G01X115533Y291181D02*
X120866D01*
G01Y291142D02*
X116518D01*
G01X120866Y289803D02*
X115533D01*
G01X115531Y289311D02*
X116516D01*
G01Y286673D02*
X115531D01*
G01X115533Y286181D02*
X120866D01*
G01Y286142D02*
X116518D01*
G01X120866Y284803D02*
X115533D01*
G01X115531Y284311D02*
X116516D01*
G01Y281673D02*
X115531D01*
G01X115533Y281181D02*
X120866D01*
G01Y281142D02*
X116518D01*
G01X120866Y279803D02*
X115533D01*
G01X115531Y279311D02*
X116516D01*
G01Y276673D02*
X115531D01*
G01X115533Y276181D02*
X120866D01*
G01Y276142D02*
X116518D01*
G01X120866Y274803D02*
X115533D01*
G01X115531Y274311D02*
X116516D01*
G01Y271673D02*
X115531D01*
G01X115533Y271181D02*
X120866D01*
G01Y271142D02*
X116518D01*
G01X120866Y269803D02*
X115533D01*
G01X115531Y269311D02*
X116516D01*
G01Y266673D02*
X115531D01*
G01X115533Y266181D02*
X120866D01*
G01Y266142D02*
X116518D01*
G01X120866Y264803D02*
X115533D01*
G01X115531Y264311D02*
X116516D01*
G01Y261673D02*
X115531D01*
G01X115533Y261181D02*
X120866D01*
G01Y261142D02*
X116518D01*
G01X115531Y291377D02*
X116487Y291378D01*
G01X116516Y289607D02*
X115531Y289606D01*
G01Y286377D02*
X116487Y286378D01*
G01X116516Y284607D02*
X115531Y284606D01*
G01Y281377D02*
X116487Y281378D01*
G01X116516Y279607D02*
X115531Y279606D01*
G01Y276377D02*
X116487Y276378D01*
G01X116516Y274607D02*
X115531Y274606D01*
G01Y271377D02*
X116487Y271378D01*
G01X116516Y269607D02*
X115531Y269606D01*
G01Y266377D02*
X116487Y266378D01*
G01X116516Y264607D02*
X115531Y264606D01*
G01Y261377D02*
X116487Y261378D01*
G01X108539Y299232D02*
X109843Y301201D01*
G01X114515Y307123D02*
X112205Y302894D01*
G01X116516Y261155D02*
Y261164D01*
G01Y266155D02*
Y266164D01*
G01Y271155D02*
Y271164D01*
G01Y276155D02*
Y276164D01*
G01Y281155D02*
Y281164D01*
G01Y286155D02*
Y286164D01*
G01Y291155D02*
Y291164D01*
G01X117697Y266181D02*
Y264803D01*
G01Y271181D02*
Y269803D01*
G01Y276181D02*
Y274803D01*
G01Y281181D02*
Y279803D01*
G01Y286181D02*
Y284803D01*
G01Y291181D02*
Y289803D01*
G01X116516Y266156D02*
Y266299D01*
G01Y261156D02*
Y261299D01*
G01Y276156D02*
Y276299D01*
G01Y271156D02*
Y271299D01*
G01Y286156D02*
Y286299D01*
G01Y281156D02*
Y281299D01*
G01Y291156D02*
Y291299D01*
G01Y289311D02*
Y291673D01*
G01Y284311D02*
Y286673D01*
G01Y279311D02*
Y281673D01*
G01Y274311D02*
Y276673D01*
G01Y269311D02*
Y271673D01*
G01Y264311D02*
Y266673D01*
G01X115531D02*
Y264311D01*
G01Y271673D02*
Y269311D01*
G01Y276673D02*
Y274311D01*
G01Y281673D02*
Y279311D01*
G01Y286673D02*
Y284311D01*
G01Y291673D02*
Y289311D01*
G01X114764Y306398D02*
Y297854D01*
G01X112205Y302894D02*
Y301201D01*
G01X109843D02*
Y302894D01*
G01X107283Y297854D02*
Y306398D01*
G01X100197Y316083D02*
Y300335D01*
G01X105315Y295492D02*
X106496Y294311D01*
G01X100197Y300335D02*
X103543Y296988D01*
G01X109843Y302894D02*
X107532Y307123D01*
G01X112205Y301201D02*
X113508Y299232D01*
G01X114295Y378885D02*
G03X148106I16905J-13531D01*
G01X114295D02*
G03X148106I16905J-13531D01*
G01X114961Y316673D02*
G03X114370Y317264I-591J0D01*
G01X107677D02*
G03X107087Y316673I0J-590D01*
G01X109843Y315492D02*
G03Y313524I0J-984D01*
G01X112205D02*
G03Y315492I0J984D01*
G01X121850Y316083D02*
G03X119882Y318051I-1968J0D01*
G01X102165D02*
G03X100197Y316083I0J-1968D01*
G01X119882Y318051D02*
X102165D01*
G01X114370Y317264D02*
X107677D01*
G01X112205Y315492D02*
X109843D01*
G01Y313524D02*
X112205D01*
G01X114961Y312146D02*
X107087D01*
G01Y310571D02*
X114961D01*
G01D02*
Y316673D01*
G01X107087Y310571D02*
Y316673D01*
G01X114295Y378885D02*
G03X121220Y392016I-30737J24602D01*
G01X114295Y378885D02*
G03X121220Y392016I-30737J24602D01*
G01X73031Y368504D02*
Y374803D01*
G01Y368504D02*
Y374803D01*
G01X107087Y592067D02*
G03X107677Y591476I591J0D01*
G01X114370D02*
G03X114961Y592067I0J591D01*
G01X112205Y593248D02*
G03Y595217I0J985D01*
G01X109843D02*
G03Y593248I0J-985D01*
G01X100197Y592657D02*
G03X102165Y590689I1968J0D01*
G01X119882D02*
G03X121850Y592657I0J1968D01*
G01X114961Y598169D02*
X107087D01*
G01Y596594D02*
X114961D01*
G01X112205Y595217D02*
X109843D01*
G01Y593248D02*
X112205D01*
G01X114370Y591476D02*
X107677D01*
G01X119882Y590689D02*
X102165D01*
G01X114961Y598169D02*
Y592067D01*
G01X107087Y598169D02*
Y592067D01*
G01X100197Y608406D02*
Y592657D01*
G01X116483Y619035D02*
X116487Y619134D01*
G01X116477Y618963D02*
X116483Y619035D01*
G01X116479Y618937D02*
X116477Y618963D01*
G01X116483Y624035D02*
X116487Y624134D01*
G01X116477Y623963D02*
X116483Y624035D01*
G01X116479Y623937D02*
X116477Y623963D01*
G01X116483Y629035D02*
X116487Y629134D01*
G01X116477Y628963D02*
X116483Y629035D01*
G01X116479Y628937D02*
X116477Y628963D01*
G01X116483Y634035D02*
X116487Y634134D01*
G01X116477Y633963D02*
X116483Y634035D01*
G01X116479Y633937D02*
X116477Y633963D01*
G01X116483Y639035D02*
X116487Y639134D01*
G01X116477Y638963D02*
X116483Y639035D01*
G01X116479Y638937D02*
X116477Y638963D01*
G01X116483Y644035D02*
X116487Y644134D01*
G01X116477Y643963D02*
X116483Y644035D01*
G01X116479Y643937D02*
X116477Y643963D01*
G01X115532Y647557D02*
X115533Y647559D01*
G01X115531Y647552D02*
X115532Y647557D01*
G01X115531Y647543D02*
Y647552D01*
G01X115532Y642557D02*
X115533Y642559D01*
G01X115531Y642552D02*
X115532Y642557D01*
G01X115531Y642543D02*
Y642552D01*
G01X115532Y637557D02*
X115533Y637559D01*
G01X115531Y637552D02*
X115532Y637557D01*
G01X115531Y637543D02*
Y637552D01*
G01X115532Y632557D02*
X115533Y632559D01*
G01X115531Y632552D02*
X115532Y632557D01*
G01X115531Y632543D02*
Y632552D01*
G01X115532Y627557D02*
X115533Y627559D01*
G01X115531Y627552D02*
X115532Y627557D01*
G01X115531Y627543D02*
Y627552D01*
G01X115532Y622557D02*
X115533Y622559D01*
G01X115531Y622552D02*
X115532Y622557D01*
G01X115531Y622543D02*
Y622552D01*
G01X115532Y617557D02*
X115533Y617559D01*
G01X115531Y617552D02*
X115532Y617557D01*
G01X115531Y617543D02*
Y617552D01*
G01Y618944D02*
Y618954D01*
G01X115532Y618939D02*
X115531Y618944D01*
G01X115533Y618937D02*
X115532Y618939D01*
G01X115531Y623944D02*
Y623954D01*
G01X115532Y623939D02*
X115531Y623944D01*
G01X115533Y623937D02*
X115532Y623939D01*
G01X115531Y628944D02*
Y628954D01*
G01X115532Y628939D02*
X115531Y628944D01*
G01X115533Y628937D02*
X115532Y628939D01*
G01X115531Y633944D02*
Y633954D01*
G01X115532Y633939D02*
X115531Y633944D01*
G01X115533Y633937D02*
X115532Y633939D01*
G01X115531Y638944D02*
Y638954D01*
G01X115532Y638939D02*
X115531Y638944D01*
G01X115533Y638937D02*
X115532Y638939D01*
G01X115531Y643944D02*
Y643954D01*
G01X115532Y643939D02*
X115531Y643944D01*
G01X115533Y643937D02*
X115532Y643939D01*
G01X116508Y619081D02*
X116516Y619055D01*
G01X116498Y619107D02*
X116508Y619081D01*
G01X116487Y619134D02*
X116498Y619107D01*
G01X116508Y624081D02*
X116516Y624055D01*
G01X116498Y624107D02*
X116508Y624081D01*
G01X116487Y624134D02*
X116498Y624107D01*
G01X116508Y629081D02*
X116516Y629055D01*
G01X116498Y629107D02*
X116508Y629081D01*
G01X116487Y629134D02*
X116498Y629107D01*
G01X116508Y634081D02*
X116516Y634055D01*
G01X116498Y634107D02*
X116508Y634081D01*
G01X116487Y634134D02*
X116498Y634107D01*
G01X116508Y639081D02*
X116516Y639055D01*
G01X116498Y639107D02*
X116508Y639081D01*
G01X116487Y639134D02*
X116498Y639107D01*
G01X116508Y644081D02*
X116516Y644055D01*
G01X116498Y644107D02*
X116508Y644081D01*
G01X116487Y644134D02*
X116498Y644107D01*
G01Y618932D02*
X116479Y618937D01*
G01X116513Y618918D02*
X116498Y618932D01*
G01X116518Y618898D02*
X116513Y618918D01*
G01X116498Y623932D02*
X116479Y623937D01*
G01X116513Y623918D02*
X116498Y623932D01*
G01X116518Y623898D02*
X116513Y623918D01*
G01X116498Y628932D02*
X116479Y628937D01*
G01X116513Y628918D02*
X116498Y628932D01*
G01X116518Y628898D02*
X116513Y628918D01*
G01X116498Y633932D02*
X116479Y633937D01*
G01X116513Y633918D02*
X116498Y633932D01*
G01X116518Y633898D02*
X116513Y633918D01*
G01X116498Y638932D02*
X116479Y638937D01*
G01X116513Y638918D02*
X116498Y638932D01*
G01X116518Y638898D02*
X116513Y638918D01*
G01X116498Y643932D02*
X116479Y643937D01*
G01X116513Y643918D02*
X116498Y643932D01*
G01X116518Y643898D02*
X116513Y643918D01*
G01X116516Y618904D02*
Y618911D01*
G01X116517Y618900D02*
X116516Y618904D01*
G01X116518Y618898D02*
X116517Y618900D01*
G01X116516Y623904D02*
Y623911D01*
G01X116517Y623900D02*
X116516Y623904D01*
G01X116518Y623898D02*
X116517Y623900D01*
G01X116516Y628904D02*
Y628911D01*
G01X116517Y628900D02*
X116516Y628904D01*
G01X116518Y628898D02*
X116517Y628900D01*
G01X116516Y633904D02*
Y633911D01*
G01X116517Y633900D02*
X116516Y633904D01*
G01X116518Y633898D02*
X116517Y633900D01*
G01X116516Y638904D02*
Y638911D01*
G01X116517Y638900D02*
X116516Y638904D01*
G01X116518Y638898D02*
X116517Y638900D01*
G01X116516Y643904D02*
Y643911D01*
G01X116517Y643900D02*
X116516Y643904D01*
G01X116518Y643898D02*
X116517Y643900D01*
G01X116516Y647552D02*
Y647543D01*
G01X116517Y647557D02*
X116516Y647552D01*
G01X116519Y647559D02*
X116517Y647557D01*
G01X116516Y642552D02*
Y642543D01*
G01X116517Y642557D02*
X116516Y642552D01*
G01X116519Y642559D02*
X116517Y642557D01*
G01X116516Y637552D02*
Y637543D01*
G01X116517Y637557D02*
X116516Y637552D01*
G01X116519Y637559D02*
X116517Y637557D01*
G01X116516Y632552D02*
Y632543D01*
G01X116517Y632557D02*
X116516Y632552D01*
G01X116519Y632559D02*
X116517Y632557D01*
G01X116516Y627552D02*
Y627543D01*
G01X116517Y627557D02*
X116516Y627552D01*
G01X116519Y627559D02*
X116517Y627557D01*
G01X116516Y622552D02*
Y622543D01*
G01X116517Y622557D02*
X116516Y622552D01*
G01X116519Y622559D02*
X116517Y622557D01*
G01X116516Y617552D02*
Y617543D01*
G01X116517Y617557D02*
X116516Y617552D01*
G01X116519Y617559D02*
X116517Y617557D01*
G01X116503Y618929D02*
X116514Y618913D01*
G01X116479Y618937D02*
X116503Y618929D01*
G01Y623929D02*
X116514Y623913D01*
G01X116479Y623937D02*
X116503Y623929D01*
G01Y628929D02*
X116514Y628913D01*
G01X116479Y628937D02*
X116503Y628929D01*
G01Y633929D02*
X116514Y633913D01*
G01X116479Y633937D02*
X116503Y633929D01*
G01Y638929D02*
X116514Y638913D01*
G01X116479Y638937D02*
X116503Y638929D01*
G01Y643929D02*
X116514Y643913D01*
G01X116479Y643937D02*
X116503Y643929D01*
G01X112126Y606437D02*
G03I-1102J0D01*
G01X113583Y601161D02*
G03X114764Y602343I0J1181D01*
G01X107283D02*
G03X108465Y601161I1181J-1D01*
G01X112598Y606437D02*
G03I-1574J0D01*
G01X120866Y647559D02*
X115533D01*
G01X115531Y647067D02*
X116516D01*
G01Y644429D02*
X115531D01*
G01X115533Y643937D02*
X120866D01*
G01Y643898D02*
X116518D01*
G01X120866Y642559D02*
X115533D01*
G01X115531Y642067D02*
X116516D01*
G01Y639429D02*
X115531D01*
G01X115533Y638937D02*
X120866D01*
G01Y638898D02*
X116518D01*
G01X120866Y637559D02*
X115533D01*
G01X115531Y637067D02*
X116516D01*
G01Y634429D02*
X115531D01*
G01X115533Y633937D02*
X120866D01*
G01Y633898D02*
X116518D01*
G01X120866Y632559D02*
X115533D01*
G01X115531Y632067D02*
X116516D01*
G01Y629429D02*
X115531D01*
G01X115533Y628937D02*
X120866D01*
G01Y628898D02*
X116518D01*
G01X120866Y627559D02*
X115533D01*
G01X115531Y627067D02*
X116516D01*
G01Y624429D02*
X115531D01*
G01X115533Y623937D02*
X120866D01*
G01Y623898D02*
X116518D01*
G01X120866Y622559D02*
X115533D01*
G01X115531Y622067D02*
X116516D01*
G01Y619429D02*
X115531D01*
G01X115533Y618937D02*
X120866D01*
G01Y618898D02*
X116518D01*
G01X120866Y617559D02*
X115533D01*
G01X115531Y617067D02*
X116516D01*
G01Y647363D02*
X115531Y647362D01*
G01Y644133D02*
X116487Y644134D01*
G01X116516Y642363D02*
X115531Y642362D01*
G01Y639133D02*
X116487Y639134D01*
G01X116516Y637363D02*
X115531Y637362D01*
G01Y634133D02*
X116487Y634134D01*
G01X116516Y632363D02*
X115531Y632362D01*
G01Y629133D02*
X116487Y629134D01*
G01X116516Y627363D02*
X115531Y627362D01*
G01Y624133D02*
X116487Y624134D01*
G01X116516Y622363D02*
X115531Y622362D01*
G01Y619133D02*
X116487Y619134D01*
G01X116516Y617363D02*
X115531Y617362D01*
G01X112008Y614429D02*
X106496D01*
G01X113189Y613248D02*
X105315D01*
G01X118504Y611752D02*
X103543D01*
G01X114764Y610886D02*
X117913D01*
G01X107283D02*
X103543D01*
G01Y609508D02*
X117913D01*
G01X112205Y607539D02*
X109843D01*
G01X112205Y605846D02*
X109843D01*
G01X113583Y601161D02*
X108465D01*
G01X121850Y601122D02*
X100197D01*
G01X106496Y614429D02*
X105315Y613248D01*
G01X103543Y611752D02*
X100197Y608406D01*
G01X113508Y609508D02*
X112205Y607539D01*
G01X107532Y601617D02*
X109843Y605846D01*
G01X118504Y611752D02*
X121850Y608406D01*
G01X112008Y614429D02*
X113189Y613248D01*
G01X112205Y605846D02*
X114515Y601617D01*
G01X109843Y607539D02*
X108539Y609508D01*
G01X116516Y618911D02*
Y618920D01*
G01Y623911D02*
Y623920D01*
G01Y628911D02*
Y628920D01*
G01Y633911D02*
Y633920D01*
G01Y638911D02*
Y638920D01*
G01Y643911D02*
Y643920D01*
G01X118504Y749744D02*
Y611752D01*
G01X117913Y751988D02*
Y609508D01*
G01X117697Y618937D02*
Y617559D01*
G01Y623937D02*
Y622559D01*
G01Y628937D02*
Y627559D01*
G01Y633937D02*
Y632559D01*
G01Y638937D02*
Y637559D01*
G01Y643937D02*
Y642559D01*
G01Y648937D02*
Y647559D01*
G01X116516Y647067D02*
Y649429D01*
G01Y642067D02*
Y644429D01*
G01Y637067D02*
Y639429D01*
G01Y632067D02*
Y634429D01*
G01Y627067D02*
Y629429D01*
G01Y622067D02*
Y624429D01*
G01Y617067D02*
Y619429D01*
G01X115531D02*
Y617067D01*
G01Y624429D02*
Y622067D01*
G01Y629429D02*
Y627067D01*
G01Y634429D02*
Y632067D01*
G01Y639429D02*
Y637067D01*
G01Y644429D02*
Y642067D01*
G01Y649429D02*
Y647067D01*
G01X114764Y610886D02*
Y602343D01*
G01X113189Y649705D02*
Y613248D01*
G01X112205Y607539D02*
Y605846D01*
G01X112008Y650886D02*
Y614429D01*
G01X109843Y605846D02*
Y607539D01*
G01X107283Y602343D02*
Y610886D01*
G01X106496Y614429D02*
Y747067D01*
G01X105315Y613248D02*
Y748248D01*
G01X103543Y648543D02*
Y609508D01*
G01X116483Y649035D02*
X116487Y649134D01*
G01X116477Y648963D02*
X116483Y649035D01*
G01X116479Y648937D02*
X116477Y648963D01*
G01X116483Y674035D02*
X116487Y674134D01*
G01X116477Y673963D02*
X116483Y674035D01*
G01X116479Y673937D02*
X116477Y673963D01*
G01X116483Y679035D02*
X116487Y679134D01*
G01X116477Y678963D02*
X116483Y679035D01*
G01X116479Y678937D02*
X116477Y678963D01*
G01X116483Y684035D02*
X116487Y684134D01*
G01X116477Y683963D02*
X116483Y684035D01*
G01X116479Y683937D02*
X116477Y683963D01*
G01X116483Y689035D02*
X116487Y689134D01*
G01X116477Y688963D02*
X116483Y689035D01*
G01X116479Y688937D02*
X116477Y688963D01*
G01X116483Y694035D02*
X116487Y694134D01*
G01X116477Y693963D02*
X116483Y694035D01*
G01X116479Y693937D02*
X116477Y693963D01*
G01X102106Y663341D02*
Y663333D01*
G01X102105Y663345D02*
X102106Y663341D01*
G01Y663336D02*
X102105Y663345D01*
G01X102146Y670972D02*
Y670984D01*
G01X102143Y670959D02*
X102146Y670972D01*
G01X102143Y670945D02*
Y670959D01*
G01X102146Y667822D02*
Y667835D01*
G01X102143Y667809D02*
X102146Y667822D01*
G01X102143Y667796D02*
Y667809D01*
G01X102146Y664673D02*
Y664685D01*
G01X102143Y664660D02*
X102146Y664673D01*
G01X102143Y664646D02*
Y664660D01*
G01X102146Y661523D02*
Y661535D01*
G01X102143Y661510D02*
X102146Y661523D01*
G01X102143Y661496D02*
Y661510D01*
G01X102146Y658374D02*
Y658386D01*
G01X102143Y658361D02*
X102146Y658374D01*
G01X102143Y658347D02*
Y658361D01*
G01X102146Y655224D02*
Y655236D01*
G01X102143Y655211D02*
X102146Y655224D01*
G01X102143Y655197D02*
Y655211D01*
G01X102146Y652074D02*
Y652087D01*
G01X102143Y652061D02*
X102146Y652074D01*
G01X102143Y652048D02*
Y652061D01*
G01X115532Y692557D02*
X115533Y692559D01*
G01X115531Y692552D02*
X115532Y692557D01*
G01X115531Y692543D02*
Y692552D01*
G01X115532Y687557D02*
X115533Y687559D01*
G01X115531Y687552D02*
X115532Y687557D01*
G01X115531Y687543D02*
Y687552D01*
G01X115532Y682557D02*
X115533Y682559D01*
G01X115531Y682552D02*
X115532Y682557D01*
G01X115531Y682543D02*
Y682552D01*
G01X115532Y677557D02*
X115533Y677559D01*
G01X115531Y677552D02*
X115532Y677557D01*
G01X115531Y677543D02*
Y677552D01*
G01X115532Y672557D02*
X115533Y672559D01*
G01X115531Y672552D02*
X115532Y672557D01*
G01X115531Y672543D02*
Y672552D01*
G01X102106Y669640D02*
Y669632D01*
G01X102105Y669644D02*
X102106Y669640D01*
G01X102105Y669637D02*
Y669644D01*
G01X102143Y669435D02*
X102142Y669448D01*
G01X102146Y669422D02*
X102143Y669435D01*
G01X102146Y669409D02*
Y669422D01*
G01X102143Y666285D02*
X102142Y666299D01*
G01X102146Y666272D02*
X102143Y666285D01*
G01X102146Y666260D02*
Y666272D01*
G01X102143Y663136D02*
X102142Y663149D01*
G01X102146Y663123D02*
X102143Y663136D01*
G01X102146Y663110D02*
Y663123D01*
G01X102143Y659986D02*
X102142Y660000D01*
G01X102146Y659973D02*
X102143Y659986D01*
G01X102146Y659961D02*
Y659973D01*
G01X102143Y656837D02*
X102142Y656850D01*
G01X102146Y656824D02*
X102143Y656837D01*
G01X102146Y656811D02*
Y656824D01*
G01X102143Y653687D02*
X102142Y653700D01*
G01X102146Y653674D02*
X102143Y653687D01*
G01X102146Y653661D02*
Y653674D01*
G01X102143Y650537D02*
X102142Y650551D01*
G01X102146Y650524D02*
X102143Y650537D01*
G01X102146Y650512D02*
Y650524D01*
G01X103054Y670959D02*
X103055Y670945D01*
G01X103050Y670972D02*
X103054Y670959D01*
G01X103051Y670984D02*
X103050Y670972D01*
G01X103054Y667809D02*
X103055Y667796D01*
G01X103050Y667822D02*
X103054Y667809D01*
G01X103051Y667835D02*
X103050Y667822D01*
G01X103054Y664659D02*
X103055Y664646D01*
G01X103050Y664672D02*
X103054Y664659D01*
G01X103051Y664685D02*
X103050Y664672D01*
G01X103054Y661510D02*
X103055Y661496D01*
G01X103050Y661523D02*
X103054Y661510D01*
G01X103051Y661535D02*
X103050Y661523D01*
G01X103054Y658360D02*
X103055Y658347D01*
G01X103050Y658373D02*
X103054Y658360D01*
G01X103051Y658386D02*
X103050Y658373D01*
G01X103054Y655211D02*
X103055Y655197D01*
G01X103050Y655224D02*
X103054Y655211D01*
G01X103051Y655236D02*
X103050Y655224D01*
G01X103054Y652061D02*
X103055Y652048D01*
G01X103050Y652074D02*
X103054Y652061D01*
G01X103051Y652087D02*
X103050Y652074D01*
G01X102106Y657041D02*
Y657034D01*
G01X102105Y657046D02*
X102106Y657041D01*
G01X102105Y657039D02*
Y657046D01*
G01X102106Y666490D02*
Y666483D01*
G01X102105Y666495D02*
X102106Y666490D01*
G01X102105Y666488D02*
Y666495D01*
G01X103050Y669422D02*
X103051Y669409D01*
G01X103053Y669435D02*
X103050Y669422D01*
G01X103054Y669448D02*
X103053Y669435D01*
G01X103050Y666272D02*
X103051Y666260D01*
G01X103053Y666285D02*
X103050Y666272D01*
G01X103054Y666299D02*
X103053Y666285D01*
G01X103050Y663123D02*
X103051Y663110D01*
G01X103053Y663136D02*
X103050Y663123D01*
G01X103054Y663149D02*
X103053Y663136D01*
G01X103050Y659973D02*
X103051Y659961D01*
G01X103053Y659986D02*
X103050Y659973D01*
G01X103054Y660000D02*
X103053Y659986D01*
G01X103050Y656824D02*
X103051Y656811D01*
G01X103053Y656837D02*
X103050Y656824D01*
G01X103054Y656850D02*
X103053Y656837D01*
G01X103050Y653674D02*
X103051Y653661D01*
G01X103053Y653687D02*
X103050Y653674D01*
G01X103054Y653700D02*
X103053Y653687D01*
G01X103050Y650524D02*
X103051Y650512D01*
G01X103053Y650537D02*
X103050Y650524D01*
G01X103054Y650551D02*
X103053Y650537D01*
G01X102106Y650743D02*
Y650735D01*
G01X102105Y650747D02*
X102106Y650743D01*
G01X102105Y650741D02*
Y650747D01*
G01X102119Y670779D02*
X102143Y670787D01*
G01X102108Y670765D02*
X102119Y670779D01*
G01X102106Y670758D02*
X102108Y670765D01*
G01X102119Y667630D02*
X102143Y667638D01*
G01X102108Y667615D02*
X102119Y667630D01*
G01X102106Y667608D02*
X102108Y667615D01*
G01X102119Y664480D02*
X102143Y664488D01*
G01X102108Y664465D02*
X102119Y664480D01*
G01X102106Y664459D02*
X102108Y664465D01*
G01X102119Y661330D02*
X102143Y661339D01*
G01X102108Y661316D02*
X102119Y661330D01*
G01X102106Y661309D02*
X102108Y661316D01*
G01X102119Y658181D02*
X102143Y658189D01*
G01X102108Y658166D02*
X102119Y658181D01*
G01X102106Y658159D02*
X102108Y658166D01*
G01X102119Y655031D02*
X102143Y655039D01*
G01X102108Y655017D02*
X102119Y655031D01*
G01X102106Y655010D02*
X102108Y655017D01*
G01X102119Y651881D02*
X102143Y651890D01*
G01X102108Y651867D02*
X102119Y651881D01*
G01X102106Y651860D02*
X102108Y651867D01*
G01X102129Y653861D02*
X102143Y653858D01*
G01X102118Y653868D02*
X102129Y653861D01*
G01X102106Y653887D02*
X102118Y653868D01*
G01X102129Y657011D02*
X102143Y657008D01*
G01X102117Y657019D02*
X102129Y657011D01*
G01X102105Y657039D02*
X102117Y657019D01*
G01X102129Y666459D02*
X102143Y666457D01*
G01X102117Y666467D02*
X102129Y666459D01*
G01X102105Y666487D02*
X102117Y666467D01*
G01X103091Y650742D02*
Y650735D01*
G01X103090Y650747D02*
X103091Y650742D01*
G01X103089Y650748D02*
X103090Y650747D01*
G01X103091Y653892D02*
Y653884D01*
G01X103090Y653896D02*
X103091Y653892D01*
G01X103089Y653898D02*
X103090Y653896D01*
G01X103091Y657041D02*
Y657034D01*
G01X103090Y657046D02*
X103091Y657041D01*
G01X103089Y657047D02*
X103090Y657046D01*
G01X103091Y660191D02*
Y660183D01*
G01X103090Y660196D02*
X103091Y660191D01*
G01X103089Y660197D02*
X103090Y660196D01*
G01X103091Y663341D02*
Y663333D01*
G01X103090Y663345D02*
X103091Y663341D01*
G01X103089Y663346D02*
X103090Y663345D01*
G01X103091Y666490D02*
Y666483D01*
G01X103090Y666495D02*
X103091Y666490D01*
G01X103089Y666496D02*
X103090Y666495D01*
G01X103091Y669640D02*
Y669632D01*
G01X103090Y669644D02*
X103091Y669640D01*
G01X103089Y669646D02*
X103090Y669644D01*
G01X102129Y669609D02*
X102143Y669606D01*
G01X102116Y669617D02*
X102129Y669609D01*
G01X102105Y669637D02*
X102116Y669617D01*
G01X102128Y650712D02*
X102143Y650709D01*
G01X102115Y650720D02*
X102128Y650712D01*
G01X102105Y650741D02*
X102115Y650720D01*
G01X103090Y651871D02*
X103091Y651864D01*
G01X103088Y651877D02*
X103090Y651871D01*
G01X103085Y651883D02*
X103088Y651877D01*
G01X103090Y655020D02*
X103091Y655014D01*
G01X103088Y655027D02*
X103090Y655020D01*
G01X103085Y655033D02*
X103088Y655027D01*
G01X103090Y658170D02*
X103091Y658163D01*
G01X103088Y658176D02*
X103090Y658170D01*
G01X103085Y658182D02*
X103088Y658176D01*
G01X103090Y661320D02*
X103091Y661313D01*
G01X103088Y661326D02*
X103090Y661320D01*
G01X103085Y661332D02*
X103088Y661326D01*
G01X103090Y664469D02*
X103091Y664463D01*
G01X103088Y664476D02*
X103090Y664469D01*
G01X103085Y664481D02*
X103088Y664476D01*
G01X103090Y667619D02*
X103091Y667612D01*
G01X103088Y667625D02*
X103090Y667619D01*
G01X103085Y667631D02*
X103088Y667625D01*
G01X103090Y670769D02*
X103091Y670762D01*
G01X103088Y670775D02*
X103090Y670769D01*
G01X103085Y670781D02*
X103088Y670775D01*
G01X103052Y650704D02*
Y650698D01*
G01X103050Y650707D02*
X103052Y650704D01*
G01X103050Y650709D02*
Y650707D01*
G01X103052Y653853D02*
Y653847D01*
G01X103050Y653857D02*
X103052Y653853D01*
G01X103050Y653858D02*
Y653857D01*
G01X103052Y657003D02*
Y656997D01*
G01X103050Y657007D02*
X103052Y657003D01*
G01X103050Y657008D02*
Y657007D01*
G01X103052Y660152D02*
Y660146D01*
G01X103050Y660156D02*
X103052Y660152D01*
G01X103050Y660157D02*
Y660156D01*
G01X103052Y663302D02*
Y663296D01*
G01X103050Y663306D02*
X103052Y663302D01*
G01X103050Y663307D02*
Y663306D01*
G01X103052Y669601D02*
Y669595D01*
G01X103050Y669605D02*
X103052Y669601D01*
G01X103050Y669606D02*
Y669605D01*
G01X115531Y648944D02*
Y648954D01*
G01X115532Y648939D02*
X115531Y648944D01*
G01X115533Y648937D02*
X115532Y648939D01*
G01X115531Y673944D02*
Y673954D01*
G01X115532Y673939D02*
X115531Y673944D01*
G01X115533Y673937D02*
X115532Y673939D01*
G01X115531Y678944D02*
Y678954D01*
G01X115532Y678939D02*
X115531Y678944D01*
G01X115533Y678937D02*
X115532Y678939D01*
G01X115531Y683944D02*
Y683954D01*
G01X115532Y683939D02*
X115531Y683944D01*
G01X115533Y683937D02*
X115532Y683939D01*
G01X115531Y688944D02*
Y688954D01*
G01X115532Y688939D02*
X115531Y688944D01*
G01X115533Y688937D02*
X115532Y688939D01*
G01X115531Y693944D02*
Y693954D01*
G01X115532Y693939D02*
X115531Y693944D01*
G01X115533Y693937D02*
X115532Y693939D01*
G01X116508Y649081D02*
X116516Y649055D01*
G01X116498Y649107D02*
X116508Y649081D01*
G01X116487Y649134D02*
X116498Y649107D01*
G01X116508Y674081D02*
X116516Y674055D01*
G01X116498Y674107D02*
X116508Y674081D01*
G01X116487Y674134D02*
X116498Y674107D01*
G01X116508Y679081D02*
X116516Y679055D01*
G01X116498Y679107D02*
X116508Y679081D01*
G01X116487Y679134D02*
X116498Y679107D01*
G01X116508Y684081D02*
X116516Y684055D01*
G01X116498Y684107D02*
X116508Y684081D01*
G01X116487Y684134D02*
X116498Y684107D01*
G01X116508Y689081D02*
X116516Y689055D01*
G01X116498Y689107D02*
X116508Y689081D01*
G01X116487Y689134D02*
X116498Y689107D01*
G01X116508Y694081D02*
X116516Y694055D01*
G01X116498Y694107D02*
X116508Y694081D01*
G01X116487Y694134D02*
X116498Y694107D01*
G01X102124Y660163D02*
X102143Y660157D01*
G01X102111Y660175D02*
X102124Y660163D01*
G01X102104Y660193D02*
X102111Y660175D01*
G01X116498Y648932D02*
X116479Y648937D01*
G01X116513Y648918D02*
X116498Y648932D01*
G01X116518Y648898D02*
X116513Y648918D01*
G01X116498Y673932D02*
X116479Y673937D01*
G01X116513Y673918D02*
X116498Y673932D01*
G01X116518Y673898D02*
X116513Y673918D01*
G01X116498Y678932D02*
X116479Y678937D01*
G01X116513Y678918D02*
X116498Y678932D01*
G01X116518Y678898D02*
X116513Y678918D01*
G01X116498Y683932D02*
X116479Y683937D01*
G01X116513Y683918D02*
X116498Y683932D01*
G01X116518Y683898D02*
X116513Y683918D01*
G01X116498Y688932D02*
X116479Y688937D01*
G01X116513Y688918D02*
X116498Y688932D01*
G01X116518Y688898D02*
X116513Y688918D01*
G01X116498Y693932D02*
X116479Y693937D01*
G01X116513Y693918D02*
X116498Y693932D01*
G01X116518Y693898D02*
X116513Y693918D01*
G01X103083Y658171D02*
X103076Y658180D01*
G01X103087Y658161D02*
X103083Y658171D01*
G01X103089Y658150D02*
X103087Y658161D01*
G01X103083Y651872D02*
X103076Y651880D01*
G01X103088Y651861D02*
X103083Y651872D01*
G01X103089Y651850D02*
X103088Y651861D01*
G01X103083Y655021D02*
X103076Y655030D01*
G01X103088Y655011D02*
X103083Y655021D01*
G01X103089Y655000D02*
X103088Y655011D01*
G01X103083Y661320D02*
X103076Y661329D01*
G01X103088Y661310D02*
X103083Y661320D01*
G01X103089Y661299D02*
X103088Y661310D01*
G01X103083Y664470D02*
X103076Y664479D01*
G01X103088Y664460D02*
X103083Y664470D01*
G01X103089Y664449D02*
X103088Y664460D01*
G01X103083Y667620D02*
X103076Y667628D01*
G01X103088Y667609D02*
X103083Y667620D01*
G01X103089Y667598D02*
X103088Y667609D01*
G01X103083Y670769D02*
X103076Y670778D01*
G01X103088Y670759D02*
X103083Y670769D01*
G01X103089Y670748D02*
X103088Y670759D01*
G01X103091Y670754D02*
Y670761D01*
G01X103090Y670750D02*
X103091Y670754D01*
G01X103089Y670748D02*
X103090Y670750D01*
G01X103091Y667605D02*
Y667612D01*
G01X103090Y667600D02*
X103091Y667605D01*
G01X103089Y667598D02*
X103090Y667600D01*
G01X103091Y664455D02*
Y664462D01*
G01X103090Y664451D02*
X103091Y664455D01*
G01X103089Y664449D02*
X103090Y664451D01*
G01X103091Y661306D02*
Y661313D01*
G01X103090Y661301D02*
X103091Y661306D01*
G01X103089Y661299D02*
X103090Y661301D01*
G01X103091Y658156D02*
Y658163D01*
G01X103090Y658152D02*
X103091Y658156D01*
G01X103089Y658150D02*
X103090Y658152D01*
G01X103091Y655006D02*
Y655013D01*
G01X103090Y655002D02*
X103091Y655006D01*
G01X103089Y655000D02*
X103090Y655002D01*
G01X103091Y651857D02*
Y651864D01*
G01X103090Y651852D02*
X103091Y651857D01*
G01X103089Y651850D02*
X103090Y651852D01*
G01X102106Y660191D02*
Y660183D01*
G01X102105Y660196D02*
X102106Y660191D01*
G01X102104Y660193D02*
X102105Y660196D01*
G01X116516Y648904D02*
Y648911D01*
G01X116517Y648900D02*
X116516Y648904D01*
G01X116518Y648898D02*
X116517Y648900D01*
G01X116516Y673904D02*
Y673911D01*
G01X116517Y673900D02*
X116516Y673904D01*
G01X116518Y673898D02*
X116517Y673900D01*
G01X116516Y678904D02*
Y678911D01*
G01X116517Y678900D02*
X116516Y678904D01*
G01X116518Y678898D02*
X116517Y678900D01*
G01X116516Y683904D02*
Y683911D01*
G01X116517Y683900D02*
X116516Y683904D01*
G01X116518Y683898D02*
X116517Y683900D01*
G01X116516Y688904D02*
Y688911D01*
G01X116517Y688900D02*
X116516Y688904D01*
G01X116518Y688898D02*
X116517Y688900D01*
G01X116516Y693904D02*
Y693911D01*
G01X116517Y693900D02*
X116516Y693904D01*
G01X116518Y693898D02*
X116517Y693900D01*
G01X102129Y663310D02*
X102143Y663307D01*
G01X102117Y663317D02*
X102129Y663310D01*
G01X102106Y663335D02*
X102117Y663317D01*
G01X102106Y653892D02*
Y653884D01*
G01X102105Y653896D02*
X102106Y653892D01*
G01X102104Y653894D02*
X102105Y653896D01*
G01X103051Y670793D02*
Y670799D01*
G01X103050Y670789D02*
X103051Y670793D01*
G01X103050Y670787D02*
Y670789D01*
G01X103051Y667643D02*
Y667649D01*
G01X103050Y667639D02*
X103051Y667643D01*
G01X103050Y667638D02*
Y667639D01*
G01X103051Y664493D02*
Y664500D01*
G01X103050Y664490D02*
X103051Y664493D01*
G01X103050Y664488D02*
Y664490D01*
G01X103051Y661344D02*
Y661350D01*
G01X103050Y661340D02*
X103051Y661344D01*
G01X103050Y661339D02*
Y661340D01*
G01X103051Y658194D02*
Y658200D01*
G01X103050Y658191D02*
X103051Y658194D01*
G01X103050Y658189D02*
Y658191D01*
G01X103051Y655044D02*
Y655051D01*
G01X103050Y655041D02*
X103051Y655044D01*
G01X103050Y655039D02*
Y655041D01*
G01X103051Y651895D02*
Y651901D01*
G01X103050Y651891D02*
X103051Y651895D01*
G01X103050Y651890D02*
Y651891D01*
G01X102145Y650704D02*
X102146Y650698D01*
G01X102144Y650707D02*
X102145Y650704D01*
G01X102143Y650709D02*
X102144Y650707D01*
G01X102145Y653854D02*
X102146Y653847D01*
G01X102144Y653857D02*
X102145Y653854D01*
G01X102143Y653858D02*
X102144Y653857D01*
G01X102145Y657003D02*
X102146Y656997D01*
G01X102144Y657007D02*
X102145Y657003D01*
G01X102143Y657008D02*
X102144Y657007D01*
G01X102145Y660153D02*
X102146Y660146D01*
G01X102144Y660156D02*
X102145Y660153D01*
G01X102143Y660157D02*
X102144Y660156D01*
G01X102145Y663302D02*
X102146Y663296D01*
G01X102144Y663306D02*
X102145Y663302D01*
G01X102143Y663307D02*
X102144Y663306D01*
G01X102145Y666452D02*
X102146Y666446D01*
G01X102144Y666456D02*
X102145Y666452D01*
G01X102143Y666457D02*
X102144Y666456D01*
G01X102145Y669602D02*
X102146Y669595D01*
G01X102144Y669605D02*
X102145Y669602D01*
G01X102143Y669606D02*
X102144Y669605D01*
G01X116516Y692552D02*
Y692543D01*
G01X116517Y692557D02*
X116516Y692552D01*
G01X116519Y692559D02*
X116517Y692557D01*
G01X116516Y687552D02*
Y687543D01*
G01X116517Y687557D02*
X116516Y687552D01*
G01X116519Y687559D02*
X116517Y687557D01*
G01X116516Y682552D02*
Y682543D01*
G01X116517Y682557D02*
X116516Y682552D01*
G01X116519Y682559D02*
X116517Y682557D01*
G01X116516Y677552D02*
Y677543D01*
G01X116517Y677557D02*
X116516Y677552D01*
G01X116519Y677559D02*
X116517Y677557D01*
G01X116516Y672552D02*
Y672543D01*
G01X116517Y672557D02*
X116516Y672552D01*
G01X116519Y672559D02*
X116517Y672557D01*
G01X102106Y670754D02*
Y670762D01*
G01X102105Y670750D02*
X102106Y670754D01*
G01X102104Y670748D02*
X102105Y670750D01*
G01X102106Y667605D02*
Y667612D01*
G01X102105Y667600D02*
X102106Y667605D01*
G01X102104Y667598D02*
X102105Y667600D01*
G01X102106Y664455D02*
Y664463D01*
G01X102105Y664450D02*
X102106Y664455D01*
G01X102104Y664449D02*
X102105Y664450D01*
G01X102106Y661306D02*
Y661313D01*
G01X102105Y661301D02*
X102106Y661306D01*
G01X102104Y661299D02*
X102105Y661301D01*
G01X102106Y658156D02*
Y658163D01*
G01X102105Y658151D02*
X102106Y658156D01*
G01X102104Y658150D02*
X102105Y658151D01*
G01X102106Y655006D02*
Y655014D01*
G01X102105Y655002D02*
X102106Y655006D01*
G01X102104Y655000D02*
X102105Y655002D01*
G01X102106Y651857D02*
Y651864D01*
G01X102105Y651852D02*
X102106Y651857D01*
G01X102104Y651850D02*
X102105Y651852D01*
G01X103059Y658188D02*
X103050Y658189D01*
G01X103068Y658185D02*
X103059Y658188D01*
G01X103076Y658180D02*
X103068Y658185D01*
G01X103059Y651889D02*
X103050Y651890D01*
G01X103068Y651885D02*
X103059Y651889D01*
G01X103076Y651880D02*
X103068Y651885D01*
G01X103059Y655038D02*
X103050Y655039D01*
G01X103068Y655035D02*
X103059Y655038D01*
G01X103076Y655030D02*
X103068Y655035D01*
G01X103059Y661337D02*
X103050Y661339D01*
G01X103068Y661334D02*
X103059Y661337D01*
G01X103076Y661329D02*
X103068Y661334D01*
G01X103059Y664487D02*
X103050Y664488D01*
G01X103068Y664484D02*
X103059Y664487D01*
G01X103076Y664479D02*
X103068Y664484D01*
G01X103059Y667637D02*
X103050Y667638D01*
G01X103068Y667633D02*
X103059Y667637D01*
G01X103076Y667628D02*
X103068Y667633D01*
G01X103059Y670786D02*
X103050Y670787D01*
G01X103068Y670783D02*
X103059Y670786D01*
G01X103076Y670778D02*
X103068Y670783D01*
G01X103088Y669620D02*
X103091Y669632D01*
G01X103081Y669609D02*
X103088Y669620D01*
G01X103071Y669600D02*
X103081Y669609D01*
G01X103088Y663320D02*
X103091Y663333D01*
G01X103081Y663309D02*
X103088Y663320D01*
G01X103071Y663301D02*
X103081Y663309D01*
G01X103088Y660171D02*
X103091Y660183D01*
G01X103081Y660160D02*
X103088Y660171D01*
G01X103071Y660152D02*
X103081Y660160D01*
G01X103088Y657021D02*
X103091Y657034D01*
G01X103081Y657010D02*
X103088Y657021D01*
G01X103071Y657002D02*
X103081Y657010D01*
G01X103088Y653872D02*
X103091Y653884D01*
G01X103081Y653861D02*
X103088Y653872D01*
G01X103071Y653852D02*
X103081Y653861D01*
G01X103088Y650722D02*
X103091Y650735D01*
G01X103081Y650711D02*
X103088Y650722D01*
G01X103071Y650703D02*
X103081Y650711D01*
G01X102106Y660187D02*
Y660183D01*
G01X102107Y660182D02*
X102106Y660187D01*
G01X102118Y660167D02*
X102107Y660182D01*
G01X102141Y660158D02*
X102118Y660167D01*
G01X102145Y670793D02*
Y670799D01*
G01Y670789D02*
Y670793D01*
G01X102143Y670787D02*
X102145Y670789D01*
G01Y667643D02*
Y667649D01*
G01Y667639D02*
Y667643D01*
G01X102143Y667638D02*
X102145Y667639D01*
G01Y664493D02*
Y664500D01*
G01Y664489D02*
Y664493D01*
G01X102143Y664488D02*
X102145Y664489D01*
G01Y661344D02*
Y661350D01*
G01Y661340D02*
Y661344D01*
G01X102143Y661339D02*
X102145Y661340D01*
G01Y658194D02*
Y658200D01*
G01Y658190D02*
Y658194D01*
G01X102143Y658189D02*
X102145Y658190D01*
G01Y655044D02*
Y655051D01*
G01Y655041D02*
Y655044D01*
G01X102143Y655039D02*
X102145Y655041D01*
G01Y651895D02*
Y651901D01*
G01Y651891D02*
Y651895D01*
G01X102143Y651890D02*
X102145Y651891D01*
G01X102107Y670768D02*
X102106Y670762D01*
G01X102109Y670774D02*
X102107Y670768D01*
G01X102111Y670780D02*
X102109Y670774D01*
G01X102115Y670785D02*
X102111Y670780D01*
G01X102120Y670790D02*
X102115Y670785D01*
G01X102126Y670794D02*
X102120Y670790D01*
G01X102107Y667619D02*
X102106Y667612D01*
G01X102109Y667625D02*
X102107Y667619D01*
G01X102111Y667630D02*
X102109Y667625D01*
G01X102115Y667636D02*
X102111Y667630D01*
G01X102120Y667640D02*
X102115Y667636D01*
G01X102126Y667644D02*
X102120Y667640D01*
G01X102107Y664469D02*
X102106Y664463D01*
G01X102109Y664475D02*
X102107Y664469D01*
G01X102111Y664481D02*
X102109Y664475D01*
G01X102115Y664486D02*
X102111Y664481D01*
G01X102120Y664491D02*
X102115Y664486D01*
G01X102126Y664494D02*
X102120Y664491D01*
G01X102107Y661319D02*
X102106Y661313D01*
G01X102109Y661326D02*
X102107Y661319D01*
G01X102111Y661331D02*
X102109Y661326D01*
G01X102115Y661337D02*
X102111Y661331D01*
G01X102120Y661341D02*
X102115Y661337D01*
G01X102126Y661345D02*
X102120Y661341D01*
G01X102107Y658170D02*
X102106Y658163D01*
G01X102109Y658176D02*
X102107Y658170D01*
G01X102111Y658181D02*
X102109Y658176D01*
G01X102115Y658187D02*
X102111Y658181D01*
G01X102120Y658191D02*
X102115Y658187D01*
G01X102126Y658195D02*
X102120Y658191D01*
G01X102107Y655020D02*
X102106Y655014D01*
G01X102109Y655026D02*
X102107Y655020D01*
G01X102111Y655032D02*
X102109Y655026D01*
G01X102115Y655037D02*
X102111Y655032D01*
G01X102120Y655042D02*
X102115Y655037D01*
G01X102126Y655046D02*
X102120Y655042D01*
G01X102107Y651870D02*
X102106Y651864D01*
G01X102109Y651877D02*
X102107Y651870D01*
G01X102111Y651882D02*
X102109Y651877D01*
G01X102115Y651888D02*
X102111Y651882D01*
G01X102120Y651892D02*
X102115Y651888D01*
G01X102126Y651896D02*
X102120Y651892D01*
G01X102106Y653888D02*
Y653884D01*
G01X102108Y653882D02*
X102106Y653888D01*
G01X102120Y653867D02*
X102108Y653882D01*
G01X102144Y653858D02*
X102120Y653867D01*
G01X102106Y657038D02*
Y657034D01*
G01X102108Y657031D02*
X102106Y657038D01*
G01X102119Y657016D02*
X102108Y657031D01*
G01X102144Y657008D02*
X102119Y657016D01*
G01X102106Y663337D02*
Y663333D01*
G01X102108Y663331D02*
X102106Y663337D01*
G01X102119Y663315D02*
X102108Y663331D01*
G01X102144Y663307D02*
X102119Y663315D01*
G01X102106Y666487D02*
Y666483D01*
G01X102108Y666480D02*
X102106Y666487D01*
G01X102119Y666465D02*
X102108Y666480D01*
G01X102144Y666457D02*
X102119Y666465D01*
G01X102106Y650739D02*
Y650735D01*
G01X102108Y650732D02*
X102106Y650739D01*
G01X102119Y650717D02*
X102108Y650732D01*
G01X102144Y650709D02*
X102119Y650717D01*
G01X102106Y669636D02*
Y669632D01*
G01X102108Y669630D02*
X102106Y669636D01*
G01X102119Y669615D02*
X102108Y669630D01*
G01X102144Y669606D02*
X102119Y669615D01*
G01X116503Y648929D02*
X116514Y648913D01*
G01X116479Y648937D02*
X116503Y648929D01*
G01Y673929D02*
X116514Y673913D01*
G01X116479Y673937D02*
X116503Y673929D01*
G01Y678929D02*
X116514Y678913D01*
G01X116479Y678937D02*
X116503Y678929D01*
G01Y683929D02*
X116514Y683913D01*
G01X116479Y683937D02*
X116503Y683929D01*
G01Y688929D02*
X116514Y688913D01*
G01X116479Y688937D02*
X116503Y688929D01*
G01Y693929D02*
X116514Y693913D01*
G01X116479Y693937D02*
X116503Y693929D01*
G01X103062Y669608D02*
X103050Y669606D01*
G01X103072Y669613D02*
X103062Y669608D01*
G01Y666459D02*
X103050Y666457D01*
G01X103072Y666464D02*
X103062Y666459D01*
G01Y663309D02*
X103050Y663307D01*
G01X103072Y663314D02*
X103062Y663309D01*
G01Y660159D02*
X103050Y660157D01*
G01X103072Y660165D02*
X103062Y660159D01*
G01Y657010D02*
X103050Y657008D01*
G01X103072Y657015D02*
X103062Y657010D01*
G01Y653860D02*
X103050Y653858D01*
G01X103072Y653865D02*
X103062Y653860D01*
G01Y650711D02*
X103050Y650709D01*
G01X103072Y650716D02*
X103062Y650711D01*
G01X103081Y651888D02*
X103085Y651883D01*
G01X103076Y651893D02*
X103081Y651888D01*
G01X103070Y651896D02*
X103076Y651893D01*
G01X103065Y651899D02*
X103070Y651896D01*
G01X103058Y651901D02*
X103065Y651899D01*
G01X103051Y651901D02*
X103058D01*
G01X103081Y655038D02*
X103085Y655033D01*
G01X103076Y655042D02*
X103081Y655038D01*
G01X103070Y655046D02*
X103076Y655042D01*
G01X103065Y655048D02*
X103070Y655046D01*
G01X103058Y655050D02*
X103065Y655048D01*
G01X103051Y655051D02*
X103058Y655050D01*
G01X103081Y658187D02*
X103085Y658182D01*
G01X103076Y658192D02*
X103081Y658187D01*
G01X103070Y658196D02*
X103076Y658192D01*
G01X103065Y658198D02*
X103070Y658196D01*
G01X103058Y658200D02*
X103065Y658198D01*
G01X103051Y658200D02*
X103058D01*
G01X103081Y661337D02*
X103085Y661332D01*
G01X103076Y661341D02*
X103081Y661337D01*
G01X103070Y661345D02*
X103076Y661341D01*
G01X103065Y661348D02*
X103070Y661345D01*
G01X103058Y661350D02*
X103065Y661348D01*
G01X103051Y661350D02*
X103058D01*
G01X103081Y664487D02*
X103085Y664481D01*
G01X103076Y664491D02*
X103081Y664487D01*
G01X103070Y664495D02*
X103076Y664491D01*
G01X103065Y664497D02*
X103070Y664495D01*
G01X103058Y664499D02*
X103065Y664497D01*
G01X103051Y664500D02*
X103058Y664499D01*
G01X103081Y667636D02*
X103085Y667631D01*
G01X103076Y667641D02*
X103081Y667636D01*
G01X103070Y667644D02*
X103076Y667641D01*
G01X103065Y667647D02*
X103070Y667644D01*
G01X103058Y667649D02*
X103065Y667647D01*
G01X103051Y667649D02*
X103058D01*
G01X103081Y670786D02*
X103085Y670781D01*
G01X103076Y670790D02*
X103081Y670786D01*
G01X103070Y670794D02*
X103076Y670790D01*
G01X103065Y670796D02*
X103070Y670794D01*
G01X103058Y670798D02*
X103065Y670796D01*
G01X103051Y670799D02*
X103058Y670798D01*
G01X102107Y650727D02*
X102106Y650735D01*
G01X102109Y650720D02*
X102107Y650727D01*
G01X102113Y650714D02*
X102109Y650720D01*
G01X102118Y650708D02*
X102113Y650714D01*
G01X102124Y650704D02*
X102118Y650708D01*
G01X102131Y650700D02*
X102124Y650704D01*
G01X102138Y650698D02*
X102131Y650700D01*
G01X102146Y650698D02*
X102138D01*
G01X102107Y653877D02*
X102106Y653884D01*
G01X102109Y653870D02*
X102107Y653877D01*
G01X102113Y653864D02*
X102109Y653870D01*
G01X102118Y653858D02*
X102113Y653864D01*
G01X102124Y653853D02*
X102118Y653858D01*
G01X102131Y653850D02*
X102124Y653853D01*
G01X102138Y653848D02*
X102131Y653850D01*
G01X102146Y653847D02*
X102138Y653848D01*
G01X102107Y657026D02*
X102106Y657034D01*
G01X102109Y657020D02*
X102107Y657026D01*
G01X102113Y657013D02*
X102109Y657020D01*
G01X102118Y657007D02*
X102113Y657013D01*
G01X102124Y657003D02*
X102118Y657007D01*
G01X102131Y657000D02*
X102124Y657003D01*
G01X102138Y656998D02*
X102131Y657000D01*
G01X102146Y656997D02*
X102138Y656998D01*
G01X102107Y660176D02*
X102106Y660183D01*
G01X102109Y660169D02*
X102107Y660176D01*
G01X102113Y660163D02*
X102109Y660169D01*
G01X102118Y660157D02*
X102113Y660163D01*
G01X102124Y660152D02*
X102118Y660157D01*
G01X102131Y660149D02*
X102124Y660152D01*
G01X102138Y660147D02*
X102131Y660149D01*
G01X102146Y660146D02*
X102138Y660147D01*
G01X102107Y663326D02*
X102106Y663333D01*
G01X102109Y663319D02*
X102107Y663326D01*
G01X102113Y663313D02*
X102109Y663319D01*
G01X102118Y663307D02*
X102113Y663313D01*
G01X102124Y663302D02*
X102118Y663307D01*
G01X102131Y663299D02*
X102124Y663302D01*
G01X102138Y663297D02*
X102131Y663299D01*
G01X102146Y663296D02*
X102138Y663297D01*
G01X102107Y666475D02*
X102106Y666483D01*
G01X102109Y666469D02*
X102107Y666475D01*
G01X102113Y666462D02*
X102109Y666469D01*
G01X102118Y666456D02*
X102113Y666462D01*
G01X102124Y666452D02*
X102118Y666456D01*
G01X102131Y666448D02*
X102124Y666452D01*
G01X102138Y666446D02*
X102131Y666448D01*
G01X102146Y666446D02*
X102138D01*
G01X102107Y669625D02*
X102106Y669632D01*
G01X102109Y669618D02*
X102107Y669625D01*
G01X102113Y669612D02*
X102109Y669618D01*
G01X102118Y669606D02*
X102113Y669612D01*
G01X102124Y669601D02*
X102118Y669606D01*
G01X102131Y669598D02*
X102124Y669601D01*
G01X102138Y669596D02*
X102131Y669598D01*
G01X102146Y669595D02*
X102138Y669596D01*
G01X103060Y651889D02*
X103070Y651884D01*
G01X103050Y651890D02*
X103060Y651889D01*
G01Y655038D02*
X103070Y655034D01*
G01X103050Y655039D02*
X103060Y655038D01*
G01Y658188D02*
X103070Y658183D01*
G01X103050Y658189D02*
X103060Y658188D01*
G01Y661337D02*
X103070Y661333D01*
G01X103050Y661339D02*
X103060Y661337D01*
G01Y664487D02*
X103070Y664483D01*
G01X103050Y664488D02*
X103060Y664487D01*
G01Y667637D02*
X103070Y667632D01*
G01X103050Y667638D02*
X103060Y667637D01*
G01Y670786D02*
X103070Y670782D01*
G01X103050Y670787D02*
X103060Y670786D01*
G01X103068Y650701D02*
X103071Y650703D01*
G01X103065Y650700D02*
X103068Y650701D01*
G01X103062Y650699D02*
X103065Y650700D01*
G01X103058Y650698D02*
X103062Y650699D01*
G01X103055Y650698D02*
X103058D01*
G01X103051D02*
X103055D01*
G01X102129Y651898D02*
X102126Y651896D01*
G01X102132Y651899D02*
X102129Y651898D01*
G01X102135Y651900D02*
X102132Y651899D01*
G01X102139Y651900D02*
X102135D01*
G01X102142Y651901D02*
X102139Y651900D01*
G01X102146Y651901D02*
X102142D01*
G01X103068Y653851D02*
X103071Y653852D01*
G01X103065Y653850D02*
X103068Y653851D01*
G01X103062Y653848D02*
X103065Y653850D01*
G01X103058Y653848D02*
X103062D01*
G01X103055Y653847D02*
X103058Y653848D01*
G01X103051Y653847D02*
X103055D01*
G01X102129Y655047D02*
X102126Y655046D01*
G01X102132Y655048D02*
X102129Y655047D01*
G01X102135Y655050D02*
X102132Y655048D01*
G01X102139Y655050D02*
X102135D01*
G01X102142Y655051D02*
X102139Y655050D01*
G01X102146Y655051D02*
X102142D01*
G01X103068Y657000D02*
X103071Y657002D01*
G01X103065Y656999D02*
X103068Y657000D01*
G01X103062Y656998D02*
X103065Y656999D01*
G01X103058Y656997D02*
X103062Y656998D01*
G01X103055Y656997D02*
X103058D01*
G01X103051D02*
X103055D01*
G01X102129Y658197D02*
X102126Y658195D01*
G01X102132Y658198D02*
X102129Y658197D01*
G01X102135Y658199D02*
X102132Y658198D01*
G01X102139Y658200D02*
X102135Y658199D01*
G01X102142Y658200D02*
X102139D01*
G01X102146D02*
X102142D01*
G01X103068Y660150D02*
X103071Y660152D01*
G01X103065Y660149D02*
X103068Y660150D01*
G01X103062Y660148D02*
X103065Y660149D01*
G01X103058Y660147D02*
X103062Y660148D01*
G01X103055Y660146D02*
X103058Y660147D01*
G01X103051Y660146D02*
X103055D01*
G01X102129Y661346D02*
X102126Y661345D01*
G01X102132Y661348D02*
X102129Y661346D01*
G01X102135Y661349D02*
X102132Y661348D01*
G01X102139Y661349D02*
X102135D01*
G01X102142Y661350D02*
X102139Y661349D01*
G01X102146Y661350D02*
X102142D01*
G01X103068Y663300D02*
X103071Y663301D01*
G01X103065Y663298D02*
X103068Y663300D01*
G01X103062Y663297D02*
X103065Y663298D01*
G01X103058Y663296D02*
X103062Y663297D01*
G01X103055Y663296D02*
X103058D01*
G01X103051D02*
X103055D01*
G01X102129Y664496D02*
X102126Y664494D01*
G01X102132Y664497D02*
X102129Y664496D01*
G01X102135Y664498D02*
X102132Y664497D01*
G01X102139Y664499D02*
X102135Y664498D01*
G01X102142Y664500D02*
X102139Y664499D01*
G01X102146Y664500D02*
X102142D01*
G01X102129Y667646D02*
X102126Y667644D01*
G01X102132Y667647D02*
X102129Y667646D01*
G01X102135Y667648D02*
X102132Y667647D01*
G01X102139Y667648D02*
X102135D01*
G01X102142Y667649D02*
X102139Y667648D01*
G01X102146Y667649D02*
X102142D01*
G01X101359Y653898D02*
X100925D01*
G01X101733D02*
X101359D01*
G01Y660197D02*
X100925D01*
G01X101733D02*
X101359D01*
G01Y663346D02*
X100925D01*
G01X101732D02*
X101359D01*
G01X103090Y666475D02*
X103091Y666483D01*
G01X103087Y666469D02*
X103090Y666475D01*
G01X103084Y666462D02*
X103087Y666469D01*
G01X103079Y666456D02*
X103084Y666462D01*
G01X103073Y666452D02*
X103079Y666456D01*
G01X103066Y666448D02*
X103073Y666452D01*
G01X103059Y666446D02*
X103066Y666448D01*
G01X103051Y666446D02*
X103059D01*
G01X103068Y669599D02*
X103071Y669600D01*
G01X103065Y669598D02*
X103068Y669599D01*
G01X103062Y669596D02*
X103065Y669598D01*
G01X103058Y669596D02*
X103062D01*
G01X103055Y669595D02*
X103058Y669596D01*
G01X103051Y669595D02*
X103055D01*
G01X102129Y670795D02*
X102126Y670794D01*
G01X102132Y670796D02*
X102129Y670795D01*
G01X102135Y670798D02*
X102132Y670796D01*
G01X102139Y670798D02*
X102135D01*
G01X102142Y670799D02*
X102139Y670798D01*
G01X102146Y670799D02*
X102142D01*
G01X102109Y651870D02*
X102104Y651850D01*
G01X102124Y651885D02*
X102109Y651870D01*
G01X102143Y651890D02*
X102124Y651885D01*
G01X102109Y655020D02*
X102104Y655000D01*
G01X102124Y655034D02*
X102109Y655020D01*
G01X102143Y655039D02*
X102124Y655034D01*
G01X103084Y650728D02*
X103089Y650748D01*
G01X103069Y650714D02*
X103084Y650728D01*
G01X103050Y650709D02*
X103069Y650714D01*
G01X103084Y653878D02*
X103089Y653898D01*
G01X103069Y653864D02*
X103084Y653878D01*
G01X103050Y653858D02*
X103069Y653864D01*
G01X102109Y658169D02*
X102104Y658150D01*
G01X102124Y658184D02*
X102109Y658169D01*
G01X102143Y658189D02*
X102124Y658184D01*
G01X102109Y661319D02*
X102104Y661299D01*
G01X102124Y661333D02*
X102109Y661319D01*
G01X102143Y661339D02*
X102124Y661333D01*
G01X102109Y664469D02*
X102104Y664449D01*
G01X102124Y664483D02*
X102109Y664469D01*
G01X102143Y664488D02*
X102124Y664483D01*
G01X102109Y667618D02*
X102104Y667598D01*
G01X102124Y667633D02*
X102109Y667618D01*
G01X102143Y667638D02*
X102124Y667633D01*
G01X102109Y670768D02*
X102104Y670748D01*
G01X102124Y670782D02*
X102109Y670768D01*
G01X102143Y670787D02*
X102124Y670782D01*
G01X103084Y657028D02*
X103089Y657047D01*
G01X103069Y657013D02*
X103084Y657028D01*
G01X103050Y657008D02*
X103069Y657013D01*
G01X103084Y660177D02*
X103089Y660197D01*
G01X103069Y660163D02*
X103084Y660177D01*
G01X103050Y660157D02*
X103069Y660163D01*
G01X103084Y663327D02*
X103089Y663346D01*
G01X103069Y663313D02*
X103084Y663327D01*
G01X103050Y663307D02*
X103069Y663313D01*
G01X103084Y666476D02*
X103089Y666496D01*
G01X103069Y666462D02*
X103084Y666476D01*
G01X103050Y666457D02*
X103069Y666462D01*
G01X103084Y669626D02*
X103089Y669646D01*
G01X103069Y669612D02*
X103084Y669626D01*
G01X103050Y669606D02*
X103069Y669612D01*
G01X102104Y660193D02*
X101993Y660197D01*
G01X102104Y653894D02*
X101993Y653898D01*
G01X102104Y663343D02*
X101993Y663346D01*
G01X116516Y694429D02*
X115531D01*
G01X115533Y693937D02*
X120866D01*
G01Y693898D02*
X116518D01*
G01X120866Y692559D02*
X115533D01*
G01X115531Y692067D02*
X116516D01*
G01Y689429D02*
X115531D01*
G01X115533Y688937D02*
X120866D01*
G01Y688898D02*
X116518D01*
G01X120866Y687559D02*
X115533D01*
G01X115531Y687067D02*
X116516D01*
G01Y684429D02*
X115531D01*
G01X115533Y683937D02*
X120866D01*
G01Y683898D02*
X116518D01*
G01X120866Y682559D02*
X115533D01*
G01X115531Y682067D02*
X116516D01*
G01Y679429D02*
X115531D01*
G01X115533Y678937D02*
X120866D01*
G01Y678898D02*
X116518D01*
G01X120866Y677559D02*
X115533D01*
G01X115531Y677067D02*
X116516D01*
G01Y674429D02*
X115531D01*
G01X115533Y673937D02*
X120866D01*
G01Y673898D02*
X116518D01*
G01X103543Y672953D02*
X100197D01*
G01X120866Y672559D02*
X115533D01*
G01X115531Y672067D02*
X116516D01*
G01X113189Y671791D02*
X117126D01*
G01X103051Y670984D02*
X102146D01*
G01X103091Y670945D02*
X102106D01*
G01X103050Y670787D02*
X97165D01*
G01Y670748D02*
X103089D01*
G01X112008Y670610D02*
X115945D01*
G01X103089Y669646D02*
X97165D01*
G01X103050Y669606D02*
X97165D01*
G01X102106Y669449D02*
X103091D01*
G01X102146Y669409D02*
X103051D01*
G01Y667835D02*
X102146D01*
G01X103091Y667795D02*
X102106D01*
G01X103050Y667638D02*
X97165D01*
G01Y667598D02*
X103089D01*
G01Y666496D02*
X97165D01*
G01X103050Y666457D02*
X97165D01*
G01X102106Y666299D02*
X103091D01*
G01X102146Y666260D02*
X103051D01*
G01Y664685D02*
X102146D01*
G01X103091Y664646D02*
X102106D01*
G01X103050Y664488D02*
X97165D01*
G01Y664449D02*
X103089D01*
G01Y663346D02*
X97165D01*
G01X103050Y663307D02*
X97165D01*
G01X102106Y663150D02*
X103091D01*
G01X102146Y663110D02*
X103051D01*
G01Y661535D02*
X102146D01*
G01X103091Y661496D02*
X102106D01*
G01X103050Y661339D02*
X97165D01*
G01Y661299D02*
X103089D01*
G01Y660197D02*
X97165D01*
G01X103050Y660157D02*
X97165D01*
G01X102106Y660000D02*
X103091D01*
G01X102146Y659961D02*
X103051D01*
G01Y658386D02*
X102146D01*
G01X103091Y658346D02*
X102106D01*
G01X103050Y658189D02*
X97165D01*
G01Y658150D02*
X103089D01*
G01Y657047D02*
X97165D01*
G01X103050Y657008D02*
X97165D01*
G01X102106Y656850D02*
X103091D01*
G01X102146Y656811D02*
X103051D01*
G01Y655236D02*
X102146D01*
G01X103091Y655197D02*
X102106D01*
G01X103050Y655039D02*
X97165D01*
G01Y655000D02*
X103089D01*
G01Y653898D02*
X97165D01*
G01X103050Y653858D02*
X97165D01*
G01X102106Y653701D02*
X103091D01*
G01X102146Y653661D02*
X103051D01*
G01Y652087D02*
X102146D01*
G01X103091Y652047D02*
X102106D01*
G01X103050Y651890D02*
X97165D01*
G01Y651850D02*
X103089D01*
G01X115945Y650886D02*
X112008D01*
G01X103089Y650748D02*
X97165D01*
G01X103050Y650709D02*
X97165D01*
G01X102106Y650551D02*
X103091D01*
G01X102146Y650512D02*
X103051D01*
G01X117126Y649705D02*
X113189D01*
G01X116516Y649429D02*
X115531D01*
G01X115533Y648937D02*
X120866D01*
G01Y648898D02*
X116518D01*
G01X103543Y648543D02*
X100197D01*
G01X115531Y694133D02*
X116487Y694134D01*
G01X116516Y692363D02*
X115531Y692362D01*
G01Y689133D02*
X116487Y689134D01*
G01X116516Y687363D02*
X115531Y687362D01*
G01Y684133D02*
X116487Y684134D01*
G01X116516Y682363D02*
X115531Y682362D01*
G01Y679133D02*
X116487Y679134D01*
G01X116516Y677363D02*
X115531Y677362D01*
G01Y674133D02*
X116487Y674134D01*
G01X116516Y672363D02*
X115531Y672362D01*
G01Y649133D02*
X116487Y649134D01*
G01X101993Y669646D02*
X102105Y669637D01*
G01X115945Y670610D02*
X117126Y671791D01*
G01X112008Y670610D02*
X113189Y671791D01*
G01X115945Y650886D02*
X117126Y649705D01*
G01X112008Y650886D02*
X113189Y649705D01*
G01X103050Y666457D02*
X103053Y666446D01*
G01X103090Y651853D02*
X103091Y651864D01*
G01X103090Y655002D02*
X103091Y655013D01*
G01X103090Y658152D02*
X103091Y658163D01*
G01X103090Y661302D02*
X103091Y661313D01*
G01X103090Y664451D02*
X103091Y664462D01*
G01X103090Y667601D02*
X103091Y667612D01*
G01X103090Y670750D02*
X103091Y670761D01*
G01X116516Y648911D02*
Y648920D01*
G01Y673911D02*
Y673920D01*
G01Y678911D02*
Y678920D01*
G01Y683911D02*
Y683920D01*
G01Y688911D02*
Y688920D01*
G01Y693911D02*
Y693920D01*
G01X117697Y673937D02*
Y672559D01*
G01Y678937D02*
Y677559D01*
G01Y683937D02*
Y682559D01*
G01Y688937D02*
Y687559D01*
G01Y693937D02*
Y692559D01*
G01X117126Y671791D02*
Y649705D01*
G01X116516Y692067D02*
Y694429D01*
G01Y687067D02*
Y689429D01*
G01Y682067D02*
Y684429D01*
G01Y677067D02*
Y679429D01*
G01Y672067D02*
Y674429D01*
G01X115945Y670610D02*
Y650886D01*
G01X115531Y674429D02*
Y672067D01*
G01Y679429D02*
Y677067D01*
G01Y684429D02*
Y682067D01*
G01Y689429D02*
Y687067D01*
G01Y694429D02*
Y692067D01*
G01X113189Y748248D02*
Y671791D01*
G01X112008Y747067D02*
Y670610D01*
G01X103543Y751988D02*
Y672953D01*
G01X103091Y669449D02*
Y670945D01*
G01Y666299D02*
Y667795D01*
G01Y663150D02*
Y664646D01*
G01Y660000D02*
Y661496D01*
G01Y656850D02*
Y658346D01*
G01Y653701D02*
Y655197D01*
G01Y650551D02*
Y652047D01*
G01X103051Y650698D02*
Y650551D01*
G01Y652048D02*
Y651901D01*
G01Y656997D02*
Y656850D01*
G01Y653847D02*
Y653700D01*
G01Y655197D02*
Y655051D01*
G01Y660146D02*
Y660000D01*
G01Y661496D02*
Y661350D01*
G01Y658347D02*
Y658200D01*
G01Y666446D02*
Y666299D01*
G01Y663296D02*
Y663149D01*
G01Y664646D02*
Y664500D01*
G01Y669595D02*
Y669448D01*
G01Y670945D02*
Y670799D01*
G01Y667796D02*
Y667649D01*
G01X102146Y669448D02*
Y669595D01*
G01Y670799D02*
Y670946D01*
G01Y667649D02*
Y667796D01*
G01Y666298D02*
Y666446D01*
G01Y663149D02*
Y663296D01*
G01Y664500D02*
Y664646D01*
G01Y659999D02*
Y660146D01*
G01Y661350D02*
Y661497D01*
G01Y658200D02*
Y658347D01*
G01Y656850D02*
Y656997D01*
G01Y653700D02*
Y653847D01*
G01Y655051D02*
Y655198D01*
G01Y650550D02*
Y650698D01*
G01Y651901D02*
Y652048D01*
G01X102106Y652047D02*
Y650551D01*
G01Y655197D02*
Y653701D01*
G01Y661496D02*
Y660000D01*
G01Y658346D02*
Y656850D01*
G01Y664646D02*
Y663150D01*
G01Y670945D02*
Y669449D01*
G01Y667795D02*
Y666299D01*
G01X100925Y651890D02*
Y650709D01*
G01Y658189D02*
Y657008D01*
G01Y655039D02*
Y653858D01*
G01Y661339D02*
Y660157D01*
G01Y667638D02*
Y666457D01*
G01Y664488D02*
Y663307D01*
G01Y670787D02*
Y669606D01*
G01X100591Y672953D02*
Y648543D01*
G01X100197D02*
Y672953D01*
G01X97165Y669606D02*
Y670787D01*
G01Y666457D02*
Y667638D01*
G01Y663307D02*
Y664488D01*
G01Y660157D02*
Y661339D01*
G01Y657008D02*
Y658189D01*
G01Y653858D02*
Y655039D01*
G01Y650709D02*
Y651890D01*
G01X103091Y669632D02*
X103090Y669643D01*
G01X103091Y666483D02*
X103090Y666494D01*
G01X103091Y663333D02*
X103090Y663344D01*
G01X103091Y660183D02*
X103090Y660194D01*
G01X103091Y657034D02*
X103090Y657045D01*
G01X103091Y653884D02*
X103090Y653895D01*
G01X103091Y650735D02*
X103090Y650746D01*
G01X116483Y699035D02*
X116487Y699134D01*
G01X116477Y698963D02*
X116483Y699035D01*
G01X116479Y698937D02*
X116477Y698963D01*
G01X116483Y704035D02*
X116487Y704134D01*
G01X116477Y703963D02*
X116483Y704035D01*
G01X116479Y703937D02*
X116477Y703963D01*
G01X116483Y709035D02*
X116487Y709134D01*
G01X116477Y708963D02*
X116483Y709035D01*
G01X116479Y708937D02*
X116477Y708963D01*
G01X116483Y714035D02*
X116487Y714134D01*
G01X116477Y713963D02*
X116483Y714035D01*
G01X116479Y713937D02*
X116477Y713963D01*
G01X116483Y719035D02*
X116487Y719134D01*
G01X116477Y718963D02*
X116483Y719035D01*
G01X116479Y718937D02*
X116477Y718963D01*
G01X116483Y724035D02*
X116487Y724134D01*
G01X116477Y723963D02*
X116483Y724035D01*
G01X116479Y723937D02*
X116477Y723963D01*
G01X116483Y729035D02*
X116487Y729134D01*
G01X116477Y728963D02*
X116483Y729035D01*
G01X116479Y728937D02*
X116477Y728963D01*
G01X116483Y734035D02*
X116487Y734134D01*
G01X116477Y733963D02*
X116483Y734035D01*
G01X116479Y733937D02*
X116477Y733963D01*
G01X116483Y739035D02*
X116487Y739134D01*
G01X116477Y738963D02*
X116483Y739035D01*
G01X116479Y738937D02*
X116477Y738963D01*
G01X116483Y744035D02*
X116487Y744134D01*
G01X116477Y743963D02*
X116483Y744035D01*
G01X116479Y743937D02*
X116477Y743963D01*
G01X115532Y742557D02*
X115533Y742559D01*
G01X115531Y742552D02*
X115532Y742557D01*
G01X115531Y742543D02*
Y742552D01*
G01X115532Y737557D02*
X115533Y737559D01*
G01X115531Y737552D02*
X115532Y737557D01*
G01X115531Y737543D02*
Y737552D01*
G01X115532Y732557D02*
X115533Y732559D01*
G01X115531Y732552D02*
X115532Y732557D01*
G01X115531Y732543D02*
Y732552D01*
G01X115532Y727557D02*
X115533Y727559D01*
G01X115531Y727552D02*
X115532Y727557D01*
G01X115531Y727543D02*
Y727552D01*
G01X115532Y722557D02*
X115533Y722559D01*
G01X115531Y722552D02*
X115532Y722557D01*
G01X115531Y722543D02*
Y722552D01*
G01X115532Y717557D02*
X115533Y717559D01*
G01X115531Y717552D02*
X115532Y717557D01*
G01X115531Y717543D02*
Y717552D01*
G01X115532Y712557D02*
X115533Y712559D01*
G01X115531Y712552D02*
X115532Y712557D01*
G01X115531Y712543D02*
Y712552D01*
G01X115532Y707557D02*
X115533Y707559D01*
G01X115531Y707552D02*
X115532Y707557D01*
G01X115531Y707543D02*
Y707552D01*
G01X115532Y702557D02*
X115533Y702559D01*
G01X115531Y702552D02*
X115532Y702557D01*
G01X115531Y702543D02*
Y702552D01*
G01X115532Y697557D02*
X115533Y697559D01*
G01X115531Y697552D02*
X115532Y697557D01*
G01X115531Y697543D02*
Y697552D01*
G01Y698944D02*
Y698954D01*
G01X115532Y698939D02*
X115531Y698944D01*
G01X115533Y698937D02*
X115532Y698939D01*
G01X115531Y703944D02*
Y703954D01*
G01X115532Y703939D02*
X115531Y703944D01*
G01X115533Y703937D02*
X115532Y703939D01*
G01X115531Y708944D02*
Y708954D01*
G01X115532Y708939D02*
X115531Y708944D01*
G01X115533Y708937D02*
X115532Y708939D01*
G01X115531Y713944D02*
Y713954D01*
G01X115532Y713939D02*
X115531Y713944D01*
G01X115533Y713937D02*
X115532Y713939D01*
G01X115531Y718944D02*
Y718954D01*
G01X115532Y718939D02*
X115531Y718944D01*
G01X115533Y718937D02*
X115532Y718939D01*
G01X115531Y723944D02*
Y723954D01*
G01X115532Y723939D02*
X115531Y723944D01*
G01X115533Y723937D02*
X115532Y723939D01*
G01X115531Y728944D02*
Y728954D01*
G01X115532Y728939D02*
X115531Y728944D01*
G01X115533Y728937D02*
X115532Y728939D01*
G01X115531Y733944D02*
Y733954D01*
G01X115532Y733939D02*
X115531Y733944D01*
G01X115533Y733937D02*
X115532Y733939D01*
G01X115531Y738944D02*
Y738954D01*
G01X115532Y738939D02*
X115531Y738944D01*
G01X115533Y738937D02*
X115532Y738939D01*
G01X116508Y699081D02*
X116516Y699055D01*
G01X116498Y699107D02*
X116508Y699081D01*
G01X116487Y699134D02*
X116498Y699107D01*
G01X116508Y704081D02*
X116516Y704055D01*
G01X116498Y704107D02*
X116508Y704081D01*
G01X116487Y704134D02*
X116498Y704107D01*
G01X116508Y709081D02*
X116516Y709055D01*
G01X116498Y709107D02*
X116508Y709081D01*
G01X116487Y709134D02*
X116498Y709107D01*
G01X116508Y714081D02*
X116516Y714055D01*
G01X116498Y714107D02*
X116508Y714081D01*
G01X116487Y714134D02*
X116498Y714107D01*
G01X116508Y719081D02*
X116516Y719055D01*
G01X116498Y719107D02*
X116508Y719081D01*
G01X116487Y719134D02*
X116498Y719107D01*
G01X116508Y724081D02*
X116516Y724055D01*
G01X116498Y724107D02*
X116508Y724081D01*
G01X116487Y724134D02*
X116498Y724107D01*
G01X116508Y729081D02*
X116516Y729055D01*
G01X116498Y729107D02*
X116508Y729081D01*
G01X116487Y729134D02*
X116498Y729107D01*
G01X116508Y734081D02*
X116516Y734055D01*
G01X116498Y734107D02*
X116508Y734081D01*
G01X116487Y734134D02*
X116498Y734107D01*
G01X116508Y739081D02*
X116516Y739055D01*
G01X116498Y739107D02*
X116508Y739081D01*
G01X116487Y739134D02*
X116498Y739107D01*
G01X116508Y744081D02*
X116516Y744055D01*
G01X116498Y744107D02*
X116508Y744081D01*
G01X116487Y744134D02*
X116498Y744107D01*
G01Y698932D02*
X116479Y698937D01*
G01X116513Y698918D02*
X116498Y698932D01*
G01X116518Y698898D02*
X116513Y698918D01*
G01X116498Y703932D02*
X116479Y703937D01*
G01X116513Y703918D02*
X116498Y703932D01*
G01X116518Y703898D02*
X116513Y703918D01*
G01X116498Y708932D02*
X116479Y708937D01*
G01X116513Y708918D02*
X116498Y708932D01*
G01X116518Y708898D02*
X116513Y708918D01*
G01X116498Y713932D02*
X116479Y713937D01*
G01X116513Y713918D02*
X116498Y713932D01*
G01X116518Y713898D02*
X116513Y713918D01*
G01X116498Y718932D02*
X116479Y718937D01*
G01X116513Y718918D02*
X116498Y718932D01*
G01X116518Y718898D02*
X116513Y718918D01*
G01X116498Y723932D02*
X116479Y723937D01*
G01X116513Y723918D02*
X116498Y723932D01*
G01X116518Y723898D02*
X116513Y723918D01*
G01X116498Y728932D02*
X116479Y728937D01*
G01X116513Y728918D02*
X116498Y728932D01*
G01X116518Y728898D02*
X116513Y728918D01*
G01X116498Y733932D02*
X116479Y733937D01*
G01X116513Y733918D02*
X116498Y733932D01*
G01X116518Y733898D02*
X116513Y733918D01*
G01X116498Y738932D02*
X116479Y738937D01*
G01X116513Y738918D02*
X116498Y738932D01*
G01X116518Y738898D02*
X116513Y738918D01*
G01X116498Y743932D02*
X116479Y743937D01*
G01X116513Y743918D02*
X116498Y743932D01*
G01X116518Y743898D02*
X116513Y743918D01*
G01X116516Y698904D02*
Y698911D01*
G01X116517Y698900D02*
X116516Y698904D01*
G01X116518Y698898D02*
X116517Y698900D01*
G01X116516Y703904D02*
Y703911D01*
G01X116517Y703900D02*
X116516Y703904D01*
G01X116518Y703898D02*
X116517Y703900D01*
G01X116516Y708904D02*
Y708911D01*
G01X116517Y708900D02*
X116516Y708904D01*
G01X116518Y708898D02*
X116517Y708900D01*
G01X116516Y713904D02*
Y713911D01*
G01X116517Y713900D02*
X116516Y713904D01*
G01X116518Y713898D02*
X116517Y713900D01*
G01X116516Y718904D02*
Y718911D01*
G01X116517Y718900D02*
X116516Y718904D01*
G01X116518Y718898D02*
X116517Y718900D01*
G01X116516Y723904D02*
Y723911D01*
G01X116517Y723900D02*
X116516Y723904D01*
G01X116518Y723898D02*
X116517Y723900D01*
G01X116516Y728904D02*
Y728911D01*
G01X116517Y728900D02*
X116516Y728904D01*
G01X116518Y728898D02*
X116517Y728900D01*
G01X115531Y743944D02*
Y743954D01*
G01X115532Y743939D02*
X115531Y743944D01*
G01X115533Y743937D02*
X115532Y743939D01*
G01X116516Y742552D02*
Y742543D01*
G01X116517Y742557D02*
X116516Y742552D01*
G01X116519Y742559D02*
X116517Y742557D01*
G01X116516Y737552D02*
Y737543D01*
G01X116517Y737557D02*
X116516Y737552D01*
G01X116519Y737559D02*
X116517Y737557D01*
G01X116516Y732552D02*
Y732543D01*
G01X116517Y732557D02*
X116516Y732552D01*
G01X116519Y732559D02*
X116517Y732557D01*
G01X116516Y727552D02*
Y727543D01*
G01X116517Y727557D02*
X116516Y727552D01*
G01X116519Y727559D02*
X116517Y727557D01*
G01X116516Y722552D02*
Y722543D01*
G01X116517Y722557D02*
X116516Y722552D01*
G01X116519Y722559D02*
X116517Y722557D01*
G01X116516Y717552D02*
Y717543D01*
G01X116517Y717557D02*
X116516Y717552D01*
G01X116519Y717559D02*
X116517Y717557D01*
G01X116516Y712552D02*
Y712543D01*
G01X116517Y712557D02*
X116516Y712552D01*
G01X116519Y712559D02*
X116517Y712557D01*
G01X116516Y733904D02*
Y733911D01*
G01X116517Y733900D02*
X116516Y733904D01*
G01X116518Y733898D02*
X116517Y733900D01*
G01X116516Y738904D02*
Y738911D01*
G01X116517Y738900D02*
X116516Y738904D01*
G01X116518Y738898D02*
X116517Y738900D01*
G01X116516Y743904D02*
Y743911D01*
G01X116517Y743900D02*
X116516Y743904D01*
G01X116518Y743898D02*
X116517Y743900D01*
G01X116516Y707552D02*
Y707543D01*
G01X116517Y707557D02*
X116516Y707552D01*
G01X116519Y707559D02*
X116517Y707557D01*
G01X116516Y702552D02*
Y702543D01*
G01X116517Y702557D02*
X116516Y702552D01*
G01X116519Y702559D02*
X116517Y702557D01*
G01X116516Y697552D02*
Y697543D01*
G01X116517Y697557D02*
X116516Y697552D01*
G01X116519Y697559D02*
X116517Y697557D01*
G01X116503Y698929D02*
X116514Y698913D01*
G01X116479Y698937D02*
X116503Y698929D01*
G01Y703929D02*
X116514Y703913D01*
G01X116479Y703937D02*
X116503Y703929D01*
G01Y708929D02*
X116514Y708913D01*
G01X116479Y708937D02*
X116503Y708929D01*
G01Y713929D02*
X116514Y713913D01*
G01X116479Y713937D02*
X116503Y713929D01*
G01Y718929D02*
X116514Y718913D01*
G01X116479Y718937D02*
X116503Y718929D01*
G01Y723929D02*
X116514Y723913D01*
G01X116479Y723937D02*
X116503Y723929D01*
G01Y728929D02*
X116514Y728913D01*
G01X116479Y728937D02*
X116503Y728929D01*
G01Y733929D02*
X116514Y733913D01*
G01X116479Y733937D02*
X116503Y733929D01*
G01Y738929D02*
X116514Y738913D01*
G01X116479Y738937D02*
X116503Y738929D01*
G01Y743929D02*
X116514Y743913D01*
G01X116479Y743937D02*
X116503Y743929D01*
G01X116516Y744429D02*
X115531D01*
G01X115533Y743937D02*
X120866D01*
G01Y743898D02*
X116518D01*
G01X120866Y742559D02*
X115533D01*
G01X115531Y742067D02*
X116516D01*
G01Y739429D02*
X115531D01*
G01X115533Y738937D02*
X120866D01*
G01Y738898D02*
X116518D01*
G01X120866Y737559D02*
X115533D01*
G01X115531Y737067D02*
X116516D01*
G01Y734429D02*
X115531D01*
G01X115533Y733937D02*
X120866D01*
G01Y733898D02*
X116518D01*
G01X120866Y732559D02*
X115533D01*
G01X115531Y732067D02*
X116516D01*
G01Y729429D02*
X115531D01*
G01X115533Y728937D02*
X120866D01*
G01Y728898D02*
X116518D01*
G01X120866Y727559D02*
X115533D01*
G01X115531Y727067D02*
X116516D01*
G01Y724429D02*
X115531D01*
G01X115533Y723937D02*
X120866D01*
G01Y723898D02*
X116518D01*
G01X120866Y722559D02*
X115533D01*
G01X115531Y722067D02*
X116516D01*
G01Y719429D02*
X115531D01*
G01X115533Y718937D02*
X120866D01*
G01Y718898D02*
X116518D01*
G01X120866Y717559D02*
X115533D01*
G01X115531Y717067D02*
X116516D01*
G01Y714429D02*
X115531D01*
G01X115533Y713937D02*
X120866D01*
G01Y713898D02*
X116518D01*
G01X120866Y712559D02*
X115533D01*
G01X115531Y712067D02*
X116516D01*
G01Y709429D02*
X115531D01*
G01X115533Y708937D02*
X120866D01*
G01Y708898D02*
X116518D01*
G01X120866Y707559D02*
X115533D01*
G01X115531Y707067D02*
X116516D01*
G01X115531Y744133D02*
X116487Y744134D01*
G01X116516Y742363D02*
X115531Y742362D01*
G01Y739133D02*
X116487Y739134D01*
G01X116516Y737363D02*
X115531Y737362D01*
G01Y734133D02*
X116487Y734134D01*
G01X116516Y732363D02*
X115531Y732362D01*
G01Y729133D02*
X116487Y729134D01*
G01X116516Y727363D02*
X115531Y727362D01*
G01Y724133D02*
X116487Y724134D01*
G01X116516Y722363D02*
X115531Y722362D01*
G01Y719133D02*
X116487Y719134D01*
G01X116516Y717363D02*
X115531Y717362D01*
G01Y714133D02*
X116487Y714134D01*
G01X116516Y712363D02*
X115531Y712362D01*
G01Y709133D02*
X116487Y709134D01*
G01X116516Y707363D02*
X115531Y707362D01*
G01X116516Y704429D02*
X115531D01*
G01X115533Y703937D02*
X120866D01*
G01Y703898D02*
X116518D01*
G01X120866Y702559D02*
X115533D01*
G01X115531Y702067D02*
X116516D01*
G01Y699429D02*
X115531D01*
G01X115533Y698937D02*
X120866D01*
G01Y698898D02*
X116518D01*
G01X120866Y697559D02*
X115533D01*
G01X115531Y697067D02*
X116516D01*
G01X115531Y704133D02*
X116487Y704134D01*
G01X116516Y702363D02*
X115531Y702362D01*
G01Y699133D02*
X116487Y699134D01*
G01X116516Y697363D02*
X115531Y697362D01*
G01X116516Y698911D02*
Y698920D01*
G01Y703911D02*
Y703920D01*
G01Y708911D02*
Y708920D01*
G01Y713911D02*
Y713920D01*
G01Y718911D02*
Y718920D01*
G01Y723911D02*
Y723920D01*
G01Y728911D02*
Y728920D01*
G01Y733911D02*
Y733920D01*
G01Y738911D02*
Y738920D01*
G01Y743911D02*
Y743920D01*
G01X117697Y698937D02*
Y697559D01*
G01Y703937D02*
Y702559D01*
G01Y708937D02*
Y707559D01*
G01Y713937D02*
Y712559D01*
G01Y718937D02*
Y717559D01*
G01Y723937D02*
Y722559D01*
G01Y728937D02*
Y727559D01*
G01Y733937D02*
Y732559D01*
G01Y738937D02*
Y737559D01*
G01Y743937D02*
Y742559D01*
G01X116516Y742067D02*
Y744429D01*
G01Y737067D02*
Y739429D01*
G01Y732067D02*
Y734429D01*
G01Y727067D02*
Y729429D01*
G01Y722067D02*
Y724429D01*
G01Y717067D02*
Y719429D01*
G01Y712067D02*
Y714429D01*
G01Y707067D02*
Y709429D01*
G01Y702067D02*
Y704429D01*
G01Y697067D02*
Y699429D01*
G01X115531D02*
Y697067D01*
G01Y704429D02*
Y702067D01*
G01Y709429D02*
Y707067D01*
G01Y714429D02*
Y712067D01*
G01Y719429D02*
Y717067D01*
G01Y724429D02*
Y722067D01*
G01Y729429D02*
Y727067D01*
G01Y734429D02*
Y732067D01*
G01Y739429D02*
Y737067D01*
G01Y744429D02*
Y742067D01*
G01X114961Y769429D02*
G03X114370Y770020I-591J0D01*
G01X107677D02*
G03X107087Y769429I0J-590D01*
G01X109843Y768248D02*
G03Y766280I0J-984D01*
G01X112205D02*
G03Y768248I0J984D01*
G01X121850Y768839D02*
G03X119882Y770807I-1968J0D01*
G01X102165D02*
G03X100197Y768839I0J-1968D01*
G01X108465Y760335D02*
G03X107283Y759154I-1J-1181D01*
G01X114764D02*
G03X113583Y760335I-1181J0D01*
G01X112913Y755059D02*
G03I-1889J0D01*
G01X113386D02*
G03I-2362J0D01*
G01X119882Y770807D02*
X102165D01*
G01X114370Y770020D02*
X107677D01*
G01X112205Y768248D02*
X109843D01*
G01Y766280D02*
X112205D01*
G01X114961Y764902D02*
X107087D01*
G01Y763327D02*
X114961D01*
G01X121850Y760374D02*
X100197D01*
G01X108465Y760335D02*
X113583D01*
G01X109843Y755650D02*
X112205D01*
G01X109843Y753957D02*
X112205D01*
G01X103543Y751988D02*
X117913D01*
G01X103543Y750610D02*
X107283D01*
G01X117913D02*
X114764D01*
G01X103543Y749744D02*
X118504D01*
G01X105315Y748248D02*
X113189D01*
G01X106496Y747067D02*
X112008D01*
G01X121850Y753091D02*
X118504Y749744D01*
G01X112008Y747067D02*
X113189Y748248D01*
G01X105315D02*
X106496Y747067D01*
G01X100197Y753091D02*
X103543Y749744D01*
G01X108539Y751988D02*
X109843Y753957D01*
G01Y755650D02*
X107532Y759879D01*
G01X112205Y753957D02*
X113508Y751988D01*
G01X114515Y759879D02*
X112205Y755650D01*
G01X114961Y763327D02*
Y769429D01*
G01X114764Y759154D02*
Y750610D01*
G01X112205Y755650D02*
Y753957D01*
G01X109843D02*
Y755650D01*
G01X107283Y750610D02*
Y759154D01*
G01X107087Y763327D02*
Y769429D01*
G01X100197Y768839D02*
Y753091D01*
G01X114295Y831641D02*
G03X148106I16905J-13531D01*
G01X114295D02*
G03X121220Y844772I-30737J24602D01*
G01X114295Y831641D02*
G03X148106I16905J-13531D01*
G01X114295D02*
G03X121220Y844772I-30737J24601D01*
G01X73031Y821260D02*
Y827559D01*
G01Y821260D02*
Y827559D01*
G01X116483Y1071791D02*
X116487Y1071890D01*
G01X116477Y1071719D02*
X116483Y1071791D01*
G01X116479Y1071693D02*
X116477Y1071719D01*
G01X116483Y1076791D02*
X116487Y1076890D01*
G01X116477Y1076719D02*
X116483Y1076791D01*
G01X116479Y1076693D02*
X116477Y1076719D01*
G01X116483Y1081791D02*
X116487Y1081890D01*
G01X116477Y1081719D02*
X116483Y1081791D01*
G01X116479Y1081693D02*
X116477Y1081719D01*
G01X115532Y1080313D02*
X115533Y1080315D01*
G01X115531Y1080308D02*
X115532Y1080313D01*
G01X115531Y1080299D02*
Y1080308D01*
G01X115532Y1075313D02*
X115533Y1075315D01*
G01X115531Y1075308D02*
X115532Y1075313D01*
G01X115531Y1075299D02*
Y1075308D01*
G01X115532Y1070313D02*
X115533Y1070315D01*
G01X115531Y1070308D02*
X115532Y1070313D01*
G01X115531Y1070299D02*
Y1070308D01*
G01X116516Y1080308D02*
Y1080299D01*
G01X116517Y1080313D02*
X116516Y1080308D01*
G01X116519Y1080315D02*
X116517Y1080313D01*
G01X116516Y1075308D02*
Y1075299D01*
G01X116517Y1075313D02*
X116516Y1075308D01*
G01X116519Y1075315D02*
X116517Y1075313D01*
G01X116516Y1070308D02*
Y1070299D01*
G01X116517Y1070313D02*
X116516Y1070308D01*
G01X116519Y1070315D02*
X116517Y1070313D01*
G01X116498Y1071688D02*
X116479Y1071693D01*
G01X116513Y1071674D02*
X116498Y1071688D01*
G01X116518Y1071654D02*
X116513Y1071674D01*
G01X116498Y1076688D02*
X116479Y1076693D01*
G01X116513Y1076674D02*
X116498Y1076688D01*
G01X116518Y1076654D02*
X116513Y1076674D01*
G01X116498Y1081688D02*
X116479Y1081693D01*
G01X116513Y1081674D02*
X116498Y1081688D01*
G01X116518Y1081654D02*
X116513Y1081674D01*
G01X115531Y1071700D02*
Y1071709D01*
G01X115532Y1071695D02*
X115531Y1071700D01*
G01X115533Y1071693D02*
X115532Y1071695D01*
G01X115531Y1076700D02*
Y1076709D01*
G01X115532Y1076695D02*
X115531Y1076700D01*
G01X115533Y1076693D02*
X115532Y1076695D01*
G01X115531Y1081700D02*
Y1081709D01*
G01X115532Y1081695D02*
X115531Y1081700D01*
G01X115533Y1081693D02*
X115532Y1081695D01*
G01X116508Y1071837D02*
X116516Y1071811D01*
G01X116498Y1071863D02*
X116508Y1071837D01*
G01X116487Y1071890D02*
X116498Y1071863D01*
G01X116508Y1076837D02*
X116516Y1076811D01*
G01X116498Y1076863D02*
X116508Y1076837D01*
G01X116487Y1076890D02*
X116498Y1076863D01*
G01X116508Y1081837D02*
X116516Y1081811D01*
G01X116498Y1081863D02*
X116508Y1081837D01*
G01X116487Y1081890D02*
X116498Y1081863D01*
G01X116516Y1071660D02*
Y1071667D01*
G01X116517Y1071656D02*
X116516Y1071660D01*
G01X116518Y1071654D02*
X116517Y1071656D01*
G01X116516Y1076660D02*
Y1076667D01*
G01X116517Y1076656D02*
X116516Y1076660D01*
G01X116518Y1076654D02*
X116517Y1076656D01*
G01X116516Y1081660D02*
Y1081667D01*
G01X116517Y1081656D02*
X116516Y1081660D01*
G01X116518Y1081654D02*
X116517Y1081656D01*
G01X116503Y1071685D02*
X116514Y1071669D01*
G01X116479Y1071693D02*
X116503Y1071685D01*
G01Y1076685D02*
X116514Y1076669D01*
G01X116479Y1076693D02*
X116503Y1076685D01*
G01Y1081685D02*
X116514Y1081669D01*
G01X116479Y1081693D02*
X116503Y1081685D01*
G01X107087Y1044823D02*
G03X107677Y1044232I591J0D01*
G01X114370D02*
G03X114961Y1044823I0J591D01*
G01X112205Y1046004D02*
G03Y1047972I0J984D01*
G01X109843D02*
G03Y1046004I0J-984D01*
G01X112126Y1059193D02*
G03I-1102J0D01*
G01X113583Y1053917D02*
G03X114764Y1055098I0J1181D01*
G01X107283D02*
G03X108465Y1053917I1181J0D01*
G01X112598Y1059193D02*
G03I-1574J0D01*
G01X100197Y1045413D02*
G03X102165Y1043445I1968J0D01*
G01X119882D02*
G03X121850Y1045413I0J1968D01*
G01X116516Y1082185D02*
X115531D01*
G01X115533Y1081693D02*
X120866D01*
G01Y1081654D02*
X116518D01*
G01X120866Y1080315D02*
X115533D01*
G01X115531Y1079823D02*
X116516D01*
G01Y1077185D02*
X115531D01*
G01X115533Y1076693D02*
X120866D01*
G01Y1076654D02*
X116518D01*
G01X120866Y1075315D02*
X115533D01*
G01X115531Y1074823D02*
X116516D01*
G01Y1072185D02*
X115531D01*
G01X115533Y1071693D02*
X120866D01*
G01Y1071654D02*
X116518D01*
G01X120866Y1070315D02*
X115533D01*
G01X115531Y1069823D02*
X116516D01*
G01X112008Y1067185D02*
X106496D01*
G01X113189Y1066004D02*
X105315D01*
G01X118504Y1064508D02*
X103543D01*
G01X115531Y1081889D02*
X116487Y1081890D01*
G01X116516Y1080119D02*
X115531Y1080118D01*
G01Y1076889D02*
X116487Y1076890D01*
G01X116516Y1075119D02*
X115531Y1075118D01*
G01Y1071889D02*
X116487Y1071890D01*
G01X116516Y1070119D02*
X115531Y1070118D01*
G01X114764Y1063642D02*
X117913D01*
G01X107283D02*
X103543D01*
G01Y1062264D02*
X117913D01*
G01X112205Y1060295D02*
X109843D01*
G01X112205Y1058602D02*
X109843D01*
G01X113583Y1053917D02*
X108465D01*
G01X121850Y1053878D02*
X100197D01*
G01X114961Y1050925D02*
X107087D01*
G01Y1049350D02*
X114961D01*
G01X112205Y1047972D02*
X109843D01*
G01Y1046004D02*
X112205D01*
G01X114370Y1044232D02*
X107677D01*
G01X119882Y1043445D02*
X102165D01*
G01X118504Y1064508D02*
X121850Y1061161D01*
G01X112008Y1067185D02*
X113189Y1066004D01*
G01X109843Y1060295D02*
X108539Y1062264D01*
G01X112205Y1058602D02*
X114515Y1054373D01*
G01X106496Y1067185D02*
X105315Y1066004D01*
G01X103543Y1064508D02*
X100197Y1061161D01*
G01X113508Y1062264D02*
X112205Y1060295D01*
G01X107532Y1054373D02*
X109843Y1058602D01*
G01X116516Y1071667D02*
Y1071676D01*
G01Y1076667D02*
Y1076676D01*
G01Y1081667D02*
Y1081676D01*
G01X118504Y1202500D02*
Y1064508D01*
G01X117913Y1204744D02*
Y1062264D01*
G01X117697Y1071693D02*
Y1070315D01*
G01Y1076693D02*
Y1075315D01*
G01Y1081693D02*
Y1080315D01*
G01X116516Y1079823D02*
Y1082185D01*
G01Y1074823D02*
Y1077185D01*
G01Y1069823D02*
Y1072185D01*
G01Y1071667D02*
Y1071811D01*
G01Y1081667D02*
Y1081811D01*
G01Y1076667D02*
Y1076811D01*
G01X115531Y1072185D02*
Y1069823D01*
G01Y1077185D02*
Y1074823D01*
G01Y1082185D02*
Y1079823D01*
G01X114961Y1050925D02*
Y1044823D01*
G01X114764Y1063642D02*
Y1055098D01*
G01X113189Y1102461D02*
Y1066004D01*
G01X112205Y1060295D02*
Y1058602D01*
G01X112008Y1103642D02*
Y1067185D01*
G01X109843Y1058602D02*
Y1060295D01*
G01X107283Y1055098D02*
Y1063642D01*
G01X107087Y1050925D02*
Y1044823D01*
G01X106496Y1067185D02*
Y1199823D01*
G01X105315Y1066004D02*
Y1201004D01*
G01X103543Y1101299D02*
Y1062264D01*
G01X100197Y1061161D02*
Y1045413D01*
G01X102106Y1109797D02*
Y1109790D01*
G01X102105Y1109802D02*
X102106Y1109797D01*
G01X102105Y1109795D02*
Y1109802D01*
G01X102106Y1119246D02*
Y1119239D01*
G01X102105Y1119251D02*
X102106Y1119246D01*
G01X102105Y1119244D02*
Y1119251D01*
G01X103050Y1122178D02*
X103051Y1122165D01*
G01X103053Y1122191D02*
X103050Y1122178D01*
G01X103054Y1122204D02*
X103053Y1122191D01*
G01X103050Y1119028D02*
X103051Y1119016D01*
G01X103053Y1119041D02*
X103050Y1119028D01*
G01X103054Y1119055D02*
X103053Y1119041D01*
G01X103050Y1115879D02*
X103051Y1115866D01*
G01X103053Y1115892D02*
X103050Y1115879D01*
G01X103054Y1115905D02*
X103053Y1115892D01*
G01X103050Y1112729D02*
X103051Y1112717D01*
G01X103053Y1112742D02*
X103050Y1112729D01*
G01X103054Y1112756D02*
X103053Y1112742D01*
G01X103050Y1109580D02*
X103051Y1109567D01*
G01X103053Y1109593D02*
X103050Y1109580D01*
G01X103054Y1109606D02*
X103053Y1109593D01*
G01X103050Y1106430D02*
X103051Y1106417D01*
G01X103053Y1106443D02*
X103050Y1106430D01*
G01X103054Y1106456D02*
X103053Y1106443D01*
G01X103050Y1103280D02*
X103051Y1103268D01*
G01X103053Y1103293D02*
X103050Y1103280D01*
G01X103054Y1103307D02*
X103053Y1103293D01*
G01X102106Y1103498D02*
Y1103491D01*
G01X102105Y1103503D02*
X102106Y1103498D01*
G01X102105Y1103496D02*
Y1103503D01*
G01X102119Y1123535D02*
X102143Y1123543D01*
G01X102108Y1123520D02*
X102119Y1123535D01*
G01X102106Y1123514D02*
X102108Y1123520D01*
G01X102119Y1120385D02*
X102143Y1120394D01*
G01X102108Y1120371D02*
X102119Y1120385D01*
G01X102106Y1120364D02*
X102108Y1120371D01*
G01X102119Y1117236D02*
X102143Y1117244D01*
G01X102108Y1117221D02*
X102119Y1117236D01*
G01X102106Y1117215D02*
X102108Y1117221D01*
G01X102119Y1114086D02*
X102143Y1114094D01*
G01X102108Y1114072D02*
X102119Y1114086D01*
G01X102106Y1114065D02*
X102108Y1114072D01*
G01X102119Y1110937D02*
X102143Y1110945D01*
G01X102108Y1110922D02*
X102119Y1110937D01*
G01X102106Y1110915D02*
X102108Y1110922D01*
G01X102119Y1107787D02*
X102143Y1107795D01*
G01X102108Y1107772D02*
X102119Y1107787D01*
G01X102106Y1107766D02*
X102108Y1107772D01*
G01X102119Y1104637D02*
X102143Y1104646D01*
G01X102108Y1104623D02*
X102119Y1104637D01*
G01X102106Y1104616D02*
X102108Y1104623D01*
G01X103091Y1123510D02*
Y1123517D01*
G01X103090Y1123506D02*
X103091Y1123510D01*
G01X103089Y1123504D02*
X103090Y1123506D01*
G01X103091Y1120361D02*
Y1120368D01*
G01X103090Y1120356D02*
X103091Y1120361D01*
G01X103089Y1120354D02*
X103090Y1120356D01*
G01X103091Y1117211D02*
Y1117218D01*
G01X103090Y1117207D02*
X103091Y1117211D01*
G01X103089Y1117205D02*
X103090Y1117207D01*
G01X103091Y1114061D02*
Y1114069D01*
G01X103090Y1114057D02*
X103091Y1114061D01*
G01X103089Y1114055D02*
X103090Y1114057D01*
G01X103091Y1110912D02*
Y1110919D01*
G01X103090Y1110907D02*
X103091Y1110912D01*
G01X103089Y1110906D02*
X103090Y1110907D01*
G01X103091Y1107762D02*
Y1107769D01*
G01X103090Y1107758D02*
X103091Y1107762D01*
G01X103089Y1107756D02*
X103090Y1107758D01*
G01X103091Y1104613D02*
Y1104620D01*
G01X103090Y1104608D02*
X103091Y1104613D01*
G01X103089Y1104606D02*
X103090Y1104608D01*
G01X102106Y1112947D02*
Y1112939D01*
G01X102105Y1112952D02*
X102106Y1112947D01*
G01X102104Y1112949D02*
X102105Y1112952D01*
G01X102106Y1106648D02*
Y1106640D01*
G01X102105Y1106652D02*
X102106Y1106648D01*
G01X102104Y1106650D02*
X102105Y1106652D01*
G01X103051Y1123548D02*
Y1123555D01*
G01X103050Y1123545D02*
X103051Y1123548D01*
G01X103050Y1123543D02*
Y1123545D01*
G01X103051Y1120399D02*
Y1120405D01*
G01X103050Y1120395D02*
X103051Y1120399D01*
G01X103050Y1120394D02*
Y1120395D01*
G01X103051Y1117249D02*
Y1117256D01*
G01X103050Y1117246D02*
X103051Y1117249D01*
G01X103050Y1117244D02*
Y1117246D01*
G01X103051Y1114100D02*
Y1114106D01*
G01X103050Y1114096D02*
X103051Y1114100D01*
G01X103050Y1114094D02*
Y1114096D01*
G01X103051Y1110950D02*
Y1110956D01*
G01X103050Y1110946D02*
X103051Y1110950D01*
G01X103050Y1110945D02*
Y1110946D01*
G01X103051Y1107800D02*
Y1107807D01*
G01X103050Y1107797D02*
X103051Y1107800D01*
G01X103050Y1107795D02*
Y1107797D01*
G01X103051Y1104651D02*
Y1104657D01*
G01X103050Y1104647D02*
X103051Y1104651D01*
G01X103050Y1104646D02*
Y1104647D01*
G01X116483Y1086791D02*
X116487Y1086890D01*
G01X116477Y1086719D02*
X116483Y1086791D01*
G01X116479Y1086693D02*
X116477Y1086719D01*
G01X116483Y1091791D02*
X116487Y1091890D01*
G01X116477Y1091719D02*
X116483Y1091791D01*
G01X116479Y1091693D02*
X116477Y1091719D01*
G01X116483Y1096791D02*
X116487Y1096890D01*
G01X116477Y1096719D02*
X116483Y1096791D01*
G01X116479Y1096693D02*
X116477Y1096719D01*
G01X116483Y1101791D02*
X116487Y1101890D01*
G01X116477Y1101719D02*
X116483Y1101791D01*
G01X116479Y1101693D02*
X116477Y1101719D01*
G01X116483Y1126791D02*
X116487Y1126890D01*
G01X116477Y1126719D02*
X116483Y1126791D01*
G01X116479Y1126693D02*
X116477Y1126719D01*
G01X102106Y1116096D02*
Y1116089D01*
G01X102105Y1116101D02*
X102106Y1116096D01*
G01Y1116092D02*
X102105Y1116101D01*
G01X102146Y1123728D02*
Y1123740D01*
G01X102143Y1123715D02*
X102146Y1123728D01*
G01X102143Y1123701D02*
Y1123715D01*
G01X102146Y1120578D02*
Y1120591D01*
G01X102143Y1120565D02*
X102146Y1120578D01*
G01X102143Y1120552D02*
Y1120565D01*
G01X102146Y1117429D02*
Y1117441D01*
G01X102143Y1117416D02*
X102146Y1117429D01*
G01X102143Y1117402D02*
Y1117416D01*
G01X102146Y1114279D02*
Y1114291D01*
G01X102143Y1114266D02*
X102146Y1114279D01*
G01X102143Y1114252D02*
Y1114266D01*
G01X102146Y1111130D02*
Y1111142D01*
G01X102143Y1111117D02*
X102146Y1111130D01*
G01X102143Y1111103D02*
Y1111117D01*
G01X102146Y1107980D02*
Y1107992D01*
G01X102143Y1107967D02*
X102146Y1107980D01*
G01X102143Y1107953D02*
Y1107967D01*
G01X102146Y1104830D02*
Y1104843D01*
G01X102143Y1104817D02*
X102146Y1104830D01*
G01X102143Y1104804D02*
Y1104817D01*
G01X115532Y1130313D02*
X115533Y1130315D01*
G01X115531Y1130308D02*
X115532Y1130313D01*
G01X115531Y1130299D02*
Y1130308D01*
G01X115532Y1125313D02*
X115533Y1125315D01*
G01X115531Y1125308D02*
X115532Y1125313D01*
G01X115531Y1125299D02*
Y1125308D01*
G01X115532Y1100313D02*
X115533Y1100315D01*
G01X115531Y1100308D02*
X115532Y1100313D01*
G01X115531Y1100299D02*
Y1100308D01*
G01X115532Y1095313D02*
X115533Y1095315D01*
G01X115531Y1095308D02*
X115532Y1095313D01*
G01X115531Y1095299D02*
Y1095308D01*
G01X115532Y1090313D02*
X115533Y1090315D01*
G01X115531Y1090308D02*
X115532Y1090313D01*
G01X115531Y1090299D02*
Y1090308D01*
G01X115532Y1085313D02*
X115533Y1085315D01*
G01X115531Y1085308D02*
X115532Y1085313D01*
G01X115531Y1085299D02*
Y1085308D01*
G01X102106Y1122396D02*
Y1122388D01*
G01X102105Y1122400D02*
X102106Y1122396D01*
G01X102105Y1122393D02*
Y1122400D01*
G01X102143Y1122191D02*
X102142Y1122204D01*
G01X102146Y1122178D02*
X102143Y1122191D01*
G01X102146Y1122165D02*
Y1122178D01*
G01X102143Y1119041D02*
X102142Y1119055D01*
G01X102146Y1119028D02*
X102143Y1119041D01*
G01X102146Y1119016D02*
Y1119028D01*
G01X102143Y1115892D02*
X102142Y1115905D01*
G01X102146Y1115879D02*
X102143Y1115892D01*
G01X102146Y1115866D02*
Y1115879D01*
G01X102143Y1112742D02*
X102142Y1112756D01*
G01X102146Y1112729D02*
X102143Y1112742D01*
G01X102146Y1112717D02*
Y1112729D01*
G01X102143Y1109593D02*
X102142Y1109606D01*
G01X102146Y1109580D02*
X102143Y1109593D01*
G01X102146Y1109567D02*
Y1109580D01*
G01X102143Y1106443D02*
X102142Y1106456D01*
G01X102146Y1106430D02*
X102143Y1106443D01*
G01X102146Y1106417D02*
Y1106430D01*
G01X102143Y1103293D02*
X102142Y1103307D01*
G01X102146Y1103280D02*
X102143Y1103293D01*
G01X102146Y1103268D02*
Y1103280D01*
G01X103054Y1123715D02*
X103055Y1123701D01*
G01X103050Y1123728D02*
X103054Y1123715D01*
G01X103051Y1123740D02*
X103050Y1123728D01*
G01X103054Y1120565D02*
X103055Y1120552D01*
G01X103050Y1120578D02*
X103054Y1120565D01*
G01X103051Y1120591D02*
X103050Y1120578D01*
G01X103054Y1117415D02*
X103055Y1117402D01*
G01X103050Y1117428D02*
X103054Y1117415D01*
G01X103051Y1117441D02*
X103050Y1117428D01*
G01X103054Y1114266D02*
X103055Y1114252D01*
G01X103050Y1114279D02*
X103054Y1114266D01*
G01X103051Y1114291D02*
X103050Y1114279D01*
G01X103054Y1111116D02*
X103055Y1111103D01*
G01X103050Y1111129D02*
X103054Y1111116D01*
G01X103051Y1111142D02*
X103050Y1111129D01*
G01X103054Y1107967D02*
X103055Y1107953D01*
G01X103050Y1107980D02*
X103054Y1107967D01*
G01X103051Y1107992D02*
X103050Y1107980D01*
G01X103054Y1104817D02*
X103055Y1104804D01*
G01X103050Y1104830D02*
X103054Y1104817D01*
G01X103051Y1104843D02*
X103050Y1104830D01*
G01X116516Y1130308D02*
Y1130299D01*
G01X116517Y1130313D02*
X116516Y1130308D01*
G01X116519Y1130315D02*
X116517Y1130313D01*
G01X116516Y1125308D02*
Y1125299D01*
G01X116517Y1125313D02*
X116516Y1125308D01*
G01X116519Y1125315D02*
X116517Y1125313D01*
G01X116516Y1100308D02*
Y1100299D01*
G01X116517Y1100313D02*
X116516Y1100308D01*
G01X116519Y1100315D02*
X116517Y1100313D01*
G01X116516Y1095308D02*
Y1095299D01*
G01X116517Y1095313D02*
X116516Y1095308D01*
G01X116519Y1095315D02*
X116517Y1095313D01*
G01X116516Y1090308D02*
Y1090299D01*
G01X116517Y1090313D02*
X116516Y1090308D01*
G01X116519Y1090315D02*
X116517Y1090313D01*
G01X116516Y1085308D02*
Y1085299D01*
G01X116517Y1085313D02*
X116516Y1085308D01*
G01X116519Y1085315D02*
X116517Y1085313D01*
G01X102106Y1123510D02*
Y1123518D01*
G01X102105Y1123506D02*
X102106Y1123510D01*
G01X102104Y1123504D02*
X102105Y1123506D01*
G01X102106Y1120361D02*
Y1120368D01*
G01X102105Y1120356D02*
X102106Y1120361D01*
G01X102104Y1120354D02*
X102105Y1120356D01*
G01X102106Y1117211D02*
Y1117219D01*
G01X102105Y1117206D02*
X102106Y1117211D01*
G01X102104Y1117205D02*
X102105Y1117206D01*
G01X102106Y1114061D02*
Y1114069D01*
G01X102105Y1114057D02*
X102106Y1114061D01*
G01X102104Y1114055D02*
X102105Y1114057D01*
G01X102106Y1110912D02*
Y1110919D01*
G01X102105Y1110907D02*
X102106Y1110912D01*
G01X102104Y1110906D02*
X102105Y1110907D01*
G01X102106Y1107762D02*
Y1107770D01*
G01X102105Y1107757D02*
X102106Y1107762D01*
G01X102104Y1107756D02*
X102105Y1107757D01*
G01X102106Y1104613D02*
Y1104620D01*
G01X102105Y1104608D02*
X102106Y1104613D01*
G01X102104Y1104606D02*
X102105Y1104608D01*
G01X103088Y1122376D02*
X103091Y1122388D01*
G01X103081Y1122365D02*
X103088Y1122376D01*
G01X103071Y1122356D02*
X103081Y1122365D01*
G01X103088Y1116076D02*
X103091Y1116089D01*
G01X103081Y1116065D02*
X103088Y1116076D01*
G01X103071Y1116057D02*
X103081Y1116065D01*
G01X103088Y1112927D02*
X103091Y1112939D01*
G01X103081Y1112916D02*
X103088Y1112927D01*
G01X103071Y1112907D02*
X103081Y1112916D01*
G01X103088Y1109777D02*
X103091Y1109790D01*
G01X103081Y1109766D02*
X103088Y1109777D01*
G01X103071Y1109758D02*
X103081Y1109766D01*
G01X103083Y1110927D02*
X103076Y1110935D01*
G01X103087Y1110917D02*
X103083Y1110927D01*
G01X103089Y1110906D02*
X103087Y1110917D01*
G01X103083Y1104628D02*
X103076Y1104636D01*
G01X103088Y1104617D02*
X103083Y1104628D01*
G01X103089Y1104606D02*
X103088Y1104617D01*
G01X103083Y1107777D02*
X103076Y1107786D01*
G01X103088Y1107767D02*
X103083Y1107777D01*
G01X103089Y1107756D02*
X103088Y1107767D01*
G01X103083Y1114076D02*
X103076Y1114085D01*
G01X103088Y1114066D02*
X103083Y1114076D01*
G01X103089Y1114055D02*
X103088Y1114066D01*
G01X103083Y1117226D02*
X103076Y1117235D01*
G01X103088Y1117216D02*
X103083Y1117226D01*
G01X103089Y1117205D02*
X103088Y1117216D01*
G01X103083Y1120376D02*
X103076Y1120384D01*
G01X103088Y1120365D02*
X103083Y1120376D01*
G01X103089Y1120354D02*
X103088Y1120365D01*
G01X103083Y1123525D02*
X103076Y1123534D01*
G01X103088Y1123515D02*
X103083Y1123525D01*
G01X103089Y1123504D02*
X103088Y1123515D01*
G01Y1106628D02*
X103091Y1106640D01*
G01X103081Y1106617D02*
X103088Y1106628D01*
G01X103071Y1106608D02*
X103081Y1106617D01*
G01X103088Y1103478D02*
X103091Y1103491D01*
G01X103081Y1103467D02*
X103088Y1103478D01*
G01X103071Y1103459D02*
X103081Y1103467D01*
G01X102145Y1123548D02*
Y1123555D01*
G01Y1123544D02*
Y1123548D01*
G01X102143Y1123543D02*
X102145Y1123544D01*
G01Y1120399D02*
Y1120405D01*
G01Y1120395D02*
Y1120399D01*
G01X102143Y1120394D02*
X102145Y1120395D01*
G01Y1117249D02*
Y1117256D01*
G01Y1117245D02*
Y1117249D01*
G01X102143Y1117244D02*
X102145Y1117245D01*
G01Y1114100D02*
Y1114106D01*
G01Y1114096D02*
Y1114100D01*
G01X102143Y1114094D02*
X102145Y1114096D01*
G01Y1110950D02*
Y1110956D01*
G01Y1110946D02*
Y1110950D01*
G01X102143Y1110945D02*
X102145Y1110946D01*
G01Y1107800D02*
Y1107807D01*
G01Y1107796D02*
Y1107800D01*
G01X102143Y1107795D02*
X102145Y1107796D01*
G01Y1104651D02*
Y1104657D01*
G01Y1104647D02*
Y1104651D01*
G01X102143Y1104646D02*
X102145Y1104647D01*
G01X102107Y1123524D02*
X102106Y1123518D01*
G01X102109Y1123530D02*
X102107Y1123524D01*
G01X102111Y1123536D02*
X102109Y1123530D01*
G01X102115Y1123541D02*
X102111Y1123536D01*
G01X102120Y1123546D02*
X102115Y1123541D01*
G01X102126Y1123550D02*
X102120Y1123546D01*
G01X102107Y1120374D02*
X102106Y1120368D01*
G01X102109Y1120381D02*
X102107Y1120374D01*
G01X102111Y1120386D02*
X102109Y1120381D01*
G01X102115Y1120392D02*
X102111Y1120386D01*
G01X102120Y1120396D02*
X102115Y1120392D01*
G01X102126Y1120400D02*
X102120Y1120396D01*
G01X102107Y1117225D02*
X102106Y1117219D01*
G01X102109Y1117231D02*
X102107Y1117225D01*
G01X102111Y1117237D02*
X102109Y1117231D01*
G01X102115Y1117242D02*
X102111Y1117237D01*
G01X102120Y1117246D02*
X102115Y1117242D01*
G01X102126Y1117250D02*
X102120Y1117246D01*
G01X102107Y1114075D02*
X102106Y1114069D01*
G01X102109Y1114081D02*
X102107Y1114075D01*
G01X102111Y1114087D02*
X102109Y1114081D01*
G01X102115Y1114093D02*
X102111Y1114087D01*
G01X102120Y1114097D02*
X102115Y1114093D01*
G01X102126Y1114101D02*
X102120Y1114097D01*
G01X102107Y1110926D02*
X102106Y1110919D01*
G01X102109Y1110932D02*
X102107Y1110926D01*
G01X102111Y1110937D02*
X102109Y1110932D01*
G01X102115Y1110943D02*
X102111Y1110937D01*
G01X102120Y1110947D02*
X102115Y1110943D01*
G01X102126Y1110951D02*
X102120Y1110947D01*
G01X102107Y1107776D02*
X102106Y1107770D01*
G01X102109Y1107782D02*
X102107Y1107776D01*
G01X102111Y1107788D02*
X102109Y1107782D01*
G01X102115Y1107793D02*
X102111Y1107788D01*
G01X102120Y1107798D02*
X102115Y1107793D01*
G01X102126Y1107802D02*
X102120Y1107798D01*
G01X102107Y1104626D02*
X102106Y1104620D01*
G01X102109Y1104633D02*
X102107Y1104626D01*
G01X102111Y1104638D02*
X102109Y1104633D01*
G01X102115Y1104644D02*
X102111Y1104638D01*
G01X102120Y1104648D02*
X102115Y1104644D01*
G01X102126Y1104652D02*
X102120Y1104648D01*
G01X116498Y1086688D02*
X116479Y1086693D01*
G01X116513Y1086674D02*
X116498Y1086688D01*
G01X116518Y1086654D02*
X116513Y1086674D01*
G01X116498Y1091688D02*
X116479Y1091693D01*
G01X116513Y1091674D02*
X116498Y1091688D01*
G01X116518Y1091654D02*
X116513Y1091674D01*
G01X116498Y1096688D02*
X116479Y1096693D01*
G01X116513Y1096674D02*
X116498Y1096688D01*
G01X116518Y1096654D02*
X116513Y1096674D01*
G01X116498Y1101688D02*
X116479Y1101693D01*
G01X116513Y1101674D02*
X116498Y1101688D01*
G01X116518Y1101654D02*
X116513Y1101674D01*
G01X116498Y1126688D02*
X116479Y1126693D01*
G01X116513Y1126674D02*
X116498Y1126688D01*
G01X116518Y1126654D02*
X116513Y1126674D01*
G01X103062Y1122364D02*
X103050Y1122362D01*
G01X103072Y1122369D02*
X103062Y1122364D01*
G01Y1119215D02*
X103050Y1119213D01*
G01X103072Y1119220D02*
X103062Y1119215D01*
G01Y1116065D02*
X103050Y1116063D01*
G01X103072Y1116070D02*
X103062Y1116065D01*
G01Y1112915D02*
X103050Y1112913D01*
G01X103072Y1112920D02*
X103062Y1112915D01*
G01Y1109766D02*
X103050Y1109764D01*
G01X103072Y1109771D02*
X103062Y1109766D01*
G01Y1106616D02*
X103050Y1106614D01*
G01X103072Y1106621D02*
X103062Y1106616D01*
G01Y1103467D02*
X103050Y1103465D01*
G01X103072Y1103472D02*
X103062Y1103467D01*
G01X103090Y1104627D02*
X103091Y1104620D01*
G01X103088Y1104633D02*
X103090Y1104627D01*
G01X103085Y1104639D02*
X103088Y1104633D01*
G01X103090Y1107776D02*
X103091Y1107770D01*
G01X103088Y1107783D02*
X103090Y1107776D01*
G01X103085Y1107789D02*
X103088Y1107783D01*
G01X103090Y1110926D02*
X103091Y1110919D01*
G01X103088Y1110932D02*
X103090Y1110926D01*
G01X103085Y1110938D02*
X103088Y1110932D01*
G01X103090Y1114076D02*
X103091Y1114069D01*
G01X103088Y1114082D02*
X103090Y1114076D01*
G01X103085Y1114088D02*
X103088Y1114082D01*
G01X103090Y1117225D02*
X103091Y1117219D01*
G01X103088Y1117231D02*
X103090Y1117225D01*
G01X103085Y1117237D02*
X103088Y1117231D01*
G01X103052Y1103459D02*
Y1103454D01*
G01X103050Y1103463D02*
X103052Y1103459D01*
G01X103050Y1103465D02*
Y1103463D01*
G01X103052Y1106609D02*
Y1106603D01*
G01X103050Y1106613D02*
X103052Y1106609D01*
G01X103050Y1106614D02*
Y1106613D01*
G01X103052Y1109759D02*
Y1109753D01*
G01X103050Y1109763D02*
X103052Y1109759D01*
G01X103050Y1109764D02*
Y1109763D01*
G01X103052Y1112908D02*
Y1112902D01*
G01X103050Y1112912D02*
X103052Y1112908D01*
G01X103050Y1112913D02*
Y1112912D01*
G01X103052Y1116058D02*
Y1116052D01*
G01X103050Y1116062D02*
X103052Y1116058D01*
G01X103050Y1116063D02*
Y1116062D01*
G01X103052Y1122357D02*
Y1122351D01*
G01X103050Y1122361D02*
X103052Y1122357D01*
G01X103050Y1122362D02*
Y1122361D01*
G01X115531Y1086700D02*
Y1086709D01*
G01X115532Y1086695D02*
X115531Y1086700D01*
G01X115533Y1086693D02*
X115532Y1086695D01*
G01X115531Y1091700D02*
Y1091709D01*
G01X115532Y1091695D02*
X115531Y1091700D01*
G01X115533Y1091693D02*
X115532Y1091695D01*
G01X115531Y1096700D02*
Y1096709D01*
G01X115532Y1096695D02*
X115531Y1096700D01*
G01X115533Y1096693D02*
X115532Y1096695D01*
G01X115531Y1101700D02*
Y1101709D01*
G01X115532Y1101695D02*
X115531Y1101700D01*
G01X115533Y1101693D02*
X115532Y1101695D01*
G01X115531Y1126700D02*
Y1126709D01*
G01X115532Y1126695D02*
X115531Y1126700D01*
G01X115533Y1126693D02*
X115532Y1126695D01*
G01X116508Y1086837D02*
X116516Y1086811D01*
G01X116498Y1086863D02*
X116508Y1086837D01*
G01X116487Y1086890D02*
X116498Y1086863D01*
G01X116508Y1091837D02*
X116516Y1091811D01*
G01X116498Y1091863D02*
X116508Y1091837D01*
G01X116487Y1091890D02*
X116498Y1091863D01*
G01X116508Y1096837D02*
X116516Y1096811D01*
G01X116498Y1096863D02*
X116508Y1096837D01*
G01X116487Y1096890D02*
X116498Y1096863D01*
G01X116508Y1101837D02*
X116516Y1101811D01*
G01X116498Y1101863D02*
X116508Y1101837D01*
G01X116487Y1101890D02*
X116498Y1101863D01*
G01X116508Y1126837D02*
X116516Y1126811D01*
G01X116498Y1126863D02*
X116508Y1126837D01*
G01X116487Y1126890D02*
X116498Y1126863D01*
G01X102124Y1112919D02*
X102143Y1112913D01*
G01X102111Y1112931D02*
X102124Y1112919D01*
G01X102104Y1112949D02*
X102111Y1112931D01*
G01X102129Y1106617D02*
X102143Y1106614D01*
G01X102118Y1106624D02*
X102129Y1106617D01*
G01X102106Y1106643D02*
X102118Y1106624D01*
G01X102129Y1116066D02*
X102143Y1116063D01*
G01X102117Y1116073D02*
X102129Y1116066D01*
G01X102106Y1116091D02*
X102117Y1116073D01*
G01X102129Y1109767D02*
X102143Y1109764D01*
G01X102117Y1109774D02*
X102129Y1109767D01*
G01X102105Y1109794D02*
X102117Y1109774D01*
G01X102129Y1119215D02*
X102143Y1119213D01*
G01X102117Y1119223D02*
X102129Y1119215D01*
G01X102105Y1119243D02*
X102117Y1119223D01*
G01X103091Y1103498D02*
Y1103491D01*
G01X103090Y1103503D02*
X103091Y1103498D01*
G01X103089Y1103504D02*
X103090Y1103503D01*
G01X103091Y1106648D02*
Y1106640D01*
G01X103090Y1106652D02*
X103091Y1106648D01*
G01X103089Y1106654D02*
X103090Y1106652D01*
G01X103091Y1109797D02*
Y1109790D01*
G01X103090Y1109802D02*
X103091Y1109797D01*
G01X103089Y1109803D02*
X103090Y1109802D01*
G01X103091Y1112947D02*
Y1112939D01*
G01X103090Y1112952D02*
X103091Y1112947D01*
G01X103089Y1112953D02*
X103090Y1112952D01*
G01X103091Y1116096D02*
Y1116089D01*
G01X103090Y1116101D02*
X103091Y1116096D01*
G01X103089Y1116102D02*
X103090Y1116101D01*
G01X103091Y1119246D02*
Y1119239D01*
G01X103090Y1119251D02*
X103091Y1119246D01*
G01X103089Y1119252D02*
X103090Y1119251D01*
G01X103091Y1122396D02*
Y1122388D01*
G01X103090Y1122400D02*
X103091Y1122396D01*
G01X103089Y1122402D02*
X103090Y1122400D01*
G01X102129Y1122365D02*
X102143Y1122362D01*
G01X102116Y1122373D02*
X102129Y1122365D01*
G01X102105Y1122393D02*
X102116Y1122373D01*
G01X102128Y1103468D02*
X102143Y1103465D01*
G01X102115Y1103476D02*
X102128Y1103468D01*
G01X102105Y1103496D02*
X102115Y1103476D01*
G01X103090Y1120375D02*
X103091Y1120368D01*
G01X103088Y1120381D02*
X103090Y1120375D01*
G01X103085Y1120387D02*
X103088Y1120381D01*
G01X103090Y1123524D02*
X103091Y1123518D01*
G01X103088Y1123531D02*
X103090Y1123524D01*
G01X103085Y1123537D02*
X103088Y1123531D01*
G01X116516Y1086660D02*
Y1086667D01*
G01X116517Y1086656D02*
X116516Y1086660D01*
G01X116518Y1086654D02*
X116517Y1086656D01*
G01X116516Y1091660D02*
Y1091667D01*
G01X116517Y1091656D02*
X116516Y1091660D01*
G01X116518Y1091654D02*
X116517Y1091656D01*
G01X116516Y1096660D02*
Y1096667D01*
G01X116517Y1096656D02*
X116516Y1096660D01*
G01X116518Y1096654D02*
X116517Y1096656D01*
G01X116516Y1101660D02*
Y1101667D01*
G01X116517Y1101656D02*
X116516Y1101660D01*
G01X116518Y1101654D02*
X116517Y1101656D01*
G01X116516Y1126660D02*
Y1126667D01*
G01X116517Y1126656D02*
X116516Y1126660D01*
G01X116518Y1126654D02*
X116517Y1126656D01*
G01X102145Y1103460D02*
X102146Y1103454D01*
G01X102144Y1103463D02*
X102145Y1103460D01*
G01X102143Y1103465D02*
X102144Y1103463D01*
G01X102145Y1106609D02*
X102146Y1106603D01*
G01X102144Y1106613D02*
X102145Y1106609D01*
G01X102143Y1106614D02*
X102144Y1106613D01*
G01X102145Y1109759D02*
X102146Y1109753D01*
G01X102144Y1109763D02*
X102145Y1109759D01*
G01X102143Y1109764D02*
X102144Y1109763D01*
G01X102145Y1112909D02*
X102146Y1112902D01*
G01X102144Y1112912D02*
X102145Y1112909D01*
G01X102143Y1112913D02*
X102144Y1112912D01*
G01X102145Y1116058D02*
X102146Y1116052D01*
G01X102144Y1116062D02*
X102145Y1116058D01*
G01X102143Y1116063D02*
X102144Y1116062D01*
G01X102145Y1119208D02*
X102146Y1119202D01*
G01X102144Y1119211D02*
X102145Y1119208D01*
G01X102143Y1119213D02*
X102144Y1119211D01*
G01X102145Y1122357D02*
X102146Y1122351D01*
G01X102144Y1122361D02*
X102145Y1122357D01*
G01X102143Y1122362D02*
X102144Y1122361D01*
G01X103059Y1110944D02*
X103050Y1110945D01*
G01X103068Y1110941D02*
X103059Y1110944D01*
G01X103076Y1110935D02*
X103068Y1110941D01*
G01X103059Y1104644D02*
X103050Y1104646D01*
G01X103068Y1104641D02*
X103059Y1104644D01*
G01X103076Y1104636D02*
X103068Y1104641D01*
G01X103059Y1107794D02*
X103050Y1107795D01*
G01X103068Y1107791D02*
X103059Y1107794D01*
G01X103076Y1107786D02*
X103068Y1107791D01*
G01X103059Y1114093D02*
X103050Y1114094D01*
G01X103068Y1114090D02*
X103059Y1114093D01*
G01X103076Y1114085D02*
X103068Y1114090D01*
G01X103059Y1117243D02*
X103050Y1117244D01*
G01X103068Y1117240D02*
X103059Y1117243D01*
G01X103076Y1117235D02*
X103068Y1117240D01*
G01X103059Y1120393D02*
X103050Y1120394D01*
G01X103068Y1120389D02*
X103059Y1120393D01*
G01X103076Y1120384D02*
X103068Y1120389D01*
G01X103059Y1123542D02*
X103050Y1123543D01*
G01X103068Y1123539D02*
X103059Y1123542D01*
G01X103076Y1123534D02*
X103068Y1123539D01*
G01X116503Y1086685D02*
X116514Y1086669D01*
G01X116479Y1086693D02*
X116503Y1086685D01*
G01Y1091685D02*
X116514Y1091669D01*
G01X116479Y1091693D02*
X116503Y1091685D01*
G01X102106Y1112943D02*
Y1112939D01*
G01X102107Y1112938D02*
X102106Y1112943D01*
G01X102118Y1112923D02*
X102107Y1112938D01*
G01X102141Y1112914D02*
X102118Y1112923D01*
G01X102106Y1106644D02*
Y1106640D01*
G01X102108Y1106638D02*
X102106Y1106644D01*
G01X102120Y1106622D02*
X102108Y1106638D01*
G01X102144Y1106614D02*
X102120Y1106622D01*
G01X102106Y1109794D02*
Y1109790D01*
G01X102108Y1109787D02*
X102106Y1109794D01*
G01X102119Y1109772D02*
X102108Y1109787D01*
G01X102144Y1109764D02*
X102119Y1109772D01*
G01X102106Y1116093D02*
Y1116089D01*
G01X102108Y1116087D02*
X102106Y1116093D01*
G01X102119Y1116071D02*
X102108Y1116087D01*
G01X102144Y1116063D02*
X102119Y1116071D01*
G01X102106Y1119243D02*
Y1119239D01*
G01X102108Y1119236D02*
X102106Y1119243D01*
G01X102119Y1119221D02*
X102108Y1119236D01*
G01X102144Y1119213D02*
X102119Y1119221D01*
G01X102106Y1103494D02*
Y1103491D01*
G01X102108Y1103488D02*
X102106Y1103494D01*
G01X102119Y1103473D02*
X102108Y1103488D01*
G01X102144Y1103465D02*
X102119Y1103473D01*
G01X102106Y1122392D02*
Y1122388D01*
G01X102108Y1122386D02*
X102106Y1122392D01*
G01X102119Y1122370D02*
X102108Y1122386D01*
G01X102144Y1122362D02*
X102119Y1122370D01*
G01X116503Y1096685D02*
X116514Y1096669D01*
G01X116479Y1096693D02*
X116503Y1096685D01*
G01Y1101685D02*
X116514Y1101669D01*
G01X116479Y1101693D02*
X116503Y1101685D01*
G01Y1126685D02*
X116514Y1126669D01*
G01X116479Y1126693D02*
X116503Y1126685D01*
G01X103081Y1104644D02*
X103085Y1104639D01*
G01X103076Y1104648D02*
X103081Y1104644D01*
G01X103070Y1104652D02*
X103076Y1104648D01*
G01X103065Y1104655D02*
X103070Y1104652D01*
G01X103058Y1104657D02*
X103065Y1104655D01*
G01X103051Y1104657D02*
X103058D01*
G01X103081Y1107794D02*
X103085Y1107789D01*
G01X103076Y1107798D02*
X103081Y1107794D01*
G01X103070Y1107802D02*
X103076Y1107798D01*
G01X103065Y1107804D02*
X103070Y1107802D01*
G01X103058Y1107806D02*
X103065Y1107804D01*
G01X103051Y1107807D02*
X103058Y1107806D01*
G01X103081Y1110943D02*
X103085Y1110938D01*
G01X103076Y1110948D02*
X103081Y1110943D01*
G01X103070Y1110952D02*
X103076Y1110948D01*
G01X103065Y1110954D02*
X103070Y1110952D01*
G01X103058Y1110956D02*
X103065Y1110954D01*
G01X103051Y1110956D02*
X103058D01*
G01X103081Y1114093D02*
X103085Y1114088D01*
G01X103076Y1114097D02*
X103081Y1114093D01*
G01X103070Y1114101D02*
X103076Y1114097D01*
G01X103065Y1114104D02*
X103070Y1114101D01*
G01X103058Y1114106D02*
X103065Y1114104D01*
G01X103051Y1114106D02*
X103058D01*
G01X103081Y1117243D02*
X103085Y1117237D01*
G01X103076Y1117247D02*
X103081Y1117243D01*
G01X103070Y1117251D02*
X103076Y1117247D01*
G01X103065Y1117253D02*
X103070Y1117251D01*
G01X103058Y1117255D02*
X103065Y1117253D01*
G01X103051Y1117256D02*
X103058Y1117255D01*
G01X103081Y1120392D02*
X103085Y1120387D01*
G01X103076Y1120396D02*
X103081Y1120392D01*
G01X103070Y1120400D02*
X103076Y1120396D01*
G01X103065Y1120403D02*
X103070Y1120400D01*
G01X103058Y1120405D02*
X103065Y1120403D01*
G01X103051Y1120405D02*
X103058D01*
G01X103081Y1123542D02*
X103085Y1123537D01*
G01X103076Y1123546D02*
X103081Y1123542D01*
G01X103070Y1123550D02*
X103076Y1123546D01*
G01X103065Y1123552D02*
X103070Y1123550D01*
G01X103058Y1123554D02*
X103065Y1123552D01*
G01X103051Y1123555D02*
X103058Y1123554D01*
G01X102107Y1103483D02*
X102106Y1103491D01*
G01X102109Y1103476D02*
X102107Y1103483D01*
G01X102113Y1103470D02*
X102109Y1103476D01*
G01X102118Y1103464D02*
X102113Y1103470D01*
G01X102124Y1103459D02*
X102118Y1103464D01*
G01X102131Y1103456D02*
X102124Y1103459D01*
G01X102138Y1103454D02*
X102131Y1103456D01*
G01X102146Y1103454D02*
X102138D01*
G01X102107Y1106633D02*
X102106Y1106640D01*
G01X102109Y1106626D02*
X102107Y1106633D01*
G01X102113Y1106620D02*
X102109Y1106626D01*
G01X102118Y1106614D02*
X102113Y1106620D01*
G01X102124Y1106609D02*
X102118Y1106614D01*
G01X102131Y1106606D02*
X102124Y1106609D01*
G01X102138Y1106604D02*
X102131Y1106606D01*
G01X102146Y1106603D02*
X102138Y1106604D01*
G01X102107Y1109782D02*
X102106Y1109790D01*
G01X102109Y1109776D02*
X102107Y1109782D01*
G01X102113Y1109769D02*
X102109Y1109776D01*
G01X102118Y1109763D02*
X102113Y1109769D01*
G01X102124Y1109759D02*
X102118Y1109763D01*
G01X102131Y1109756D02*
X102124Y1109759D01*
G01X102138Y1109754D02*
X102131Y1109756D01*
G01X102146Y1109753D02*
X102138Y1109754D01*
G01X102107Y1112932D02*
X102106Y1112939D01*
G01X102109Y1112925D02*
X102107Y1112932D01*
G01X102113Y1112919D02*
X102109Y1112925D01*
G01X102118Y1112913D02*
X102113Y1112919D01*
G01X102124Y1112908D02*
X102118Y1112913D01*
G01X102131Y1112905D02*
X102124Y1112908D01*
G01X102138Y1112903D02*
X102131Y1112905D01*
G01X102146Y1112902D02*
X102138Y1112903D01*
G01X102107Y1116081D02*
X102106Y1116089D01*
G01X102109Y1116075D02*
X102107Y1116081D01*
G01X102113Y1116069D02*
X102109Y1116075D01*
G01X102118Y1116063D02*
X102113Y1116069D01*
G01X102124Y1116058D02*
X102118Y1116063D01*
G01X102131Y1116055D02*
X102124Y1116058D01*
G01X102138Y1116053D02*
X102131Y1116055D01*
G01X102146Y1116052D02*
X102138Y1116053D01*
G01X102107Y1119231D02*
X102106Y1119239D01*
G01X102109Y1119224D02*
X102107Y1119231D01*
G01X102113Y1119218D02*
X102109Y1119224D01*
G01X102118Y1119212D02*
X102113Y1119218D01*
G01X102124Y1119207D02*
X102118Y1119212D01*
G01X102131Y1119204D02*
X102124Y1119207D01*
G01X102138Y1119202D02*
X102131Y1119204D01*
G01X102146Y1119202D02*
X102138D01*
G01X102107Y1122381D02*
X102106Y1122388D01*
G01X102109Y1122374D02*
X102107Y1122381D01*
G01X102113Y1122368D02*
X102109Y1122374D01*
G01X102118Y1122362D02*
X102113Y1122368D01*
G01X102124Y1122357D02*
X102118Y1122362D01*
G01X102131Y1122354D02*
X102124Y1122357D01*
G01X102138Y1122352D02*
X102131Y1122354D01*
G01X102146Y1122351D02*
X102138Y1122352D01*
G01X103060Y1104644D02*
X103070Y1104640D01*
G01X103050Y1104646D02*
X103060Y1104644D01*
G01Y1107794D02*
X103070Y1107790D01*
G01X103050Y1107795D02*
X103060Y1107794D01*
G01Y1110944D02*
X103070Y1110939D01*
G01X103050Y1110945D02*
X103060Y1110944D01*
G01Y1114093D02*
X103070Y1114089D01*
G01X103050Y1114094D02*
X103060Y1114093D01*
G01Y1117243D02*
X103070Y1117239D01*
G01X103050Y1117244D02*
X103060Y1117243D01*
G01Y1120393D02*
X103070Y1120388D01*
G01X103050Y1120394D02*
X103060Y1120393D01*
G01Y1123542D02*
X103070Y1123538D01*
G01X103050Y1123543D02*
X103060Y1123542D01*
G01X103068Y1103457D02*
X103071Y1103459D01*
G01X103065Y1103456D02*
X103068Y1103457D01*
G01X103062Y1103455D02*
X103065Y1103456D01*
G01X103058Y1103454D02*
X103062Y1103455D01*
G01X103055Y1103454D02*
X103058D01*
G01X103051D02*
X103055D01*
G01X102129Y1104654D02*
X102126Y1104652D01*
G01X102132Y1104655D02*
X102129Y1104654D01*
G01X102135Y1104656D02*
X102132Y1104655D01*
G01X102139Y1104656D02*
X102135D01*
G01X102142Y1104657D02*
X102139Y1104656D01*
G01X102146Y1104657D02*
X102142D01*
G01X103068Y1106607D02*
X103071Y1106608D01*
G01X103065Y1106606D02*
X103068Y1106607D01*
G01X103062Y1106604D02*
X103065Y1106606D01*
G01X103058Y1106604D02*
X103062D01*
G01X103055Y1106603D02*
X103058Y1106604D01*
G01X103051Y1106603D02*
X103055D01*
G01X102129Y1107803D02*
X102126Y1107802D01*
G01X102132Y1107804D02*
X102129Y1107803D01*
G01X102135Y1107806D02*
X102132Y1107804D01*
G01X102139Y1107806D02*
X102135D01*
G01X102142Y1107807D02*
X102139Y1107806D01*
G01X102146Y1107807D02*
X102142D01*
G01X103068Y1109756D02*
X103071Y1109758D01*
G01X103065Y1109755D02*
X103068Y1109756D01*
G01X103062Y1109754D02*
X103065Y1109755D01*
G01X103058Y1109753D02*
X103062Y1109754D01*
G01X103055Y1109753D02*
X103058D01*
G01X103051D02*
X103055D01*
G01X102129Y1110953D02*
X102126Y1110951D01*
G01X102132Y1110954D02*
X102129Y1110953D01*
G01X102135Y1110955D02*
X102132Y1110954D01*
G01X102139Y1110956D02*
X102135Y1110955D01*
G01X102142Y1110956D02*
X102139D01*
G01X102146D02*
X102142D01*
G01X103068Y1112906D02*
X103071Y1112907D01*
G01X103065Y1112905D02*
X103068Y1112906D01*
G01X103062Y1112904D02*
X103065Y1112905D01*
G01X103058Y1112903D02*
X103062Y1112904D01*
G01X103055Y1112902D02*
X103058Y1112903D01*
G01X103051Y1112902D02*
X103055D01*
G01X102129Y1114102D02*
X102126Y1114101D01*
G01X102132Y1114104D02*
X102129Y1114102D01*
G01X102135Y1114105D02*
X102132Y1114104D01*
G01X102139Y1114105D02*
X102135D01*
G01X102142Y1114106D02*
X102139Y1114105D01*
G01X102146Y1114106D02*
X102142D01*
G01X103068Y1116056D02*
X103071Y1116057D01*
G01X103065Y1116054D02*
X103068Y1116056D01*
G01X103062Y1116053D02*
X103065Y1116054D01*
G01X103058Y1116052D02*
X103062Y1116053D01*
G01X103055Y1116052D02*
X103058D01*
G01X103051D02*
X103055D01*
G01X102129Y1117252D02*
X102126Y1117250D01*
G01X102132Y1117253D02*
X102129Y1117252D01*
G01X102135Y1117254D02*
X102132Y1117253D01*
G01X102139Y1117255D02*
X102135Y1117254D01*
G01X102142Y1117256D02*
X102139Y1117255D01*
G01X102146Y1117256D02*
X102142D01*
G01X101359Y1106654D02*
X100925D01*
G01X101733D02*
X101359D01*
G01Y1112953D02*
X100925D01*
G01X101733D02*
X101359D01*
G01Y1116102D02*
X100925D01*
G01X101732D02*
X101359D01*
G01X103090Y1119231D02*
X103091Y1119239D01*
G01X103087Y1119224D02*
X103090Y1119231D01*
G01X103084Y1119218D02*
X103087Y1119224D01*
G01X103079Y1119212D02*
X103084Y1119218D01*
G01X103073Y1119207D02*
X103079Y1119212D01*
G01X103066Y1119204D02*
X103073Y1119207D01*
G01X103059Y1119202D02*
X103066Y1119204D01*
G01X103051Y1119202D02*
X103059D01*
G01X102129Y1120402D02*
X102126Y1120400D01*
G01X102132Y1120403D02*
X102129Y1120402D01*
G01X102135Y1120404D02*
X102132Y1120403D01*
G01X102139Y1120404D02*
X102135D01*
G01X102142Y1120405D02*
X102139Y1120404D01*
G01X102146Y1120405D02*
X102142D01*
G01X103068Y1122355D02*
X103071Y1122356D01*
G01X103065Y1122354D02*
X103068Y1122355D01*
G01X103062Y1122352D02*
X103065Y1122354D01*
G01X103058Y1122352D02*
X103062D01*
G01X103055Y1122351D02*
X103058Y1122352D01*
G01X103051Y1122351D02*
X103055D01*
G01X102129Y1123551D02*
X102126Y1123550D01*
G01X102132Y1123552D02*
X102129Y1123551D01*
G01X102135Y1123554D02*
X102132Y1123552D01*
G01X102139Y1123554D02*
X102135D01*
G01X102142Y1123555D02*
X102139Y1123554D01*
G01X102146Y1123555D02*
X102142D01*
G01X102109Y1104626D02*
X102104Y1104606D01*
G01X102124Y1104641D02*
X102109Y1104626D01*
G01X102143Y1104646D02*
X102124Y1104641D01*
G01X102109Y1107776D02*
X102104Y1107756D01*
G01X102124Y1107790D02*
X102109Y1107776D01*
G01X102143Y1107795D02*
X102124Y1107790D01*
G01X102109Y1110925D02*
X102104Y1110906D01*
G01X102124Y1110940D02*
X102109Y1110925D01*
G01X102143Y1110945D02*
X102124Y1110940D01*
G01X102109Y1114075D02*
X102104Y1114055D01*
G01X102124Y1114089D02*
X102109Y1114075D01*
G01X102143Y1114094D02*
X102124Y1114089D01*
G01X102109Y1117224D02*
X102104Y1117205D01*
G01X102124Y1117239D02*
X102109Y1117224D01*
G01X102143Y1117244D02*
X102124Y1117239D01*
G01X103084Y1103484D02*
X103089Y1103504D01*
G01X103069Y1103470D02*
X103084Y1103484D01*
G01X103050Y1103465D02*
X103069Y1103470D01*
G01X103084Y1106634D02*
X103089Y1106654D01*
G01X103069Y1106620D02*
X103084Y1106634D01*
G01X103050Y1106614D02*
X103069Y1106620D01*
G01X103084Y1109783D02*
X103089Y1109803D01*
G01X103069Y1109769D02*
X103084Y1109783D01*
G01X103050Y1109764D02*
X103069Y1109769D01*
G01X103084Y1112933D02*
X103089Y1112953D01*
G01X103069Y1112919D02*
X103084Y1112933D01*
G01X103050Y1112913D02*
X103069Y1112919D01*
G01X103084Y1116083D02*
X103089Y1116102D01*
G01X103069Y1116069D02*
X103084Y1116083D01*
G01X103050Y1116063D02*
X103069Y1116069D01*
G01X103084Y1119232D02*
X103089Y1119252D01*
G01X103069Y1119218D02*
X103084Y1119232D01*
G01X103050Y1119213D02*
X103069Y1119218D01*
G01X102109Y1120374D02*
X102104Y1120354D01*
G01X102124Y1120389D02*
X102109Y1120374D01*
G01X102143Y1120394D02*
X102124Y1120389D01*
G01X102109Y1123524D02*
X102104Y1123504D01*
G01X102124Y1123538D02*
X102109Y1123524D01*
G01X102143Y1123543D02*
X102124Y1123538D01*
G01X103084Y1122382D02*
X103089Y1122402D01*
G01X103069Y1122368D02*
X103084Y1122382D01*
G01X103050Y1122362D02*
X103069Y1122368D01*
G01X102104Y1112949D02*
X101993Y1112953D01*
G01X102104Y1106650D02*
X101993Y1106654D01*
G01X102104Y1116099D02*
X101993Y1116102D01*
G01X120866Y1130315D02*
X115533D01*
G01X115531Y1129823D02*
X116516D01*
G01Y1127185D02*
X115531D01*
G01X115533Y1126693D02*
X120866D01*
G01Y1126654D02*
X116518D01*
G01X103543Y1125709D02*
X100197D01*
G01X120866Y1125315D02*
X115533D01*
G01X115531Y1124823D02*
X116516D01*
G01X113189Y1124547D02*
X117126D01*
G01X103051Y1123740D02*
X102146D01*
G01X103091Y1123701D02*
X102106D01*
G01X103050Y1123543D02*
X97165D01*
G01Y1123504D02*
X103089D01*
G01X112008Y1123366D02*
X115945D01*
G01X103089Y1122402D02*
X97165D01*
G01X103050Y1122362D02*
X97165D01*
G01X102106Y1122205D02*
X103091D01*
G01X102146Y1122165D02*
X103051D01*
G01Y1120591D02*
X102146D01*
G01X103091Y1120551D02*
X102106D01*
G01X103050Y1120394D02*
X97165D01*
G01Y1120354D02*
X103089D01*
G01Y1119252D02*
X97165D01*
G01X103050Y1119213D02*
X97165D01*
G01X102106Y1119055D02*
X103091D01*
G01X102146Y1119016D02*
X103051D01*
G01Y1117441D02*
X102146D01*
G01X103091Y1117402D02*
X102106D01*
G01X103050Y1117244D02*
X97165D01*
G01Y1117205D02*
X103089D01*
G01Y1116102D02*
X97165D01*
G01X103050Y1116063D02*
X97165D01*
G01X102106Y1115906D02*
X103091D01*
G01X102146Y1115866D02*
X103051D01*
G01Y1114291D02*
X102146D01*
G01X103091Y1114252D02*
X102106D01*
G01X103050Y1114094D02*
X97165D01*
G01Y1114055D02*
X103089D01*
G01Y1112953D02*
X97165D01*
G01X103050Y1112913D02*
X97165D01*
G01X102106Y1112756D02*
X103091D01*
G01X102146Y1112717D02*
X103051D01*
G01Y1111142D02*
X102146D01*
G01X103091Y1111102D02*
X102106D01*
G01X103050Y1110945D02*
X97165D01*
G01Y1110906D02*
X103089D01*
G01Y1109803D02*
X97165D01*
G01X103050Y1109764D02*
X97165D01*
G01X102106Y1109606D02*
X103091D01*
G01X102146Y1109567D02*
X103051D01*
G01Y1107992D02*
X102146D01*
G01X103091Y1107953D02*
X102106D01*
G01X103050Y1107795D02*
X97165D01*
G01Y1107756D02*
X103089D01*
G01Y1106654D02*
X97165D01*
G01X103050Y1106614D02*
X97165D01*
G01X102106Y1106457D02*
X103091D01*
G01X102146Y1106417D02*
X103051D01*
G01Y1104843D02*
X102146D01*
G01X103091Y1104803D02*
X102106D01*
G01X103050Y1104646D02*
X97165D01*
G01Y1104606D02*
X103089D01*
G01X115945Y1103642D02*
X112008D01*
G01X103089Y1103504D02*
X97165D01*
G01X103050Y1103465D02*
X97165D01*
G01X102106Y1103307D02*
X103091D01*
G01X102146Y1103268D02*
X103051D01*
G01X117126Y1102461D02*
X113189D01*
G01X116516Y1102185D02*
X115531D01*
G01X115533Y1101693D02*
X120866D01*
G01Y1101654D02*
X116518D01*
G01X103543Y1101299D02*
X100197D01*
G01X120866Y1100315D02*
X115533D01*
G01X115531Y1099823D02*
X116516D01*
G01Y1097185D02*
X115531D01*
G01X115533Y1096693D02*
X120866D01*
G01Y1096654D02*
X116518D01*
G01X120866Y1095315D02*
X115533D01*
G01X115531Y1094823D02*
X116516D01*
G01Y1092185D02*
X115531D01*
G01X115533Y1091693D02*
X120866D01*
G01Y1091654D02*
X116518D01*
G01X120866Y1090315D02*
X115533D01*
G01X115531Y1089823D02*
X116516D01*
G01Y1087185D02*
X115531D01*
G01X115533Y1086693D02*
X120866D01*
G01Y1086654D02*
X116518D01*
G01X120866Y1085315D02*
X115533D01*
G01X115531Y1084823D02*
X116516D01*
G01Y1130119D02*
X115531Y1130118D01*
G01Y1126889D02*
X116487Y1126890D01*
G01X116516Y1125119D02*
X115531Y1125118D01*
G01Y1101889D02*
X116487Y1101890D01*
G01X116516Y1100119D02*
X115531Y1100118D01*
G01Y1096889D02*
X116487Y1096890D01*
G01X116516Y1095119D02*
X115531Y1095118D01*
G01Y1091889D02*
X116487Y1091890D01*
G01X116516Y1090119D02*
X115531Y1090118D01*
G01Y1086889D02*
X116487Y1086890D01*
G01X116516Y1085119D02*
X115531Y1085118D01*
G01X101993Y1122402D02*
X102105Y1122393D01*
G01X115945Y1103642D02*
X117126Y1102461D01*
G01X112008Y1103642D02*
X113189Y1102461D01*
G01X103050Y1119213D02*
X103053Y1119202D01*
G01X115945Y1123366D02*
X117126Y1124547D01*
G01X112008Y1123366D02*
X113189Y1124547D01*
G01X103090Y1104609D02*
X103091Y1104620D01*
G01X103090Y1107758D02*
X103091Y1107769D01*
G01X103090Y1110908D02*
X103091Y1110919D01*
G01X103090Y1114057D02*
X103091Y1114069D01*
G01X103090Y1117207D02*
X103091Y1117218D01*
G01X103090Y1120357D02*
X103091Y1120368D01*
G01X103090Y1123506D02*
X103091Y1123517D01*
G01X116516Y1086667D02*
Y1086676D01*
G01Y1091667D02*
Y1091676D01*
G01Y1096667D02*
Y1096676D01*
G01Y1101667D02*
Y1101676D01*
G01Y1126667D02*
Y1126676D01*
G01X117697Y1086693D02*
Y1085315D01*
G01Y1091693D02*
Y1090315D01*
G01Y1096693D02*
Y1095315D01*
G01Y1101693D02*
Y1100315D01*
G01Y1126693D02*
Y1125315D01*
G01Y1131693D02*
Y1130315D01*
G01X117126Y1124547D02*
Y1102461D01*
G01X116516Y1129823D02*
Y1132185D01*
G01Y1124823D02*
Y1127185D01*
G01Y1099823D02*
Y1102185D01*
G01Y1094823D02*
Y1097185D01*
G01Y1089823D02*
Y1092185D01*
G01Y1084823D02*
Y1087185D01*
G01Y1091667D02*
Y1091811D01*
G01Y1086667D02*
Y1086811D01*
G01Y1101667D02*
Y1101811D01*
G01Y1096667D02*
Y1096811D01*
G01Y1126667D02*
Y1126811D01*
G01X115945Y1123366D02*
Y1103642D01*
G01X115531Y1087185D02*
Y1084823D01*
G01Y1092185D02*
Y1089823D01*
G01Y1097185D02*
Y1094823D01*
G01Y1102185D02*
Y1099823D01*
G01Y1127185D02*
Y1124823D01*
G01Y1132185D02*
Y1129823D01*
G01X113189Y1201004D02*
Y1124547D01*
G01X112008Y1199823D02*
Y1123366D01*
G01X103543Y1204744D02*
Y1125709D01*
G01X103091Y1122205D02*
Y1123701D01*
G01Y1119055D02*
Y1120551D01*
G01Y1115906D02*
Y1117402D01*
G01Y1112756D02*
Y1114252D01*
G01Y1109606D02*
Y1111102D01*
G01Y1106457D02*
Y1107953D01*
G01Y1103307D02*
Y1104803D01*
G01X103051Y1106603D02*
Y1106456D01*
G01Y1103454D02*
Y1103307D01*
G01Y1104804D02*
Y1104657D01*
G01Y1109753D02*
Y1109606D01*
G01Y1111103D02*
Y1110956D01*
G01Y1107953D02*
Y1107807D01*
G01Y1116052D02*
Y1115905D01*
G01Y1112902D02*
Y1112756D01*
G01Y1114252D02*
Y1114106D01*
G01Y1119202D02*
Y1119055D01*
G01Y1120552D02*
Y1120405D01*
G01Y1117402D02*
Y1117256D01*
G01Y1122351D02*
Y1122204D01*
G01Y1123701D02*
Y1123555D01*
G01X102146Y1122204D02*
Y1122351D01*
G01Y1123555D02*
Y1123702D01*
G01Y1119054D02*
Y1119202D01*
G01Y1120405D02*
Y1120552D01*
G01Y1117256D02*
Y1117402D01*
G01Y1115905D02*
Y1116052D01*
G01Y1112755D02*
Y1112902D01*
G01Y1114106D02*
Y1114253D01*
G01Y1109606D02*
Y1109753D01*
G01Y1110956D02*
Y1111103D01*
G01Y1107807D02*
Y1107954D01*
G01Y1106456D02*
Y1106603D01*
G01Y1103306D02*
Y1103454D01*
G01Y1104657D02*
Y1104804D01*
G01X102106Y1104803D02*
Y1103307D01*
G01Y1111102D02*
Y1109606D01*
G01Y1107953D02*
Y1106457D01*
G01Y1114252D02*
Y1112756D01*
G01Y1120551D02*
Y1119055D01*
G01Y1117402D02*
Y1115906D01*
G01Y1123701D02*
Y1122205D01*
G01X100925Y1107795D02*
Y1106614D01*
G01Y1104646D02*
Y1103465D01*
G01Y1110945D02*
Y1109764D01*
G01Y1117244D02*
Y1116063D01*
G01Y1114094D02*
Y1112913D01*
G01Y1120394D02*
Y1119213D01*
G01Y1123543D02*
Y1122362D01*
G01X100591Y1125709D02*
Y1101299D01*
G01X100197D02*
Y1125709D01*
G01X97165Y1122362D02*
Y1123543D01*
G01Y1119213D02*
Y1120394D01*
G01Y1116063D02*
Y1117244D01*
G01Y1112913D02*
Y1114094D01*
G01Y1109764D02*
Y1110945D01*
G01Y1106614D02*
Y1107795D01*
G01Y1103465D02*
Y1104646D01*
G01X103091Y1122388D02*
X103090Y1122399D01*
G01X103091Y1119239D02*
X103090Y1119250D01*
G01X103091Y1116089D02*
X103090Y1116100D01*
G01X103091Y1112939D02*
X103090Y1112950D01*
G01X103091Y1109790D02*
X103090Y1109801D01*
G01X103091Y1106640D02*
X103090Y1106651D01*
G01X103091Y1103491D02*
X103090Y1103502D01*
G01X116516Y1175308D02*
Y1175299D01*
G01X116517Y1175313D02*
X116516Y1175308D01*
G01X116519Y1175315D02*
X116517Y1175313D01*
G01X116516Y1170308D02*
Y1170299D01*
G01X116517Y1170313D02*
X116516Y1170308D01*
G01X116519Y1170315D02*
X116517Y1170313D01*
G01X116516Y1165308D02*
Y1165299D01*
G01X116517Y1165313D02*
X116516Y1165308D01*
G01X116519Y1165315D02*
X116517Y1165313D01*
G01X116516Y1160308D02*
Y1160299D01*
G01X116517Y1160313D02*
X116516Y1160308D01*
G01X116519Y1160315D02*
X116517Y1160313D01*
G01X116516Y1155308D02*
Y1155299D01*
G01X116517Y1155313D02*
X116516Y1155308D01*
G01X116519Y1155315D02*
X116517Y1155313D01*
G01X116516Y1150308D02*
Y1150299D01*
G01X116517Y1150313D02*
X116516Y1150308D01*
G01X116519Y1150315D02*
X116517Y1150313D01*
G01X116516Y1145308D02*
Y1145299D01*
G01X116517Y1145313D02*
X116516Y1145308D01*
G01X116519Y1145315D02*
X116517Y1145313D01*
G01X116516Y1140308D02*
Y1140299D01*
G01X116517Y1140313D02*
X116516Y1140308D01*
G01X116519Y1140315D02*
X116517Y1140313D01*
G01X116483Y1131791D02*
X116487Y1131890D01*
G01X116477Y1131719D02*
X116483Y1131791D01*
G01X116479Y1131693D02*
X116477Y1131719D01*
G01X116483Y1136791D02*
X116487Y1136890D01*
G01X116477Y1136719D02*
X116483Y1136791D01*
G01X116479Y1136693D02*
X116477Y1136719D01*
G01X116483Y1141791D02*
X116487Y1141890D01*
G01X116477Y1141719D02*
X116483Y1141791D01*
G01X116479Y1141693D02*
X116477Y1141719D01*
G01X116483Y1146791D02*
X116487Y1146890D01*
G01X116477Y1146719D02*
X116483Y1146791D01*
G01X116479Y1146693D02*
X116477Y1146719D01*
G01X116483Y1151791D02*
X116487Y1151890D01*
G01X116477Y1151719D02*
X116483Y1151791D01*
G01X116479Y1151693D02*
X116477Y1151719D01*
G01X116483Y1156791D02*
X116487Y1156890D01*
G01X116477Y1156719D02*
X116483Y1156791D01*
G01X116479Y1156693D02*
X116477Y1156719D01*
G01X116483Y1161791D02*
X116487Y1161890D01*
G01X116477Y1161719D02*
X116483Y1161791D01*
G01X116479Y1161693D02*
X116477Y1161719D01*
G01X116483Y1166791D02*
X116487Y1166890D01*
G01X116477Y1166719D02*
X116483Y1166791D01*
G01X116479Y1166693D02*
X116477Y1166719D01*
G01X116483Y1171791D02*
X116487Y1171890D01*
G01X116477Y1171719D02*
X116483Y1171791D01*
G01X116479Y1171693D02*
X116477Y1171719D01*
G01X116483Y1176791D02*
X116487Y1176890D01*
G01X116477Y1176719D02*
X116483Y1176791D01*
G01X116479Y1176693D02*
X116477Y1176719D01*
G01X115532Y1175313D02*
X115533Y1175315D01*
G01X115531Y1175308D02*
X115532Y1175313D01*
G01X115531Y1175299D02*
Y1175308D01*
G01X115532Y1170313D02*
X115533Y1170315D01*
G01X115531Y1170308D02*
X115532Y1170313D01*
G01X115531Y1170299D02*
Y1170308D01*
G01X115532Y1165313D02*
X115533Y1165315D01*
G01X115531Y1165308D02*
X115532Y1165313D01*
G01X115531Y1165299D02*
Y1165308D01*
G01X115532Y1160313D02*
X115533Y1160315D01*
G01X115531Y1160308D02*
X115532Y1160313D01*
G01X115531Y1160299D02*
Y1160308D01*
G01X115532Y1155313D02*
X115533Y1155315D01*
G01X115531Y1155308D02*
X115532Y1155313D01*
G01X115531Y1155299D02*
Y1155308D01*
G01X115532Y1150313D02*
X115533Y1150315D01*
G01X115531Y1150308D02*
X115532Y1150313D01*
G01X115531Y1150299D02*
Y1150308D01*
G01X115532Y1145313D02*
X115533Y1145315D01*
G01X115531Y1145308D02*
X115532Y1145313D01*
G01X115531Y1145299D02*
Y1145308D01*
G01X115532Y1140313D02*
X115533Y1140315D01*
G01X115531Y1140308D02*
X115532Y1140313D01*
G01X115531Y1140299D02*
Y1140308D01*
G01X115532Y1135313D02*
X115533Y1135315D01*
G01X115531Y1135308D02*
X115532Y1135313D01*
G01X115531Y1135299D02*
Y1135308D01*
G01X116516D02*
Y1135299D01*
G01X116517Y1135313D02*
X116516Y1135308D01*
G01X116519Y1135315D02*
X116517Y1135313D01*
G01X116498Y1131688D02*
X116479Y1131693D01*
G01X116513Y1131674D02*
X116498Y1131688D01*
G01X116518Y1131654D02*
X116513Y1131674D01*
G01X116498Y1136688D02*
X116479Y1136693D01*
G01X116513Y1136674D02*
X116498Y1136688D01*
G01X116518Y1136654D02*
X116513Y1136674D01*
G01X116498Y1141688D02*
X116479Y1141693D01*
G01X116513Y1141674D02*
X116498Y1141688D01*
G01X116518Y1141654D02*
X116513Y1141674D01*
G01X116498Y1146688D02*
X116479Y1146693D01*
G01X116513Y1146674D02*
X116498Y1146688D01*
G01X116518Y1146654D02*
X116513Y1146674D01*
G01X116498Y1151688D02*
X116479Y1151693D01*
G01X116513Y1151674D02*
X116498Y1151688D01*
G01X116518Y1151654D02*
X116513Y1151674D01*
G01X116498Y1156688D02*
X116479Y1156693D01*
G01X116513Y1156674D02*
X116498Y1156688D01*
G01X116518Y1156654D02*
X116513Y1156674D01*
G01X116498Y1161688D02*
X116479Y1161693D01*
G01X116513Y1161674D02*
X116498Y1161688D01*
G01X116518Y1161654D02*
X116513Y1161674D01*
G01X116498Y1166688D02*
X116479Y1166693D01*
G01X116513Y1166674D02*
X116498Y1166688D01*
G01X116518Y1166654D02*
X116513Y1166674D01*
G01X116498Y1171688D02*
X116479Y1171693D01*
G01X116513Y1171674D02*
X116498Y1171688D01*
G01X116518Y1171654D02*
X116513Y1171674D01*
G01X116498Y1176688D02*
X116479Y1176693D01*
G01X116513Y1176674D02*
X116498Y1176688D01*
G01X116518Y1176654D02*
X116513Y1176674D01*
G01X115531Y1131700D02*
Y1131709D01*
G01X115532Y1131695D02*
X115531Y1131700D01*
G01X115533Y1131693D02*
X115532Y1131695D01*
G01X115531Y1136700D02*
Y1136709D01*
G01X115532Y1136695D02*
X115531Y1136700D01*
G01X115533Y1136693D02*
X115532Y1136695D01*
G01X115531Y1141700D02*
Y1141709D01*
G01X115532Y1141695D02*
X115531Y1141700D01*
G01X115533Y1141693D02*
X115532Y1141695D01*
G01X115531Y1146700D02*
Y1146709D01*
G01X115532Y1146695D02*
X115531Y1146700D01*
G01X115533Y1146693D02*
X115532Y1146695D01*
G01X115531Y1151700D02*
Y1151709D01*
G01X115532Y1151695D02*
X115531Y1151700D01*
G01X115533Y1151693D02*
X115532Y1151695D01*
G01X115531Y1156700D02*
Y1156709D01*
G01X115532Y1156695D02*
X115531Y1156700D01*
G01X115533Y1156693D02*
X115532Y1156695D01*
G01X115531Y1161700D02*
Y1161709D01*
G01X115532Y1161695D02*
X115531Y1161700D01*
G01X115533Y1161693D02*
X115532Y1161695D01*
G01X115531Y1166700D02*
Y1166709D01*
G01X115532Y1166695D02*
X115531Y1166700D01*
G01X115533Y1166693D02*
X115532Y1166695D01*
G01X115531Y1171700D02*
Y1171709D01*
G01X115532Y1171695D02*
X115531Y1171700D01*
G01X115533Y1171693D02*
X115532Y1171695D01*
G01X115531Y1176700D02*
Y1176709D01*
G01X115532Y1176695D02*
X115531Y1176700D01*
G01X115533Y1176693D02*
X115532Y1176695D01*
G01X116508Y1131837D02*
X116516Y1131811D01*
G01X116498Y1131863D02*
X116508Y1131837D01*
G01X116487Y1131890D02*
X116498Y1131863D01*
G01X116508Y1136837D02*
X116516Y1136811D01*
G01X116498Y1136863D02*
X116508Y1136837D01*
G01X116487Y1136890D02*
X116498Y1136863D01*
G01X116508Y1141837D02*
X116516Y1141811D01*
G01X116498Y1141863D02*
X116508Y1141837D01*
G01X116487Y1141890D02*
X116498Y1141863D01*
G01X116508Y1146837D02*
X116516Y1146811D01*
G01X116498Y1146863D02*
X116508Y1146837D01*
G01X116487Y1146890D02*
X116498Y1146863D01*
G01X116508Y1151837D02*
X116516Y1151811D01*
G01X116498Y1151863D02*
X116508Y1151837D01*
G01X116487Y1151890D02*
X116498Y1151863D01*
G01X116508Y1156837D02*
X116516Y1156811D01*
G01X116498Y1156863D02*
X116508Y1156837D01*
G01X116487Y1156890D02*
X116498Y1156863D01*
G01X116508Y1161837D02*
X116516Y1161811D01*
G01X116498Y1161863D02*
X116508Y1161837D01*
G01X116487Y1161890D02*
X116498Y1161863D01*
G01X116508Y1166837D02*
X116516Y1166811D01*
G01X116498Y1166863D02*
X116508Y1166837D01*
G01X116487Y1166890D02*
X116498Y1166863D01*
G01X116508Y1171837D02*
X116516Y1171811D01*
G01X116498Y1171863D02*
X116508Y1171837D01*
G01X116487Y1171890D02*
X116498Y1171863D01*
G01X116508Y1176837D02*
X116516Y1176811D01*
G01X116498Y1176863D02*
X116508Y1176837D01*
G01X116487Y1176890D02*
X116498Y1176863D01*
G01X116516Y1131660D02*
Y1131667D01*
G01X116517Y1131656D02*
X116516Y1131660D01*
G01X116518Y1131654D02*
X116517Y1131656D01*
G01X116516Y1136660D02*
Y1136667D01*
G01X116517Y1136656D02*
X116516Y1136660D01*
G01X116518Y1136654D02*
X116517Y1136656D01*
G01X116516Y1141660D02*
Y1141667D01*
G01X116517Y1141656D02*
X116516Y1141660D01*
G01X116518Y1141654D02*
X116517Y1141656D01*
G01X116516Y1146660D02*
Y1146667D01*
G01X116517Y1146656D02*
X116516Y1146660D01*
G01X116518Y1146654D02*
X116517Y1146656D01*
G01X116516Y1151660D02*
Y1151667D01*
G01X116517Y1151656D02*
X116516Y1151660D01*
G01X116518Y1151654D02*
X116517Y1151656D01*
G01X116516Y1156660D02*
Y1156667D01*
G01X116517Y1156656D02*
X116516Y1156660D01*
G01X116518Y1156654D02*
X116517Y1156656D01*
G01X116516Y1161660D02*
Y1161667D01*
G01X116517Y1161656D02*
X116516Y1161660D01*
G01X116518Y1161654D02*
X116517Y1161656D01*
G01X116516Y1166660D02*
Y1166667D01*
G01X116517Y1166656D02*
X116516Y1166660D01*
G01X116518Y1166654D02*
X116517Y1166656D01*
G01X116516Y1171660D02*
Y1171667D01*
G01X116517Y1171656D02*
X116516Y1171660D01*
G01X116518Y1171654D02*
X116517Y1171656D01*
G01X116516Y1176660D02*
Y1176667D01*
G01X116517Y1176656D02*
X116516Y1176660D01*
G01X116518Y1176654D02*
X116517Y1176656D01*
G01X116503Y1131685D02*
X116514Y1131669D01*
G01X116479Y1131693D02*
X116503Y1131685D01*
G01Y1136685D02*
X116514Y1136669D01*
G01X116479Y1136693D02*
X116503Y1136685D01*
G01Y1141685D02*
X116514Y1141669D01*
G01X116479Y1141693D02*
X116503Y1141685D01*
G01Y1146685D02*
X116514Y1146669D01*
G01X116479Y1146693D02*
X116503Y1146685D01*
G01Y1151685D02*
X116514Y1151669D01*
G01X116479Y1151693D02*
X116503Y1151685D01*
G01Y1156685D02*
X116514Y1156669D01*
G01X116479Y1156693D02*
X116503Y1156685D01*
G01Y1161685D02*
X116514Y1161669D01*
G01X116479Y1161693D02*
X116503Y1161685D01*
G01Y1166685D02*
X116514Y1166669D01*
G01X116479Y1166693D02*
X116503Y1166685D01*
G01Y1171685D02*
X116514Y1171669D01*
G01X116479Y1171693D02*
X116503Y1171685D01*
G01Y1176685D02*
X116514Y1176669D01*
G01X116479Y1176693D02*
X116503Y1176685D01*
G01X116516Y1177185D02*
X115531D01*
G01X115533Y1176693D02*
X120866D01*
G01Y1176654D02*
X116518D01*
G01X120866Y1175315D02*
X115533D01*
G01X115531Y1174823D02*
X116516D01*
G01Y1172185D02*
X115531D01*
G01X115533Y1171693D02*
X120866D01*
G01Y1171654D02*
X116518D01*
G01X120866Y1170315D02*
X115533D01*
G01X115531Y1169823D02*
X116516D01*
G01Y1167185D02*
X115531D01*
G01X115533Y1166693D02*
X120866D01*
G01Y1166654D02*
X116518D01*
G01X120866Y1165315D02*
X115533D01*
G01X115531Y1164823D02*
X116516D01*
G01Y1162185D02*
X115531D01*
G01X115533Y1161693D02*
X120866D01*
G01Y1161654D02*
X116518D01*
G01X120866Y1160315D02*
X115533D01*
G01X115531Y1159823D02*
X116516D01*
G01Y1157185D02*
X115531D01*
G01X115533Y1156693D02*
X120866D01*
G01Y1156654D02*
X116518D01*
G01X120866Y1155315D02*
X115533D01*
G01X115531Y1154823D02*
X116516D01*
G01X115531Y1176889D02*
X116487Y1176890D01*
G01X116516Y1175119D02*
X115531Y1175118D01*
G01Y1171889D02*
X116487Y1171890D01*
G01X116516Y1170119D02*
X115531Y1170118D01*
G01Y1166889D02*
X116487Y1166890D01*
G01X116516Y1165119D02*
X115531Y1165118D01*
G01Y1161889D02*
X116487Y1161890D01*
G01X116516Y1160119D02*
X115531Y1160118D01*
G01Y1156889D02*
X116487Y1156890D01*
G01X116516Y1155119D02*
X115531Y1155118D01*
G01X116516Y1152185D02*
X115531D01*
G01X115533Y1151693D02*
X120866D01*
G01Y1151654D02*
X116518D01*
G01X120866Y1150315D02*
X115533D01*
G01X115531Y1149823D02*
X116516D01*
G01Y1147185D02*
X115531D01*
G01X115533Y1146693D02*
X120866D01*
G01Y1146654D02*
X116518D01*
G01X120866Y1145315D02*
X115533D01*
G01X115531Y1144823D02*
X116516D01*
G01Y1142185D02*
X115531D01*
G01X115533Y1141693D02*
X120866D01*
G01Y1141654D02*
X116518D01*
G01X120866Y1140315D02*
X115533D01*
G01X115531Y1139823D02*
X116516D01*
G01Y1137185D02*
X115531D01*
G01X115533Y1136693D02*
X120866D01*
G01Y1136654D02*
X116518D01*
G01X120866Y1135315D02*
X115533D01*
G01X115531Y1134823D02*
X116516D01*
G01Y1132185D02*
X115531D01*
G01X115533Y1131693D02*
X120866D01*
G01Y1131654D02*
X116518D01*
G01X115531Y1151889D02*
X116487Y1151890D01*
G01X116516Y1150119D02*
X115531Y1150118D01*
G01Y1146889D02*
X116487Y1146890D01*
G01X116516Y1145119D02*
X115531Y1145118D01*
G01Y1141889D02*
X116487Y1141890D01*
G01X116516Y1140119D02*
X115531Y1140118D01*
G01Y1136889D02*
X116487Y1136890D01*
G01X116516Y1135119D02*
X115531Y1135118D01*
G01Y1131889D02*
X116487Y1131890D01*
G01X116516Y1131667D02*
Y1131676D01*
G01Y1136667D02*
Y1136676D01*
G01Y1141667D02*
Y1141676D01*
G01Y1146667D02*
Y1146676D01*
G01Y1151667D02*
Y1151676D01*
G01Y1156667D02*
Y1156676D01*
G01Y1161667D02*
Y1161676D01*
G01Y1166667D02*
Y1166676D01*
G01Y1171667D02*
Y1171676D01*
G01Y1176667D02*
Y1176676D01*
G01X117697Y1136693D02*
Y1135315D01*
G01Y1141693D02*
Y1140315D01*
G01Y1146693D02*
Y1145315D01*
G01Y1151693D02*
Y1150315D01*
G01Y1156693D02*
Y1155315D01*
G01Y1161693D02*
Y1160315D01*
G01Y1166693D02*
Y1165315D01*
G01Y1171693D02*
Y1170315D01*
G01Y1176693D02*
Y1175315D01*
G01X116516Y1174823D02*
Y1177185D01*
G01Y1169823D02*
Y1172185D01*
G01Y1164823D02*
Y1167185D01*
G01Y1159823D02*
Y1162185D01*
G01Y1154823D02*
Y1157185D01*
G01Y1149823D02*
Y1152185D01*
G01Y1144823D02*
Y1147185D01*
G01Y1139823D02*
Y1142185D01*
G01Y1134823D02*
Y1137185D01*
G01Y1131667D02*
Y1131811D01*
G01Y1141667D02*
Y1141811D01*
G01Y1136667D02*
Y1136811D01*
G01Y1151667D02*
Y1151811D01*
G01Y1146667D02*
Y1146811D01*
G01Y1161667D02*
Y1161811D01*
G01Y1156667D02*
Y1156811D01*
G01Y1171667D02*
Y1171811D01*
G01Y1166667D02*
Y1166811D01*
G01Y1176667D02*
Y1176811D01*
G01X115531Y1137185D02*
Y1134823D01*
G01Y1142185D02*
Y1139823D01*
G01Y1147185D02*
Y1144823D01*
G01Y1152185D02*
Y1149823D01*
G01Y1157185D02*
Y1154823D01*
G01Y1162185D02*
Y1159823D01*
G01Y1167185D02*
Y1164823D01*
G01Y1172185D02*
Y1169823D01*
G01Y1177185D02*
Y1174823D01*
G01X116516Y1195308D02*
Y1195299D01*
G01X116517Y1195313D02*
X116516Y1195308D01*
G01X116519Y1195315D02*
X116517Y1195313D01*
G01X116516Y1190308D02*
Y1190299D01*
G01X116517Y1190313D02*
X116516Y1190308D01*
G01X116519Y1190315D02*
X116517Y1190313D01*
G01X116516Y1185308D02*
Y1185299D01*
G01X116517Y1185313D02*
X116516Y1185308D01*
G01X116519Y1185315D02*
X116517Y1185313D01*
G01X116516Y1180308D02*
Y1180299D01*
G01X116517Y1180313D02*
X116516Y1180308D01*
G01X116519Y1180315D02*
X116517Y1180313D01*
G01X116483Y1181791D02*
X116487Y1181890D01*
G01X116477Y1181719D02*
X116483Y1181791D01*
G01X116479Y1181693D02*
X116477Y1181719D01*
G01X116483Y1186791D02*
X116487Y1186890D01*
G01X116477Y1186719D02*
X116483Y1186791D01*
G01X116479Y1186693D02*
X116477Y1186719D01*
G01X116483Y1191791D02*
X116487Y1191890D01*
G01X116477Y1191719D02*
X116483Y1191791D01*
G01X116479Y1191693D02*
X116477Y1191719D01*
G01X116483Y1196791D02*
X116487Y1196890D01*
G01X116477Y1196719D02*
X116483Y1196791D01*
G01X116479Y1196693D02*
X116477Y1196719D01*
G01X115532Y1195313D02*
X115533Y1195315D01*
G01X115531Y1195308D02*
X115532Y1195313D01*
G01X115531Y1195299D02*
Y1195308D01*
G01X115532Y1190313D02*
X115533Y1190315D01*
G01X115531Y1190308D02*
X115532Y1190313D01*
G01X115531Y1190299D02*
Y1190308D01*
G01X115532Y1185313D02*
X115533Y1185315D01*
G01X115531Y1185308D02*
X115532Y1185313D01*
G01X115531Y1185299D02*
Y1185308D01*
G01X115532Y1180313D02*
X115533Y1180315D01*
G01X115531Y1180308D02*
X115532Y1180313D01*
G01X115531Y1180299D02*
Y1180308D01*
G01X116498Y1181688D02*
X116479Y1181693D01*
G01X116513Y1181674D02*
X116498Y1181688D01*
G01X116518Y1181654D02*
X116513Y1181674D01*
G01X116498Y1186688D02*
X116479Y1186693D01*
G01X116513Y1186674D02*
X116498Y1186688D01*
G01X116518Y1186654D02*
X116513Y1186674D01*
G01X116498Y1191688D02*
X116479Y1191693D01*
G01X116513Y1191674D02*
X116498Y1191688D01*
G01X116518Y1191654D02*
X116513Y1191674D01*
G01X116498Y1196688D02*
X116479Y1196693D01*
G01X116513Y1196674D02*
X116498Y1196688D01*
G01X116518Y1196654D02*
X116513Y1196674D01*
G01X115531Y1181700D02*
Y1181709D01*
G01X115532Y1181695D02*
X115531Y1181700D01*
G01X115533Y1181693D02*
X115532Y1181695D01*
G01X115531Y1186700D02*
Y1186709D01*
G01X115532Y1186695D02*
X115531Y1186700D01*
G01X115533Y1186693D02*
X115532Y1186695D01*
G01X116508Y1181837D02*
X116516Y1181811D01*
G01X116498Y1181863D02*
X116508Y1181837D01*
G01X116487Y1181890D02*
X116498Y1181863D01*
G01X116508Y1186837D02*
X116516Y1186811D01*
G01X116498Y1186863D02*
X116508Y1186837D01*
G01X116487Y1186890D02*
X116498Y1186863D01*
G01X116508Y1191837D02*
X116516Y1191811D01*
G01X116498Y1191863D02*
X116508Y1191837D01*
G01X116487Y1191890D02*
X116498Y1191863D01*
G01X116508Y1196837D02*
X116516Y1196811D01*
G01X116498Y1196863D02*
X116508Y1196837D01*
G01X116487Y1196890D02*
X116498Y1196863D01*
G01X115531Y1191700D02*
Y1191709D01*
G01X115532Y1191695D02*
X115531Y1191700D01*
G01X115533Y1191693D02*
X115532Y1191695D01*
G01X115531Y1196700D02*
Y1196709D01*
G01X115532Y1196695D02*
X115531Y1196700D01*
G01X115533Y1196693D02*
X115532Y1196695D01*
G01X116516Y1181660D02*
Y1181667D01*
G01X116517Y1181656D02*
X116516Y1181660D01*
G01X116518Y1181654D02*
X116517Y1181656D01*
G01X116516Y1186660D02*
Y1186667D01*
G01X116517Y1186656D02*
X116516Y1186660D01*
G01X116518Y1186654D02*
X116517Y1186656D01*
G01X116516Y1191660D02*
Y1191667D01*
G01X116517Y1191656D02*
X116516Y1191660D01*
G01X116518Y1191654D02*
X116517Y1191656D01*
G01X116516Y1196660D02*
Y1196667D01*
G01X116517Y1196656D02*
X116516Y1196660D01*
G01X116518Y1196654D02*
X116517Y1196656D01*
G01X116503Y1181685D02*
X116514Y1181669D01*
G01X116479Y1181693D02*
X116503Y1181685D01*
G01Y1186685D02*
X116514Y1186669D01*
G01X116479Y1186693D02*
X116503Y1186685D01*
G01Y1191685D02*
X116514Y1191669D01*
G01X116479Y1191693D02*
X116503Y1191685D01*
G01Y1196685D02*
X116514Y1196669D01*
G01X116479Y1196693D02*
X116503Y1196685D01*
G01X114961Y1222185D02*
G03X114370Y1222776I-591J0D01*
G01X107677D02*
G03X107087Y1222185I1J-591D01*
G01X109843Y1221004D02*
G03Y1219035I0J-985D01*
G01X112205D02*
G03Y1221004I0J985D01*
G01X121850Y1221594D02*
G03X119882Y1223563I-1968J1D01*
G01X102165D02*
G03X100197Y1221594I0J-1968D01*
G01X108465Y1213091D02*
G03X107283Y1211909I-1J-1181D01*
G01X114764D02*
G03X113583Y1213091I-1181J1D01*
G01X112913Y1207815D02*
G03I-1889J0D01*
G01X113386D02*
G03I-2362J0D01*
G01X119882Y1223563D02*
X102165D01*
G01X114370Y1222776D02*
X107677D01*
G01X112205Y1221004D02*
X109843D01*
G01Y1219035D02*
X112205D01*
G01X114961Y1217657D02*
X107087D01*
G01Y1216083D02*
X114961D01*
G01X121850Y1213130D02*
X100197D01*
G01X108465Y1213091D02*
X113583D01*
G01X109843Y1208406D02*
X112205D01*
G01X109843Y1206713D02*
X112205D01*
G01X103543Y1204744D02*
X117913D01*
G01X103543Y1203366D02*
X107283D01*
G01X117913D02*
X114764D01*
G01X103543Y1202500D02*
X118504D01*
G01X105315Y1201004D02*
X113189D01*
G01X106496Y1199823D02*
X112008D01*
G01X116516Y1197185D02*
X115531D01*
G01X115533Y1196693D02*
X120866D01*
G01Y1196654D02*
X116518D01*
G01X120866Y1195315D02*
X115533D01*
G01X115531Y1194823D02*
X116516D01*
G01Y1192185D02*
X115531D01*
G01X115533Y1191693D02*
X120866D01*
G01Y1191654D02*
X116518D01*
G01X120866Y1190315D02*
X115533D01*
G01X115531Y1189823D02*
X116516D01*
G01Y1187185D02*
X115531D01*
G01X115533Y1186693D02*
X120866D01*
G01Y1186654D02*
X116518D01*
G01X120866Y1185315D02*
X115533D01*
G01X115531Y1184823D02*
X116516D01*
G01Y1182185D02*
X115531D01*
G01X115533Y1181693D02*
X120866D01*
G01Y1181654D02*
X116518D01*
G01X120866Y1180315D02*
X115533D01*
G01X115531Y1179823D02*
X116516D01*
G01X115531Y1196889D02*
X116487Y1196890D01*
G01X116516Y1195119D02*
X115531Y1195118D01*
G01Y1191889D02*
X116487Y1191890D01*
G01X116516Y1190119D02*
X115531Y1190118D01*
G01Y1186889D02*
X116487Y1186890D01*
G01X116516Y1185119D02*
X115531Y1185118D01*
G01Y1181889D02*
X116487Y1181890D01*
G01X116516Y1180119D02*
X115531Y1180118D01*
G01X105315Y1201004D02*
X106496Y1199823D01*
G01X100197Y1205846D02*
X103543Y1202500D01*
G01X112205Y1206713D02*
X113508Y1204744D01*
G01X109843Y1208406D02*
X107532Y1212635D01*
G01X116516Y1181667D02*
Y1181676D01*
G01Y1186667D02*
Y1186676D01*
G01Y1191667D02*
Y1191676D01*
G01Y1196667D02*
Y1196676D01*
G01X117697Y1181693D02*
Y1180315D01*
G01Y1186693D02*
Y1185315D01*
G01Y1191693D02*
Y1190315D01*
G01Y1196693D02*
Y1195315D01*
G01X116516Y1194823D02*
Y1197185D01*
G01Y1189823D02*
Y1192185D01*
G01Y1184823D02*
Y1187185D01*
G01Y1179823D02*
Y1182185D01*
G01Y1181667D02*
Y1181811D01*
G01Y1191667D02*
Y1191811D01*
G01Y1186667D02*
Y1186811D01*
G01Y1196667D02*
Y1196811D01*
G01X115531Y1182185D02*
Y1179823D01*
G01Y1187185D02*
Y1184823D01*
G01Y1192185D02*
Y1189823D01*
G01Y1197185D02*
Y1194823D01*
G01X114961Y1216083D02*
Y1222185D01*
G01X114764Y1211909D02*
Y1203366D01*
G01X112205Y1208406D02*
Y1206713D01*
G01X109843D02*
Y1208406D01*
G01X107283Y1203366D02*
Y1211909D01*
G01X107087Y1216083D02*
Y1222185D01*
G01X100197Y1221594D02*
Y1205846D01*
G01X121850D02*
X118504Y1202500D01*
G01X112008Y1199823D02*
X113189Y1201004D01*
G01X108539Y1204744D02*
X109843Y1206713D01*
G01X114515Y1212635D02*
X112205Y1208406D01*
G01X114295Y1284397D02*
G03X148106I16905J-13531D01*
G01X114295D02*
G03X148106I16905J-13531D01*
G01X73031Y1274016D02*
Y1280315D01*
G01Y1274016D02*
Y1280315D01*
G01X114295Y1284397D02*
G03X121220Y1297528I-30737J24602D01*
G01X114295Y1284397D02*
G03X121220Y1297528I-30737J24601D01*
G01X100898Y1841823D02*
Y1822886D01*
G01X122933Y20472D02*
G03X131594I4330J0D01*
G01Y20473D02*
G03I-4330J0D01*
G01Y20472D02*
G03X122933I-4331J0D01*
G01X121850Y139902D02*
Y155650D01*
G01X120866Y194803D02*
Y196181D01*
G01Y189803D02*
Y191181D01*
G01Y184803D02*
Y186181D01*
G01Y179803D02*
Y181181D01*
G01Y174803D02*
Y176181D01*
G01Y169803D02*
Y171181D01*
G01Y164803D02*
Y166181D01*
G01Y259803D02*
Y261181D01*
G01Y254803D02*
Y256181D01*
G01Y249803D02*
Y251181D01*
G01Y244803D02*
Y246181D01*
G01Y239803D02*
Y241181D01*
G01Y234803D02*
Y236181D01*
G01Y229803D02*
Y231181D01*
G01Y224803D02*
Y226181D01*
G01Y219803D02*
Y221181D01*
G01X121850Y300335D02*
Y316083D01*
G01X120866Y289803D02*
Y291181D01*
G01Y284803D02*
Y286181D01*
G01Y279803D02*
Y281181D01*
G01Y274803D02*
Y276181D01*
G01Y269803D02*
Y271181D01*
G01Y264803D02*
Y266181D01*
G01X141181Y392016D02*
G03X148106Y378885I37662J11471D01*
G01X141181Y392016D02*
G03X121220I-9980J-3039D01*
G01X141181D02*
G03X148106Y378885I37662J11471D01*
G01X141181Y392016D02*
G03X121220I-9980J-3039D01*
G01X121850Y592657D02*
Y608406D01*
G01X176575Y646457D02*
G03X160039I-8268J0D01*
G01D02*
G03X176575I8268J0D01*
G01D02*
G03I-8268J0D01*
G01X120866Y647559D02*
Y648937D01*
G01Y642559D02*
Y643937D01*
G01Y637559D02*
Y638937D01*
G01Y632559D02*
Y633937D01*
G01Y627559D02*
Y628937D01*
G01Y622559D02*
Y623937D01*
G01Y617559D02*
Y618937D01*
G01Y692559D02*
Y693937D01*
G01Y687559D02*
Y688937D01*
G01Y682559D02*
Y683937D01*
G01Y677559D02*
Y678937D01*
G01Y672559D02*
Y673937D01*
G01Y742559D02*
Y743937D01*
G01Y737559D02*
Y738937D01*
G01Y732559D02*
Y733937D01*
G01Y727559D02*
Y728937D01*
G01Y722559D02*
Y723937D01*
G01Y717559D02*
Y718937D01*
G01Y712559D02*
Y713937D01*
G01Y707559D02*
Y708937D01*
G01Y702559D02*
Y703937D01*
G01Y697559D02*
Y698937D01*
G01X121850Y753091D02*
Y768839D01*
G01X141181Y844772D02*
G03X148106Y831641I37662J11471D01*
G01X141181Y844772D02*
G03X148106Y831641I37662J11471D01*
G01X141181Y844772D02*
G03X121220I-9980J-3039D01*
G01X141181D02*
G03X121220I-9980J-3040D01*
G01X166240Y1062992D02*
G03X180217I6988J0D01*
G01D02*
G03X166240I-6988J0D01*
G01X180217D02*
G03I-6989J0D01*
G01X121850Y1045413D02*
Y1061161D01*
G01X120866Y1080315D02*
Y1081693D01*
G01Y1075315D02*
Y1076693D01*
G01Y1070315D02*
Y1071693D01*
G01X167717Y1114173D02*
G03X178741I5512J0D01*
G01D02*
G03X167717I-5512J0D01*
G01X178740D02*
G03I-5512J0D01*
G01X120866Y1130315D02*
Y1131693D01*
G01Y1125315D02*
Y1126693D01*
G01Y1100315D02*
Y1101693D01*
G01Y1095315D02*
Y1096693D01*
G01Y1090315D02*
Y1091693D01*
G01Y1085315D02*
Y1086693D01*
G01Y1175315D02*
Y1176693D01*
G01Y1170315D02*
Y1171693D01*
G01Y1165315D02*
Y1166693D01*
G01Y1160315D02*
Y1161693D01*
G01Y1155315D02*
Y1156693D01*
G01Y1150315D02*
Y1151693D01*
G01Y1145315D02*
Y1146693D01*
G01Y1140315D02*
Y1141693D01*
G01Y1135315D02*
Y1136693D01*
G01X121850Y1205846D02*
Y1221594D01*
G01X120866Y1195315D02*
Y1196693D01*
G01Y1190315D02*
Y1191693D01*
G01Y1185315D02*
Y1186693D01*
G01Y1180315D02*
Y1181693D01*
G01X141181Y1297528D02*
G03X148106Y1284397I37662J11471D01*
G01X141181Y1297528D02*
G03X121220I-9980J-3040D01*
G01X141181D02*
G03X148106Y1284397I37662J11471D01*
G01X141181Y1297528D02*
G03X121220I-9980J-3040D01*
G01X195276Y374803D02*
G03X196457I591J0D01*
G01Y368504D02*
G03X195276I-590J0D01*
G01X193307D02*
G03X192126I-591J0D01*
G01Y374803D02*
G03X193307I591J0D01*
G01X195276D02*
G03X196457I591J0D01*
G01Y368504D02*
G03X195276I-590J0D01*
G01X193307D02*
G03X192126I-591J0D01*
G01Y374803D02*
G03X193307I591J0D01*
G01X195276D02*
X193307D01*
G01X192126D02*
X191339D01*
G01X195276D02*
X193307D01*
G01X192126D02*
X191339D01*
G01X197244D02*
X196457D01*
G01X197244D02*
X196457D01*
G01X197244Y373819D02*
X191339D01*
G01Y373622D02*
X197244D01*
G01X191339Y369685D02*
X197244D01*
G01Y369488D02*
X191339D01*
G01X196457Y368504D02*
X197244D01*
G01X196457D02*
X197244D01*
G01X193307D02*
X195276D01*
G01X191339D02*
X192126D01*
G01X193307D02*
X195276D01*
G01X191339D02*
X192126D01*
G01X197244D02*
Y374803D01*
G01Y368504D02*
Y374803D01*
G01X191339Y368504D02*
Y374803D01*
G01D02*
Y368504D01*
G01X195276Y827559D02*
G03X196457I591J0D01*
G01Y821260D02*
G03X195276I-590J0D01*
G01X193307D02*
G03X192126I-591J0D01*
G01Y827559D02*
G03X193307I591J0D01*
G01X195276D02*
G03X196457I591J0D01*
G01Y821260D02*
G03X195276I-590J0D01*
G01X193307D02*
G03X192126I-591J0D01*
G01Y827559D02*
G03X193307I591J0D01*
G01X195276D02*
X193307D01*
G01X192126D02*
X191339D01*
G01X195276D02*
X193307D01*
G01X192126D02*
X191339D01*
G01X197244D02*
X196457D01*
G01X197244D02*
X196457D01*
G01X197244Y826575D02*
X191339D01*
G01Y826378D02*
X197244D01*
G01X191339Y822441D02*
X197244D01*
G01Y822244D02*
X191339D01*
G01X196457Y821260D02*
X197244D01*
G01X196457D02*
X197244D01*
G01X193307D02*
X195276D01*
G01X191339D02*
X192126D01*
G01X193307D02*
X195276D01*
G01X191339D02*
X192126D01*
G01X197244D02*
Y827559D01*
G01Y821260D02*
Y827559D01*
G01X191339Y821260D02*
Y827559D01*
G01D02*
Y821260D01*
G01X196457Y1274016D02*
G03X195276I-590J0D01*
G01X193307D02*
G03X192126I-591J0D01*
G01X196457D02*
G03X195276I-590J0D01*
G01X193307D02*
G03X192126I-591J0D01*
G01X191339Y1275197D02*
X197244D01*
G01Y1275000D02*
X191339D01*
G01X196457Y1274016D02*
X197244D01*
G01X196457D02*
X197244D01*
G01X193307D02*
X195276D01*
G01X191339D02*
X192126D01*
G01X193307D02*
X195276D01*
G01X191339D02*
X192126D01*
G01X197244D02*
Y1280315D01*
G01Y1274016D02*
Y1280315D01*
G01X191339Y1274016D02*
Y1280315D01*
G01D02*
Y1274016D01*
G01X195276Y1280315D02*
G03X196457I591J0D01*
G01X192126D02*
G03X193307I591J0D01*
G01X195276D02*
G03X196457I591J0D01*
G01X192126D02*
G03X193307I591J0D01*
G01X195276D02*
X193307D01*
G01X192126D02*
X191339D01*
G01X195276D02*
X193307D01*
G01X192126D02*
X191339D01*
G01X197244D02*
X196457D01*
G01X197244D02*
X196457D01*
G01X197244Y1279331D02*
X191339D01*
G01Y1279134D02*
X197244D01*
G01X244094Y137933D02*
G03X246063Y139902I0J1969D01*
G01X231299Y139311D02*
G03X231890Y138720I591J0D01*
G01X238583D02*
G03X239173Y139311I-1J591D01*
G01X236417Y140492D02*
G03Y142461I0J984D01*
G01X234055D02*
G03Y140492I0J-984D01*
G01X236339Y153681D02*
G03I-1103J0D01*
G01X237795Y148406D02*
G03X238976Y149587I0J1181D01*
G01X231496D02*
G03X232677Y148406I1181J0D01*
G01X236811Y153681D02*
G03I-1575J0D01*
G01X224409Y139902D02*
G03X226378Y137933I1969J0D01*
G01X230709Y161673D02*
X229528Y160492D01*
G01X227756Y158996D02*
X224409Y155650D01*
G01X237721Y156752D02*
X236417Y154783D01*
G01X231745Y148861D02*
X234055Y153091D01*
G01X236220Y161673D02*
X230709D01*
G01X237402Y160492D02*
X229528D01*
G01X242717Y158996D02*
X227756D01*
G01X238976Y158130D02*
X242126D01*
G01X231496D02*
X227756D01*
G01Y156752D02*
X242126D01*
G01X236417Y154783D02*
X234055D01*
G01X236417Y153091D02*
X234055D01*
G01X237795Y148406D02*
X232677D01*
G01X246063Y148366D02*
X224409D01*
G01X239173Y145413D02*
X231299D01*
G01Y143839D02*
X239173D01*
G01X236417Y142461D02*
X234055D01*
G01Y140492D02*
X236417D01*
G01X238583Y138720D02*
X231890D01*
G01X244094Y137933D02*
X226378D01*
G01X246063Y139902D02*
Y155650D01*
G01X242717Y296988D02*
Y158996D01*
G01X242126Y299232D02*
Y156752D01*
G01X239173Y145413D02*
Y139311D01*
G01X238976Y158130D02*
Y149587D01*
G01X237402Y196949D02*
Y160492D01*
G01X236417Y154783D02*
Y153091D01*
G01X236220Y198130D02*
Y161673D01*
G01X234055Y153091D02*
Y154783D01*
G01X231496Y149587D02*
Y158130D01*
G01X231299Y145413D02*
Y139311D01*
G01X230709Y161673D02*
Y294311D01*
G01X229528Y160492D02*
Y295492D01*
G01X227756Y195787D02*
Y156752D01*
G01X224409Y155650D02*
Y139902D01*
G01X236417Y153091D02*
X238728Y148861D01*
G01X234055Y154783D02*
X232752Y156752D01*
G01X242717Y158996D02*
X246063Y155650D01*
G01X236220Y161673D02*
X237402Y160492D01*
G01X227272Y205432D02*
X227262Y205433D01*
G01X227280Y205429D02*
X227272Y205432D01*
G01X227288Y205424D02*
X227280Y205429D01*
G01X227272Y199133D02*
X227262Y199134D01*
G01X227281Y199130D02*
X227272Y199133D01*
G01X227288Y199124D02*
X227281Y199130D01*
G01X227272Y202282D02*
X227262Y202283D01*
G01X227281Y202279D02*
X227272Y202282D01*
G01X227288Y202274D02*
X227281Y202279D01*
G01X227272Y208581D02*
X227262Y208583D01*
G01X227281Y208578D02*
X227272Y208581D01*
G01X227288Y208573D02*
X227281Y208578D01*
G01X227272Y211731D02*
X227262Y211732D01*
G01X227281Y211728D02*
X227272Y211731D01*
G01X227288Y211723D02*
X227281Y211728D01*
G01X226358Y197948D02*
Y197942D01*
G01X226357Y197952D02*
X226358Y197948D01*
G01X226356Y197953D02*
X226357Y197952D01*
G01X226358Y201098D02*
Y201091D01*
G01X226357Y201101D02*
X226358Y201098D01*
G01X226356Y201102D02*
X226357Y201101D01*
G01X226358Y204247D02*
Y204241D01*
G01X226357Y204251D02*
X226358Y204247D01*
G01X226356Y204252D02*
X226357Y204251D01*
G01X226358Y207397D02*
Y207391D01*
G01X226357Y207400D02*
X226358Y207397D01*
G01X226356Y207402D02*
X226357Y207400D01*
G01X226358Y210546D02*
Y210540D01*
G01X226357Y210550D02*
X226358Y210546D01*
G01X226356Y210551D02*
X226357Y210550D01*
G01X240729Y166148D02*
X240728Y166156D01*
G01X240730Y166144D02*
X240729Y166148D01*
G01X240731Y166142D02*
X240730Y166144D01*
G01X240729Y171148D02*
X240728Y171156D01*
G01X240730Y171144D02*
X240729Y171148D01*
G01X240731Y171142D02*
X240730Y171144D01*
G01X240729Y176148D02*
X240728Y176156D01*
G01X240730Y176144D02*
X240729Y176148D01*
G01X240731Y176142D02*
X240730Y176144D01*
G01X240729Y181148D02*
X240728Y181156D01*
G01X240730Y181144D02*
X240729Y181148D01*
G01X240731Y181142D02*
X240730Y181144D01*
G01X240729Y186148D02*
X240728Y186156D01*
G01X240730Y186144D02*
X240729Y186148D01*
G01X240731Y186142D02*
X240730Y186144D01*
G01X240729Y191148D02*
X240728Y191156D01*
G01X240730Y191144D02*
X240729Y191148D01*
G01X240731Y191142D02*
X240730Y191144D01*
G01X240729Y196148D02*
X240728Y196156D01*
G01X240730Y196144D02*
X240729Y196148D01*
G01X240731Y196142D02*
X240730Y196144D01*
G01X226342Y201105D02*
X226356Y201102D01*
G01X226330Y201112D02*
X226342Y201105D01*
G01X226318Y201131D02*
X226330Y201112D01*
G01X226342Y210554D02*
X226356Y210551D01*
G01X226330Y210561D02*
X226342Y210554D01*
G01X226318Y210580D02*
X226330Y210561D01*
G01X226341Y204255D02*
X226356Y204252D01*
G01X226329Y204263D02*
X226341Y204255D01*
G01X226317Y204283D02*
X226329Y204263D01*
G01X227303Y197986D02*
Y197979D01*
G01X227302Y197991D02*
X227303Y197986D01*
G01X227302Y197992D02*
Y197991D01*
G01X227303Y201136D02*
Y201128D01*
G01X227302Y201141D02*
X227303Y201136D01*
G01X227302Y201142D02*
Y201141D01*
G01X227303Y204285D02*
Y204278D01*
G01X227302Y204290D02*
X227303Y204285D01*
G01X227302Y204291D02*
Y204290D01*
G01X227303Y207435D02*
Y207428D01*
G01X227302Y207440D02*
X227303Y207435D01*
G01X227302Y207441D02*
Y207440D01*
G01X227303Y210585D02*
Y210577D01*
G01X227302Y210589D02*
X227303Y210585D01*
G01X227302Y210591D02*
Y210589D01*
G01X226341Y197956D02*
X226356Y197953D01*
G01X226328Y197964D02*
X226341Y197956D01*
G01X226317Y197985D02*
X226328Y197964D01*
G01X227302Y199115D02*
X227303Y199108D01*
G01X227301Y199121D02*
X227302Y199115D01*
G01X227298Y199127D02*
X227301Y199121D01*
G01X227302Y202265D02*
X227303Y202258D01*
G01X227301Y202271D02*
X227302Y202265D01*
G01X227298Y202277D02*
X227301Y202271D01*
G01X227302Y205414D02*
X227303Y205407D01*
G01X227301Y205420D02*
X227302Y205414D01*
G01X227298Y205426D02*
X227301Y205420D01*
G01X227302Y208564D02*
X227303Y208557D01*
G01X227301Y208570D02*
X227302Y208564D01*
G01X227298Y208576D02*
X227301Y208570D01*
G01X227302Y211713D02*
X227303Y211707D01*
G01X227301Y211720D02*
X227302Y211713D01*
G01X227298Y211726D02*
X227301Y211720D01*
G01X227264Y197948D02*
X227265Y197942D01*
G01X227263Y197952D02*
X227264Y197948D01*
G01X227262Y197953D02*
X227263Y197952D01*
G01X227264Y201097D02*
X227265Y201091D01*
G01X227263Y201101D02*
X227264Y201097D01*
G01X227262Y201102D02*
X227263Y201101D01*
G01X227264Y204247D02*
X227265Y204241D01*
G01X227263Y204251D02*
X227264Y204247D01*
G01X227262Y204252D02*
X227263Y204251D01*
G01X227264Y207396D02*
X227265Y207391D01*
G01X227263Y207400D02*
X227264Y207396D01*
G01X227262Y207402D02*
X227263Y207400D01*
G01X227264Y210546D02*
X227265Y210540D01*
G01X227263Y210550D02*
X227264Y210546D01*
G01X227262Y210551D02*
X227263Y210550D01*
G01X239744Y166189D02*
Y166198D01*
G01X239745Y166183D02*
X239744Y166189D01*
G01X239746Y166181D02*
X239745Y166183D01*
G01X239744Y171189D02*
Y171198D01*
G01X239745Y171183D02*
X239744Y171189D01*
G01X239746Y171181D02*
X239745Y171183D01*
G01X239744Y176189D02*
Y176198D01*
G01X239745Y176183D02*
X239744Y176189D01*
G01X239746Y176181D02*
X239745Y176183D01*
G01X239744Y181189D02*
Y181198D01*
G01X239745Y181183D02*
X239744Y181189D01*
G01X239746Y181181D02*
X239745Y181183D01*
G01X239744Y186189D02*
Y186198D01*
G01X239745Y186183D02*
X239744Y186189D01*
G01X239746Y186181D02*
X239745Y186183D01*
G01X239744Y191189D02*
Y191198D01*
G01X239745Y191183D02*
X239744Y191189D01*
G01X239746Y191181D02*
X239745Y191183D01*
G01X239744Y196189D02*
Y196198D01*
G01X239745Y196183D02*
X239744Y196189D01*
G01X239746Y196181D02*
X239745Y196183D01*
G01X240720Y166325D02*
X240728Y166299D01*
G01X240711Y166352D02*
X240720Y166325D01*
G01X240699Y166378D02*
X240711Y166352D01*
G01X240720Y171325D02*
X240728Y171299D01*
G01X240711Y171352D02*
X240720Y171325D01*
G01X240699Y171378D02*
X240711Y171352D01*
G01X240720Y176325D02*
X240728Y176299D01*
G01X240711Y176352D02*
X240720Y176325D01*
G01X240699Y176378D02*
X240711Y176352D01*
G01X240720Y181325D02*
X240728Y181299D01*
G01X240711Y181352D02*
X240720Y181325D01*
G01X240699Y181378D02*
X240711Y181352D01*
G01X240720Y186325D02*
X240728Y186299D01*
G01X240711Y186352D02*
X240720Y186325D01*
G01X240699Y186378D02*
X240711Y186352D01*
G01X240720Y191325D02*
X240728Y191299D01*
G01X240711Y191352D02*
X240720Y191325D01*
G01X240699Y191378D02*
X240711Y191352D01*
G01X240720Y196325D02*
X240728Y196299D01*
G01X240711Y196352D02*
X240720Y196325D01*
G01X240699Y196378D02*
X240711Y196352D01*
G01X226337Y207407D02*
X226356Y207402D01*
G01X226323Y207419D02*
X226337Y207407D01*
G01X226317Y207437D02*
X226323Y207419D01*
G01X240716Y166173D02*
X240727Y166157D01*
G01X240691Y166181D02*
X240716Y166173D01*
G01Y171173D02*
X240727Y171157D01*
G01X240691Y171181D02*
X240716Y171173D01*
G01Y176173D02*
X240727Y176157D01*
G01X240691Y176181D02*
X240716Y176173D01*
G01Y181173D02*
X240727Y181157D01*
G01X240691Y181181D02*
X240716Y181173D01*
G01Y186173D02*
X240727Y186157D01*
G01X240691Y186181D02*
X240716Y186173D01*
G01Y191173D02*
X240727Y191157D01*
G01X240691Y191181D02*
X240716Y191173D01*
G01X226319Y207431D02*
Y207428D01*
G01X226320Y207426D02*
X226319Y207431D01*
G01X226330Y207411D02*
X226320Y207426D01*
G01X226354Y207402D02*
X226330Y207411D01*
G01X240711Y166176D02*
X240692Y166181D01*
G01X240726Y166162D02*
X240711Y166176D01*
G01X240731Y166142D02*
X240726Y166162D01*
G01X240711Y171176D02*
X240692Y171181D01*
G01X240726Y171162D02*
X240711Y171176D01*
G01X240731Y171142D02*
X240726Y171162D01*
G01X240711Y176176D02*
X240692Y176181D01*
G01X240726Y176162D02*
X240711Y176176D01*
G01X240731Y176142D02*
X240726Y176162D01*
G01X240711Y181176D02*
X240692Y181181D01*
G01X240726Y181162D02*
X240711Y181176D01*
G01X240731Y181142D02*
X240726Y181162D01*
G01X240711Y186176D02*
X240692Y186181D01*
G01X240726Y186162D02*
X240711Y186176D01*
G01X240731Y186142D02*
X240726Y186162D01*
G01X240711Y191176D02*
X240692Y191181D01*
G01X240726Y191162D02*
X240711Y191176D01*
G01X240731Y191142D02*
X240726Y191162D01*
G01X240711Y196176D02*
X240692Y196181D01*
G01X240726Y196162D02*
X240711Y196176D01*
G01X240731Y196142D02*
X240726Y196162D01*
G01X227296Y205415D02*
X227288Y205424D01*
G01X227300Y205405D02*
X227296Y205415D01*
G01X227302Y205394D02*
X227300Y205405D01*
G01X227296Y199116D02*
X227288Y199124D01*
G01X227300Y199106D02*
X227296Y199116D01*
G01X227302Y199094D02*
X227300Y199106D01*
G01X227296Y202265D02*
X227288Y202274D01*
G01X227300Y202255D02*
X227296Y202265D01*
G01X227302Y202244D02*
X227300Y202255D01*
G01X227296Y208565D02*
X227288Y208573D01*
G01X227300Y208554D02*
X227296Y208565D01*
G01X227302Y208543D02*
X227300Y208554D01*
G01X227296Y211714D02*
X227288Y211723D01*
G01X227300Y211704D02*
X227296Y211714D01*
G01X227302Y211693D02*
X227300Y211704D01*
G01X240695Y166279D02*
X240699Y166378D01*
G01X240690Y166207D02*
X240695Y166279D01*
G01X240692Y166181D02*
X240690Y166207D01*
G01X240695Y171279D02*
X240699Y171378D01*
G01X240690Y171207D02*
X240695Y171279D01*
G01X240692Y171181D02*
X240690Y171207D01*
G01X240695Y176279D02*
X240699Y176378D01*
G01X240690Y176207D02*
X240695Y176279D01*
G01X240692Y176181D02*
X240690Y176207D01*
G01X240695Y181279D02*
X240699Y181378D01*
G01X240690Y181207D02*
X240695Y181279D01*
G01X240692Y181181D02*
X240690Y181207D01*
G01X240695Y186279D02*
X240699Y186378D01*
G01X240690Y186207D02*
X240695Y186279D01*
G01X240692Y186181D02*
X240690Y186207D01*
G01X240695Y191279D02*
X240699Y191378D01*
G01X240690Y191207D02*
X240695Y191279D01*
G01X240692Y191181D02*
X240690Y191207D01*
G01X240695Y196279D02*
X240699Y196378D01*
G01X240690Y196207D02*
X240695Y196279D01*
G01X240692Y196181D02*
X240690Y196207D01*
G01X226319Y210585D02*
Y210577D01*
G01X226318Y210589D02*
X226319Y210585D01*
G01X226318Y210580D02*
Y210589D01*
G01X226359Y211917D02*
X226358Y211929D01*
G01X226356Y211904D02*
X226359Y211917D01*
G01X226356Y211890D02*
Y211904D01*
G01X226359Y208767D02*
X226358Y208780D01*
G01X226356Y208754D02*
X226359Y208767D01*
G01X226356Y208741D02*
Y208754D01*
G01X226359Y205618D02*
X226358Y205630D01*
G01X226356Y205605D02*
X226359Y205618D01*
G01X226356Y205591D02*
Y205605D01*
G01X226359Y202468D02*
X226358Y202480D01*
G01X226356Y202455D02*
X226359Y202468D01*
G01X226356Y202441D02*
Y202455D01*
G01X226359Y199319D02*
X226358Y199331D01*
G01X226356Y199306D02*
X226359Y199319D01*
G01X226356Y199292D02*
Y199306D01*
G01X239745Y194802D02*
X239746Y194803D01*
G01X239744Y194796D02*
X239745Y194802D01*
G01X239744Y194787D02*
Y194796D01*
G01X239745Y189802D02*
X239746Y189803D01*
G01X239744Y189796D02*
X239745Y189802D01*
G01X239744Y189787D02*
Y189796D01*
G01X239745Y184802D02*
X239746Y184803D01*
G01X239744Y184796D02*
X239745Y184802D01*
G01X239744Y184787D02*
Y184796D01*
G01X239745Y179802D02*
X239746Y179803D01*
G01X239744Y179796D02*
X239745Y179802D01*
G01X239744Y179787D02*
Y179796D01*
G01X239745Y174802D02*
X239746Y174803D01*
G01X239744Y174796D02*
X239745Y174802D01*
G01X239744Y174787D02*
Y174796D01*
G01X239745Y169802D02*
X239746Y169803D01*
G01X239744Y169796D02*
X239745Y169802D01*
G01X239744Y169787D02*
Y169796D01*
G01X239745Y164802D02*
X239746Y164803D01*
G01X239744Y164796D02*
X239745Y164802D01*
G01X239744Y164787D02*
Y164796D01*
G01X226319Y201132D02*
Y201128D01*
G01X226320Y201126D02*
X226319Y201132D01*
G01X226332Y201111D02*
X226320Y201126D01*
G01X226357Y201102D02*
X226332Y201111D01*
G01X226319Y204282D02*
Y204278D01*
G01X226320Y204276D02*
X226319Y204282D01*
G01X226332Y204260D02*
X226320Y204276D01*
G01X226356Y204252D02*
X226332Y204260D01*
G01X226319Y210581D02*
Y210577D01*
G01X226320Y210575D02*
X226319Y210581D01*
G01X226332Y210559D02*
X226320Y210575D01*
G01X226356Y210551D02*
X226332Y210559D01*
G01X226319Y197983D02*
Y197979D01*
G01X226320Y197976D02*
X226319Y197983D01*
G01X226332Y197961D02*
X226320Y197976D01*
G01X226356Y197953D02*
X226332Y197961D01*
G01X240716Y196173D02*
X240727Y196157D01*
G01X240691Y196181D02*
X240716Y196173D01*
G01X226356Y210380D02*
X226355Y210393D01*
G01X226359Y210367D02*
X226356Y210380D01*
G01X226358Y210354D02*
X226359Y210367D01*
G01X226356Y207230D02*
X226355Y207244D01*
G01X226359Y207217D02*
X226356Y207230D01*
G01X226358Y207205D02*
X226359Y207217D01*
G01X226356Y204081D02*
X226355Y204094D01*
G01X226359Y204068D02*
X226356Y204081D01*
G01X226358Y204055D02*
X226359Y204068D01*
G01X226356Y200931D02*
X226355Y200944D01*
G01X226359Y200918D02*
X226356Y200931D01*
G01X226358Y200906D02*
X226359Y200918D01*
G01X226356Y197781D02*
X226355Y197795D01*
G01X226359Y197769D02*
X226356Y197781D01*
G01X226358Y197756D02*
X226359Y197769D01*
G01X227266Y211904D02*
X227267Y211890D01*
G01X227263Y211917D02*
X227266Y211904D01*
G01X227264Y211929D02*
X227263Y211917D01*
G01X227266Y208754D02*
X227267Y208741D01*
G01X227263Y208767D02*
X227266Y208754D01*
G01X227264Y208780D02*
X227263Y208767D01*
G01X227266Y205604D02*
X227267Y205591D01*
G01X227263Y205617D02*
X227266Y205604D01*
G01X227264Y205630D02*
X227263Y205617D01*
G01X227266Y202455D02*
X227267Y202441D01*
G01X227263Y202468D02*
X227266Y202455D01*
G01X227264Y202480D02*
X227263Y202468D01*
G01X227266Y199305D02*
X227267Y199292D01*
G01X227263Y199318D02*
X227266Y199305D01*
G01X227264Y199331D02*
X227263Y199318D01*
G01X226319Y204285D02*
Y204278D01*
G01X226318Y204290D02*
X226319Y204285D01*
G01X226317Y204283D02*
X226318Y204290D01*
G01X227263Y210367D02*
X227264Y210354D01*
G01X227266Y210380D02*
X227263Y210367D01*
G01X227267Y210393D02*
X227266Y210380D01*
G01X227263Y207217D02*
X227264Y207205D01*
G01X227266Y207230D02*
X227263Y207217D01*
G01X227267Y207244D02*
X227266Y207230D01*
G01X227263Y204068D02*
X227264Y204055D01*
G01X227266Y204081D02*
X227263Y204068D01*
G01X227267Y204094D02*
X227266Y204081D01*
G01X227263Y200918D02*
X227264Y200906D01*
G01X227266Y200931D02*
X227263Y200918D01*
G01X227267Y200944D02*
X227266Y200931D01*
G01X227263Y197769D02*
X227264Y197756D01*
G01X227266Y197781D02*
X227263Y197769D01*
G01X227267Y197795D02*
X227266Y197781D01*
G01X226319Y197987D02*
Y197979D01*
G01X226318Y197991D02*
X226319Y197987D01*
G01X226317Y197985D02*
X226318Y197991D01*
G01X227294Y199132D02*
X227298Y199127D01*
G01X227289Y199137D02*
X227294Y199132D01*
G01X227283Y199141D02*
X227289Y199137D01*
G01X227277Y199143D02*
X227283Y199141D01*
G01X227270Y199145D02*
X227277Y199143D01*
G01X227264Y199145D02*
X227270D01*
G01X227294Y202282D02*
X227298Y202277D01*
G01X227289Y202286D02*
X227294Y202282D01*
G01X227283Y202290D02*
X227289Y202286D01*
G01X227277Y202293D02*
X227283Y202290D01*
G01X227270Y202294D02*
X227277Y202293D01*
G01X227264Y202295D02*
X227270Y202294D01*
G01X227294Y205431D02*
X227298Y205426D01*
G01X227289Y205436D02*
X227294Y205431D01*
G01X227283Y205440D02*
X227289Y205436D01*
G01X227277Y205442D02*
X227283Y205440D01*
G01X227270Y205444D02*
X227277Y205442D01*
G01X227264Y205444D02*
X227270D01*
G01X227294Y208581D02*
X227298Y208576D01*
G01X227289Y208585D02*
X227294Y208581D01*
G01X227283Y208589D02*
X227289Y208585D01*
G01X227277Y208592D02*
X227283Y208589D01*
G01X227270Y208594D02*
X227277Y208592D01*
G01X227264Y208594D02*
X227270D01*
G01X227294Y211731D02*
X227298Y211726D01*
G01X227289Y211735D02*
X227294Y211731D01*
G01X227283Y211739D02*
X227289Y211735D01*
G01X227277Y211741D02*
X227283Y211739D01*
G01X227270Y211743D02*
X227277Y211741D01*
G01X227264Y211744D02*
X227270Y211743D01*
G01X226320Y197971D02*
X226319Y197979D01*
G01X226322Y197965D02*
X226320Y197971D01*
G01X226326Y197958D02*
X226322Y197965D01*
G01X226330Y197952D02*
X226326Y197958D01*
G01X226337Y197948D02*
X226330Y197952D01*
G01X226343Y197944D02*
X226337Y197948D01*
G01X226351Y197943D02*
X226343Y197944D01*
G01X226358Y197942D02*
X226351Y197943D01*
G01X226320Y201121D02*
X226319Y201128D01*
G01X226322Y201114D02*
X226320Y201121D01*
G01X226326Y201108D02*
X226322Y201114D01*
G01X226330Y201102D02*
X226326Y201108D01*
G01X226337Y201097D02*
X226330Y201102D01*
G01X226343Y201094D02*
X226337Y201097D01*
G01X226351Y201092D02*
X226343Y201094D01*
G01X226358Y201091D02*
X226351Y201092D01*
G01X226320Y204270D02*
X226319Y204278D01*
G01X226322Y204264D02*
X226320Y204270D01*
G01X226326Y204257D02*
X226322Y204264D01*
G01X226330Y204252D02*
X226326Y204257D01*
G01X226337Y204247D02*
X226330Y204252D01*
G01X226343Y204244D02*
X226337Y204247D01*
G01X226351Y204242D02*
X226343Y204244D01*
G01X226358Y204241D02*
X226351Y204242D01*
G01X226320Y207420D02*
X226319Y207428D01*
G01X226322Y207413D02*
X226320Y207420D01*
G01X226326Y207407D02*
X226322Y207413D01*
G01X226330Y207401D02*
X226326Y207407D01*
G01X226337Y207396D02*
X226330Y207401D01*
G01X226343Y207393D02*
X226337Y207396D01*
G01X226351Y207391D02*
X226343Y207393D01*
G01X226358Y207391D02*
X226351D01*
G01X226320Y210570D02*
X226319Y210577D01*
G01X226322Y210563D02*
X226320Y210570D01*
G01X226326Y210557D02*
X226322Y210563D01*
G01X226330Y210551D02*
X226326Y210557D01*
G01X226337Y210546D02*
X226330Y210551D01*
G01X226343Y210543D02*
X226337Y210546D01*
G01X226351Y210541D02*
X226343Y210543D01*
G01X226358Y210540D02*
X226351Y210541D01*
G01X227273Y199133D02*
X227282Y199128D01*
G01X227262Y199134D02*
X227273Y199133D01*
G01Y202282D02*
X227282Y202278D01*
G01X227262Y202283D02*
X227273Y202282D01*
G01Y205432D02*
X227282Y205428D01*
G01X227262Y205433D02*
X227273Y205432D01*
G01Y208581D02*
X227282Y208577D01*
G01X227262Y208583D02*
X227273Y208581D01*
G01Y211731D02*
X227282Y211727D01*
G01X227262Y211732D02*
X227273Y211731D01*
G01X226332Y211724D02*
X226356Y211732D01*
G01X226320Y211709D02*
X226332Y211724D01*
G01X226319Y211703D02*
X226320Y211709D01*
G01X226332Y208574D02*
X226356Y208583D01*
G01X226320Y208560D02*
X226332Y208574D01*
G01X226319Y208553D02*
X226320Y208560D01*
G01X226332Y205425D02*
X226356Y205433D01*
G01X226320Y205410D02*
X226332Y205425D01*
G01X226319Y205404D02*
X226320Y205410D01*
G01X226332Y202275D02*
X226356Y202283D01*
G01X226320Y202261D02*
X226332Y202275D01*
G01X226319Y202254D02*
X226320Y202261D01*
G01X226332Y199126D02*
X226356Y199134D01*
G01X226320Y199111D02*
X226332Y199126D01*
G01X226319Y199104D02*
X226320Y199111D01*
G01X227281Y197945D02*
X227284Y197947D01*
G01X227278Y197944D02*
X227281Y197945D01*
G01X227274Y197943D02*
X227278Y197944D01*
G01X227271Y197942D02*
X227274Y197943D01*
G01X227267Y197942D02*
X227271D01*
G01X227264D02*
X227267D01*
G01X226341Y199142D02*
X226338Y199140D01*
G01X226344Y199143D02*
X226341Y199142D01*
G01X226348Y199144D02*
X226344Y199143D01*
G01X226351Y199144D02*
X226348D01*
G01X226355Y199145D02*
X226351Y199144D01*
G01X226358Y199145D02*
X226355D01*
G01X227281Y201095D02*
X227284Y201096D01*
G01X227278Y201094D02*
X227281Y201095D01*
G01X227274Y201093D02*
X227278Y201094D01*
G01X227271Y201092D02*
X227274Y201093D01*
G01X227267Y201091D02*
X227271Y201092D01*
G01X227264Y201091D02*
X227267D01*
G01X226341Y202291D02*
X226338Y202290D01*
G01X226344Y202293D02*
X226341Y202291D01*
G01X226348Y202294D02*
X226344Y202293D01*
G01X226351Y202294D02*
X226348D01*
G01X226355Y202295D02*
X226351Y202294D01*
G01X226358Y202295D02*
X226355D01*
G01X227281Y204244D02*
X227284Y204246D01*
G01X227278Y204243D02*
X227281Y204244D01*
G01X227274Y204242D02*
X227278Y204243D01*
G01X227271Y204241D02*
X227274Y204242D01*
G01X227267Y204241D02*
X227271D01*
G01X227264D02*
X227267D01*
G01X226341Y205441D02*
X226338Y205439D01*
G01X226344Y205442D02*
X226341Y205441D01*
G01X226348Y205443D02*
X226344Y205442D01*
G01X226351Y205444D02*
X226348Y205443D01*
G01X226355Y205444D02*
X226351D01*
G01X226358D02*
X226355D01*
G01X227281Y207394D02*
X227284Y207396D01*
G01X227278Y207393D02*
X227281Y207394D01*
G01X227274Y207392D02*
X227278Y207393D01*
G01X227271Y207391D02*
X227274Y207392D01*
G01X227267Y207391D02*
X227271D01*
G01X227264D02*
X227267D01*
G01X226341Y208591D02*
X226338Y208589D01*
G01X226344Y208592D02*
X226341Y208591D01*
G01X226348Y208593D02*
X226344Y208592D01*
G01X226351Y208593D02*
X226348D01*
G01X226355Y208594D02*
X226351Y208593D01*
G01X226358Y208594D02*
X226355D01*
G01X227281Y210544D02*
X227284Y210545D01*
G01X227278Y210543D02*
X227281Y210544D01*
G01X227274Y210541D02*
X227278Y210543D01*
G01X227271Y210541D02*
X227274D01*
G01X227267Y210540D02*
X227271Y210541D01*
G01X227264Y210540D02*
X227267D01*
G01X226341Y211740D02*
X226338Y211739D01*
G01X226344Y211741D02*
X226341Y211740D01*
G01X226348Y211743D02*
X226344Y211741D01*
G01X226351Y211743D02*
X226348D01*
G01X226355Y211744D02*
X226351Y211743D01*
G01X226358Y211744D02*
X226355D01*
G01X225572Y201142D02*
X225138D01*
G01X225945D02*
X225572D01*
G01Y207441D02*
X225138D01*
G01X225945D02*
X225572D01*
G01Y210591D02*
X225138D01*
G01X225945D02*
X225572D01*
G01X227303Y211699D02*
Y211706D01*
G01Y211695D02*
Y211699D01*
G01X227302Y211693D02*
X227303Y211695D01*
G01Y208550D02*
Y208557D01*
G01Y208545D02*
Y208550D01*
G01X227302Y208543D02*
X227303Y208545D01*
G01Y205400D02*
Y205407D01*
G01Y205396D02*
Y205400D01*
G01X227302Y205394D02*
X227303Y205396D01*
G01Y202250D02*
Y202257D01*
G01Y202246D02*
Y202250D01*
G01X227302Y202244D02*
X227303Y202246D01*
G01Y199101D02*
Y199108D01*
G01Y199096D02*
Y199101D01*
G01X227302Y199094D02*
X227303Y199096D01*
G01X226319Y207435D02*
Y207428D01*
G01X226318Y207440D02*
X226319Y207435D01*
G01X226317Y207437D02*
X226318Y207440D01*
G01X226319Y201136D02*
Y201128D01*
G01X226318Y201141D02*
X226319Y201136D01*
G01X226317Y201138D02*
X226318Y201141D01*
G01X226322Y199114D02*
X226317Y199094D01*
G01X226336Y199129D02*
X226322Y199114D01*
G01X226356Y199134D02*
X226336Y199129D01*
G01X226322Y202264D02*
X226317Y202244D01*
G01X226336Y202278D02*
X226322Y202264D01*
G01X226356Y202283D02*
X226336Y202278D01*
G01X226322Y205413D02*
X226317Y205394D01*
G01X226336Y205428D02*
X226322Y205413D01*
G01X226356Y205433D02*
X226336Y205428D01*
G01X226322Y208563D02*
X226317Y208543D01*
G01X226336Y208578D02*
X226322Y208563D01*
G01X226356Y208583D02*
X226336Y208578D01*
G01X226322Y211713D02*
X226317Y211693D01*
G01X226336Y211727D02*
X226322Y211713D01*
G01X226356Y211732D02*
X226336Y211727D01*
G01X227296Y197972D02*
X227302Y197992D01*
G01X227282Y197958D02*
X227296Y197972D01*
G01X227262Y197953D02*
X227282Y197958D01*
G01X227296Y201122D02*
X227302Y201142D01*
G01X227282Y201108D02*
X227296Y201122D01*
G01X227262Y201102D02*
X227282Y201108D01*
G01X227296Y204272D02*
X227302Y204291D01*
G01X227282Y204257D02*
X227296Y204272D01*
G01X227262Y204252D02*
X227282Y204257D01*
G01X227296Y207421D02*
X227302Y207441D01*
G01X227282Y207407D02*
X227296Y207421D01*
G01X227262Y207402D02*
X227282Y207407D01*
G01X227296Y210571D02*
X227302Y210591D01*
G01X227282Y210557D02*
X227296Y210571D01*
G01X227262Y210551D02*
X227282Y210557D01*
G01X227264Y211737D02*
Y211744D01*
G01X227263Y211734D02*
X227264Y211737D01*
G01X227262Y211732D02*
X227263Y211734D01*
G01X227264Y208588D02*
Y208594D01*
G01X227263Y208584D02*
X227264Y208588D01*
G01X227262Y208583D02*
X227263Y208584D01*
G01X227264Y205438D02*
Y205444D01*
G01X227263Y205435D02*
X227264Y205438D01*
G01X227262Y205433D02*
X227263Y205435D01*
G01X227264Y202289D02*
Y202295D01*
G01X227263Y202285D02*
X227264Y202289D01*
G01X227262Y202283D02*
X227263Y202285D01*
G01X227264Y199139D02*
Y199145D01*
G01X227263Y199135D02*
X227264Y199139D01*
G01X227262Y199134D02*
X227263Y199135D01*
G01X240729Y194796D02*
X240728Y194787D01*
G01X240730Y194802D02*
X240729Y194796D01*
G01X240731Y194803D02*
X240730Y194802D01*
G01X240729Y189796D02*
X240728Y189787D01*
G01X240730Y189802D02*
X240729Y189796D01*
G01X240731Y189803D02*
X240730Y189802D01*
G01X240729Y184796D02*
X240728Y184787D01*
G01X240730Y184802D02*
X240729Y184796D01*
G01X240731Y184803D02*
X240730Y184802D01*
G01X240729Y179796D02*
X240728Y179787D01*
G01X240730Y179802D02*
X240729Y179796D01*
G01X240731Y179803D02*
X240730Y179802D01*
G01X240729Y174796D02*
X240728Y174787D01*
G01X240730Y174802D02*
X240729Y174796D01*
G01X240731Y174803D02*
X240730Y174802D01*
G01X240729Y169796D02*
X240728Y169787D01*
G01X240730Y169802D02*
X240729Y169796D01*
G01X240731Y169803D02*
X240730Y169802D01*
G01X240729Y164796D02*
X240728Y164787D01*
G01X240730Y164802D02*
X240729Y164796D01*
G01X240731Y164803D02*
X240730Y164802D01*
G01X226319Y211699D02*
Y211707D01*
G01X226318Y211694D02*
X226319Y211699D01*
G01X226317Y211693D02*
X226318Y211694D01*
G01X226319Y208550D02*
Y208557D01*
G01X226318Y208545D02*
X226319Y208550D01*
G01X226317Y208543D02*
X226318Y208545D01*
G01X226319Y205400D02*
Y205407D01*
G01X226318Y205395D02*
X226319Y205400D01*
G01X226317Y205394D02*
X226318Y205395D01*
G01X226319Y202250D02*
Y202258D01*
G01X226318Y202246D02*
X226319Y202250D01*
G01X226317Y202244D02*
X226318Y202246D01*
G01X226319Y199101D02*
Y199108D01*
G01X226318Y199096D02*
X226319Y199101D01*
G01X226317Y199094D02*
X226318Y199096D01*
G01X227301Y210565D02*
X227303Y210577D01*
G01X227294Y210554D02*
X227301Y210565D01*
G01X227284Y210545D02*
X227294Y210554D01*
G01X227301Y207415D02*
X227303Y207428D01*
G01X227294Y207404D02*
X227301Y207415D01*
G01X227284Y207396D02*
X227294Y207404D01*
G01X227301Y204265D02*
X227303Y204278D01*
G01X227294Y204254D02*
X227301Y204265D01*
G01X227284Y204246D02*
X227294Y204254D01*
G01X227301Y201116D02*
X227303Y201128D01*
G01X227294Y201105D02*
X227301Y201116D01*
G01X227284Y201096D02*
X227294Y201105D01*
G01X227301Y197966D02*
X227303Y197979D01*
G01X227294Y197955D02*
X227301Y197966D01*
G01X227284Y197947D02*
X227294Y197955D01*
G01X226357Y211737D02*
Y211744D01*
G01Y211733D02*
Y211737D01*
G01X226356Y211732D02*
X226357Y211733D01*
G01Y208588D02*
Y208594D01*
G01Y208584D02*
Y208588D01*
G01X226356Y208583D02*
X226357Y208584D01*
G01Y205438D02*
Y205444D01*
G01Y205434D02*
Y205438D01*
G01X226356Y205433D02*
X226357Y205434D01*
G01Y202289D02*
Y202295D01*
G01Y202285D02*
Y202289D01*
G01X226356Y202283D02*
X226357Y202285D01*
G01Y199139D02*
Y199145D01*
G01Y199135D02*
Y199139D01*
G01X226356Y199134D02*
X226357Y199135D01*
G01X226320Y211713D02*
X226319Y211707D01*
G01X226321Y211719D02*
X226320Y211713D01*
G01X226324Y211725D02*
X226321Y211719D01*
G01X226328Y211730D02*
X226324Y211725D01*
G01X226333Y211735D02*
X226328Y211730D01*
G01X226338Y211739D02*
X226333Y211735D01*
G01X226320Y208563D02*
X226319Y208557D01*
G01X226321Y208570D02*
X226320Y208563D01*
G01X226324Y208575D02*
X226321Y208570D01*
G01X226328Y208581D02*
X226324Y208575D01*
G01X226333Y208585D02*
X226328Y208581D01*
G01X226338Y208589D02*
X226333Y208585D01*
G01X226320Y205414D02*
X226319Y205407D01*
G01X226321Y205420D02*
X226320Y205414D01*
G01X226324Y205426D02*
X226321Y205420D01*
G01X226328Y205431D02*
X226324Y205426D01*
G01X226333Y205435D02*
X226328Y205431D01*
G01X226338Y205439D02*
X226333Y205435D01*
G01X226320Y202264D02*
X226319Y202258D01*
G01X226321Y202270D02*
X226320Y202264D01*
G01X226324Y202276D02*
X226321Y202270D01*
G01X226328Y202281D02*
X226324Y202276D01*
G01X226333Y202286D02*
X226328Y202281D01*
G01X226338Y202290D02*
X226333Y202286D01*
G01X226320Y199115D02*
X226319Y199108D01*
G01X226321Y199121D02*
X226320Y199115D01*
G01X226324Y199126D02*
X226321Y199121D01*
G01X226328Y199132D02*
X226324Y199126D01*
G01X226333Y199136D02*
X226328Y199132D01*
G01X226338Y199140D02*
X226333Y199136D01*
G01X227274Y210553D02*
X227262Y210551D01*
G01X227285Y210558D02*
X227274Y210553D01*
G01Y207404D02*
X227262Y207402D01*
G01X227285Y207409D02*
X227274Y207404D01*
G01Y204254D02*
X227262Y204252D01*
G01X227285Y204259D02*
X227274Y204254D01*
G01Y201104D02*
X227262Y201102D01*
G01X227285Y201109D02*
X227274Y201104D01*
G01Y197955D02*
X227262Y197953D01*
G01X227285Y197960D02*
X227274Y197955D01*
G01X226317Y207437D02*
X226206Y207441D01*
G01X226317Y201138D02*
X226206Y201142D01*
G01X226317Y210587D02*
X226206Y210591D01*
G01X227264Y211929D02*
X226358D01*
G01X227303Y211890D02*
X226319D01*
G01X227262Y211732D02*
X221378D01*
G01Y211693D02*
X227302D01*
G01Y210591D02*
X221378D01*
G01X227262Y210551D02*
X221378D01*
G01X226319Y210394D02*
X227303D01*
G01X226358Y210354D02*
X227264D01*
G01Y208780D02*
X226358D01*
G01X227303Y208740D02*
X226319D01*
G01X227262Y208583D02*
X221378D01*
G01Y208543D02*
X227302D01*
G01Y207441D02*
X221378D01*
G01X227262Y207402D02*
X221378D01*
G01X226319Y207244D02*
X227303D01*
G01X226358Y207205D02*
X227264D01*
G01Y205630D02*
X226358D01*
G01X227303Y205591D02*
X226319D01*
G01X227262Y205433D02*
X221378D01*
G01Y205394D02*
X227302D01*
G01Y204291D02*
X221378D01*
G01X227262Y204252D02*
X221378D01*
G01X226319Y204094D02*
X227303D01*
G01X226358Y204055D02*
X227264D01*
G01Y202480D02*
X226358D01*
G01X227303Y202441D02*
X226319D01*
G01X227262Y202283D02*
X221378D01*
G01Y202244D02*
X227302D01*
G01Y201142D02*
X221378D01*
G01X227262Y201102D02*
X221378D01*
G01X226319Y200945D02*
X227303D01*
G01X226358Y200906D02*
X227264D01*
G01Y199331D02*
X226358D01*
G01X227303Y199291D02*
X226319D01*
G01X227262Y199134D02*
X221378D01*
G01Y199094D02*
X227302D01*
G01X240157Y198130D02*
X236220D01*
G01X227302Y197992D02*
X221378D01*
G01X227262Y197953D02*
X221378D01*
G01X226319Y197795D02*
X227303D01*
G01X226358Y197756D02*
X227264D01*
G01X241339Y196949D02*
X237402D01*
G01X240728Y196673D02*
X239744D01*
G01X239746Y196181D02*
X245079D01*
G01Y196142D02*
X240731D01*
G01X227756Y195787D02*
X224409D01*
G01X245079Y194803D02*
X239746D01*
G01X239744Y194311D02*
X240728D01*
G01Y191673D02*
X239744D01*
G01X239746Y191181D02*
X245079D01*
G01Y191142D02*
X240731D01*
G01X245079Y189803D02*
X239746D01*
G01X239744Y189311D02*
X240728D01*
G01Y186673D02*
X239744D01*
G01X239746Y186181D02*
X245079D01*
G01Y186142D02*
X240731D01*
G01X245079Y184803D02*
X239746D01*
G01X239744Y184311D02*
X240728D01*
G01Y181673D02*
X239744D01*
G01X239746Y181181D02*
X245079D01*
G01Y181142D02*
X240731D01*
G01X245079Y179803D02*
X239746D01*
G01X239744Y179311D02*
X240728D01*
G01Y176673D02*
X239744D01*
G01X239746Y176181D02*
X245079D01*
G01Y176142D02*
X240731D01*
G01X245079Y174803D02*
X239746D01*
G01X239744Y174311D02*
X240728D01*
G01Y171673D02*
X239744D01*
G01X239746Y171181D02*
X245079D01*
G01Y171142D02*
X240731D01*
G01X245079Y169803D02*
X239746D01*
G01X239744Y169311D02*
X240728D01*
G01X239744Y196377D02*
X240699Y196378D01*
G01X240728Y194607D02*
X239744Y194606D01*
G01Y191377D02*
X240699Y191378D01*
G01X240728Y189607D02*
X239744Y189606D01*
G01Y186377D02*
X240699Y186378D01*
G01X240728Y184607D02*
X239744Y184606D01*
G01Y181377D02*
X240699Y181378D01*
G01X240728Y179607D02*
X239744Y179606D01*
G01Y176377D02*
X240699Y176378D01*
G01X240728Y174607D02*
X239744Y174606D01*
G01Y171377D02*
X240699Y171378D01*
G01X240728Y169607D02*
X239744Y169606D01*
G01Y166377D02*
X240699Y166378D01*
G01X240728Y166673D02*
X239744D01*
G01X239746Y166181D02*
X245079D01*
G01Y166142D02*
X240731D01*
G01X245079Y164803D02*
X239746D01*
G01X239744Y164311D02*
X240728D01*
G01Y164607D02*
X239744Y164606D01*
G01X227303Y199097D02*
Y199108D01*
G01Y202246D02*
Y202257D01*
G01Y205396D02*
Y205407D01*
G01Y208546D02*
Y208557D01*
G01Y211695D02*
Y211706D01*
G01X240728Y166155D02*
X240729Y166164D01*
G01X240728Y171155D02*
X240729Y171164D01*
G01X240728Y176155D02*
X240729Y176164D01*
G01X240728Y181155D02*
X240729Y181164D01*
G01X240728Y186155D02*
X240729Y186164D01*
G01X240728Y191155D02*
X240729Y191164D01*
G01X240728Y196155D02*
X240729Y196164D01*
G01X245079Y194803D02*
Y196181D01*
G01Y189803D02*
Y191181D01*
G01Y184803D02*
Y186181D01*
G01Y179803D02*
Y181181D01*
G01Y174803D02*
Y176181D01*
G01Y169803D02*
Y171181D01*
G01Y164803D02*
Y166181D01*
G01X241909D02*
Y164803D01*
G01Y171181D02*
Y169803D01*
G01Y176181D02*
Y174803D01*
G01Y181181D02*
Y179803D01*
G01Y186181D02*
Y184803D01*
G01Y191181D02*
Y189803D01*
G01Y196181D02*
Y194803D01*
G01X241339Y219035D02*
Y196949D01*
G01X240728Y171156D02*
Y171299D01*
G01Y166156D02*
Y166299D01*
G01Y181156D02*
Y181299D01*
G01Y176156D02*
Y176299D01*
G01Y191156D02*
Y191299D01*
G01Y186156D02*
Y186299D01*
G01Y196156D02*
Y196299D01*
G01Y194311D02*
Y196673D01*
G01Y189311D02*
Y191673D01*
G01Y184311D02*
Y186673D01*
G01Y179311D02*
Y181673D01*
G01Y174311D02*
Y176673D01*
G01Y169311D02*
Y171673D01*
G01Y164311D02*
Y166673D01*
G01X240157Y217854D02*
Y198130D01*
G01X239744Y166673D02*
Y164311D01*
G01Y171673D02*
Y169311D01*
G01Y176673D02*
Y174311D01*
G01Y181673D02*
Y179311D01*
G01Y186673D02*
Y184311D01*
G01Y191673D02*
Y189311D01*
G01Y196673D02*
Y194311D01*
G01X227303Y210394D02*
Y211890D01*
G01Y207244D02*
Y208740D01*
G01Y204094D02*
Y205591D01*
G01Y200945D02*
Y202441D01*
G01Y197795D02*
Y199291D01*
G01X227264Y197942D02*
Y197795D01*
G01Y201091D02*
Y200944D01*
G01Y202441D02*
Y202295D01*
G01Y199292D02*
Y199145D01*
G01Y207391D02*
Y207244D01*
G01Y204241D02*
Y204094D01*
G01Y205591D02*
Y205444D01*
G01Y210540D02*
Y210393D01*
G01Y211890D02*
Y211744D01*
G01Y208741D02*
Y208594D01*
G01X226358Y210393D02*
Y210540D01*
G01Y211744D02*
Y211891D01*
G01Y208594D02*
Y208741D01*
G01Y207243D02*
Y207391D01*
G01Y204094D02*
Y204241D01*
G01Y205444D02*
Y205591D01*
G01Y200944D02*
Y201091D01*
G01Y202295D02*
Y202442D01*
G01Y199145D02*
Y199292D01*
G01Y197794D02*
Y197942D01*
G01X226319Y202441D02*
Y200945D01*
G01Y199291D02*
Y197795D01*
G01Y205591D02*
Y204094D01*
G01Y211890D02*
Y210394D01*
G01Y208740D02*
Y207244D01*
G01X225138Y199134D02*
Y197953D01*
G01Y202283D02*
Y201102D01*
G01Y208583D02*
Y207402D01*
G01Y205433D02*
Y204252D01*
G01Y211732D02*
Y210551D01*
G01X224803Y220197D02*
Y195787D01*
G01X224409D02*
Y220197D01*
G01X221378Y210551D02*
Y211732D01*
G01Y207402D02*
Y208583D01*
G01Y204252D02*
Y205433D01*
G01Y201102D02*
Y202283D01*
G01Y197953D02*
Y199134D01*
G01X227303Y210577D02*
Y210588D01*
G01Y207428D02*
Y207439D01*
G01Y204278D02*
Y204289D01*
G01Y201128D02*
Y201139D01*
G01Y197979D02*
Y197990D01*
G01X240157Y198130D02*
X241339Y196949D01*
G01X236220Y198130D02*
X237402Y196949D01*
G01X227272Y214881D02*
X227262Y214882D01*
G01X227281Y214878D02*
X227272Y214881D01*
G01X227288Y214872D02*
X227281Y214878D01*
G01X226358Y213696D02*
Y213690D01*
G01X226357Y213700D02*
X226358Y213696D01*
G01X226356Y213701D02*
X226357Y213700D01*
G01X226358Y216846D02*
Y216839D01*
G01X226357Y216849D02*
X226358Y216846D01*
G01X226356Y216850D02*
X226357Y216849D01*
G01X240729Y221148D02*
X240728Y221156D01*
G01X240730Y221144D02*
X240729Y221148D01*
G01X240731Y221142D02*
X240730Y221144D01*
G01X240729Y226148D02*
X240728Y226156D01*
G01X240730Y226144D02*
X240729Y226148D01*
G01X240731Y226142D02*
X240730Y226144D01*
G01X240729Y231148D02*
X240728Y231156D01*
G01X240730Y231144D02*
X240729Y231148D01*
G01X240731Y231142D02*
X240730Y231144D01*
G01X240729Y236148D02*
X240728Y236156D01*
G01X240730Y236144D02*
X240729Y236148D01*
G01X240731Y236142D02*
X240730Y236144D01*
G01X240729Y241148D02*
X240728Y241156D01*
G01X240730Y241144D02*
X240729Y241148D01*
G01X240731Y241142D02*
X240730Y241144D01*
G01X240729Y246148D02*
X240728Y246156D01*
G01X240730Y246144D02*
X240729Y246148D01*
G01X240731Y246142D02*
X240730Y246144D01*
G01X240729Y251148D02*
X240728Y251156D01*
G01X240730Y251144D02*
X240729Y251148D01*
G01X240731Y251142D02*
X240730Y251144D01*
G01X240729Y256148D02*
X240728Y256156D01*
G01X240730Y256144D02*
X240729Y256148D01*
G01X240731Y256142D02*
X240730Y256144D01*
G01X226341Y213704D02*
X226356Y213701D01*
G01X226329Y213711D02*
X226341Y213704D01*
G01X226317Y213731D02*
X226329Y213711D01*
G01X227303Y213734D02*
Y213727D01*
G01X227302Y213739D02*
X227303Y213734D01*
G01X227302Y213740D02*
Y213739D01*
G01X227303Y216884D02*
Y216876D01*
G01X227302Y216889D02*
X227303Y216884D01*
G01X227302Y216890D02*
Y216889D01*
G01X226341Y216853D02*
X226356Y216850D01*
G01X226329Y216861D02*
X226341Y216853D01*
G01X226317Y216881D02*
X226329Y216861D01*
G01X227302Y214863D02*
X227303Y214856D01*
G01X227301Y214869D02*
X227302Y214863D01*
G01X227298Y214875D02*
X227301Y214869D01*
G01X227302Y218013D02*
X227303Y218006D01*
G01X227301Y218019D02*
X227302Y218013D01*
G01X227298Y218025D02*
X227301Y218019D01*
G01X227264Y216845D02*
X227265Y216839D01*
G01X227263Y216849D02*
X227264Y216845D01*
G01X227262Y216850D02*
X227263Y216849D01*
G01X239744Y221189D02*
Y221198D01*
G01X239745Y221183D02*
X239744Y221189D01*
G01X239746Y221181D02*
X239745Y221183D01*
G01X239744Y226189D02*
Y226198D01*
G01X239745Y226183D02*
X239744Y226189D01*
G01X239746Y226181D02*
X239745Y226183D01*
G01X239744Y231189D02*
Y231198D01*
G01X239745Y231183D02*
X239744Y231189D01*
G01X239746Y231181D02*
X239745Y231183D01*
G01X239744Y236189D02*
Y236198D01*
G01X239745Y236183D02*
X239744Y236189D01*
G01X239746Y236181D02*
X239745Y236183D01*
G01X240720Y221325D02*
X240728Y221299D01*
G01X240711Y221352D02*
X240720Y221325D01*
G01X240699Y221378D02*
X240711Y221352D01*
G01X240720Y226325D02*
X240728Y226299D01*
G01X240711Y226352D02*
X240720Y226325D01*
G01X240699Y226378D02*
X240711Y226352D01*
G01X240720Y231325D02*
X240728Y231299D01*
G01X240711Y231352D02*
X240720Y231325D01*
G01X240699Y231378D02*
X240711Y231352D01*
G01X227272Y218030D02*
X227262Y218031D01*
G01X227281Y218027D02*
X227272Y218030D01*
G01X227288Y218022D02*
X227281Y218027D01*
G01X239744Y241189D02*
Y241198D01*
G01X239745Y241183D02*
X239744Y241189D01*
G01X239746Y241181D02*
X239745Y241183D01*
G01X239744Y246189D02*
Y246198D01*
G01X239745Y246183D02*
X239744Y246189D01*
G01X239746Y246181D02*
X239745Y246183D01*
G01X239744Y251189D02*
Y251198D01*
G01X239745Y251183D02*
X239744Y251189D01*
G01X239746Y251181D02*
X239745Y251183D01*
G01X239744Y256189D02*
Y256198D01*
G01X239745Y256183D02*
X239744Y256189D01*
G01X239746Y256181D02*
X239745Y256183D01*
G01X240720Y236325D02*
X240728Y236299D01*
G01X240711Y236352D02*
X240720Y236325D01*
G01X240699Y236378D02*
X240711Y236352D01*
G01X240720Y241325D02*
X240728Y241299D01*
G01X240711Y241352D02*
X240720Y241325D01*
G01X240699Y241378D02*
X240711Y241352D01*
G01X240720Y246325D02*
X240728Y246299D01*
G01X240711Y246352D02*
X240720Y246325D01*
G01X240699Y246378D02*
X240711Y246352D01*
G01X240720Y251325D02*
X240728Y251299D01*
G01X240711Y251352D02*
X240720Y251325D01*
G01X240699Y251378D02*
X240711Y251352D01*
G01X240720Y256325D02*
X240728Y256299D01*
G01X240711Y256352D02*
X240720Y256325D01*
G01X240699Y256378D02*
X240711Y256352D01*
G01Y221176D02*
X240692Y221181D01*
G01X240726Y221162D02*
X240711Y221176D01*
G01X240731Y221142D02*
X240726Y221162D01*
G01X240711Y226176D02*
X240692Y226181D01*
G01X240726Y226162D02*
X240711Y226176D01*
G01X240731Y226142D02*
X240726Y226162D01*
G01X240711Y231176D02*
X240692Y231181D01*
G01X240726Y231162D02*
X240711Y231176D01*
G01X240731Y231142D02*
X240726Y231162D01*
G01X240711Y236176D02*
X240692Y236181D01*
G01X240726Y236162D02*
X240711Y236176D01*
G01X240731Y236142D02*
X240726Y236162D01*
G01X240711Y241176D02*
X240692Y241181D01*
G01X240726Y241162D02*
X240711Y241176D01*
G01X240731Y241142D02*
X240726Y241162D01*
G01X240711Y246176D02*
X240692Y246181D01*
G01X240726Y246162D02*
X240711Y246176D01*
G01X240731Y246142D02*
X240726Y246162D01*
G01X240711Y251176D02*
X240692Y251181D01*
G01X240726Y251162D02*
X240711Y251176D01*
G01X240731Y251142D02*
X240726Y251162D01*
G01X240711Y256176D02*
X240692Y256181D01*
G01X240726Y256162D02*
X240711Y256176D01*
G01X240731Y256142D02*
X240726Y256162D01*
G01X227296Y214864D02*
X227288Y214872D01*
G01X227300Y214854D02*
X227296Y214864D01*
G01X227302Y214843D02*
X227300Y214854D01*
G01X227296Y218013D02*
X227288Y218022D01*
G01X227300Y218003D02*
X227296Y218013D01*
G01X227302Y217992D02*
X227300Y218003D01*
G01X240695Y221279D02*
X240699Y221378D01*
G01X240690Y221207D02*
X240695Y221279D01*
G01X240692Y221181D02*
X240690Y221207D01*
G01X240695Y226279D02*
X240699Y226378D01*
G01X240690Y226207D02*
X240695Y226279D01*
G01X240692Y226181D02*
X240690Y226207D01*
G01X240695Y231279D02*
X240699Y231378D01*
G01X240690Y231207D02*
X240695Y231279D01*
G01X240692Y231181D02*
X240690Y231207D01*
G01X240695Y236279D02*
X240699Y236378D01*
G01X240690Y236207D02*
X240695Y236279D01*
G01X240692Y236181D02*
X240690Y236207D01*
G01X240695Y241279D02*
X240699Y241378D01*
G01X240690Y241207D02*
X240695Y241279D01*
G01X240692Y241181D02*
X240690Y241207D01*
G01X240695Y246279D02*
X240699Y246378D01*
G01X240690Y246207D02*
X240695Y246279D01*
G01X240692Y246181D02*
X240690Y246207D01*
G01X240695Y251279D02*
X240699Y251378D01*
G01X240690Y251207D02*
X240695Y251279D01*
G01X240692Y251181D02*
X240690Y251207D01*
G01X240695Y256279D02*
X240699Y256378D01*
G01X240690Y256207D02*
X240695Y256279D01*
G01X240692Y256181D02*
X240690Y256207D01*
G01X226359Y218216D02*
X226358Y218228D01*
G01X226356Y218203D02*
X226359Y218216D01*
G01X226356Y218189D02*
Y218203D01*
G01X226359Y215067D02*
X226358Y215079D01*
G01X226356Y215054D02*
X226359Y215067D01*
G01X226356Y215040D02*
Y215054D01*
G01X239745Y259802D02*
X239746Y259803D01*
G01X239744Y259796D02*
X239745Y259802D01*
G01X239744Y259787D02*
Y259796D01*
G01X239745Y254802D02*
X239746Y254803D01*
G01X239744Y254796D02*
X239745Y254802D01*
G01X239744Y254787D02*
Y254796D01*
G01X239745Y249802D02*
X239746Y249803D01*
G01X239744Y249796D02*
X239745Y249802D01*
G01X239744Y249787D02*
Y249796D01*
G01X239745Y244802D02*
X239746Y244803D01*
G01X239744Y244796D02*
X239745Y244802D01*
G01X239744Y244787D02*
Y244796D01*
G01X239745Y239802D02*
X239746Y239803D01*
G01X239744Y239796D02*
X239745Y239802D01*
G01X239744Y239787D02*
Y239796D01*
G01X239745Y234802D02*
X239746Y234803D01*
G01X239744Y234796D02*
X239745Y234802D01*
G01X239744Y234787D02*
Y234796D01*
G01X239745Y229802D02*
X239746Y229803D01*
G01X239744Y229796D02*
X239745Y229802D01*
G01X239744Y229787D02*
Y229796D01*
G01X239745Y224802D02*
X239746Y224803D01*
G01X239744Y224796D02*
X239745Y224802D01*
G01X239744Y224787D02*
Y224796D01*
G01X239745Y219802D02*
X239746Y219803D01*
G01X239744Y219796D02*
X239745Y219802D01*
G01X239744Y219787D02*
Y219796D01*
G01X226319Y216884D02*
Y216876D01*
G01X226318Y216889D02*
X226319Y216884D01*
G01X226318Y216881D02*
Y216889D01*
G01X226356Y216679D02*
X226355Y216693D01*
G01X226359Y216666D02*
X226356Y216679D01*
G01X226358Y216654D02*
X226359Y216666D01*
G01X226356Y213530D02*
X226355Y213543D01*
G01X226359Y213517D02*
X226356Y213530D01*
G01X226358Y213504D02*
X226359Y213517D01*
G01X226319Y213731D02*
Y213727D01*
G01X226320Y213724D02*
X226319Y213731D01*
G01X226332Y213709D02*
X226320Y213724D01*
G01X226356Y213701D02*
X226332Y213709D01*
G01X226319Y216880D02*
Y216876D01*
G01X226320Y216874D02*
X226319Y216880D01*
G01X226332Y216859D02*
X226320Y216874D01*
G01X226356Y216850D02*
X226332Y216859D01*
G01X240716Y221173D02*
X240727Y221157D01*
G01X240691Y221181D02*
X240716Y221173D01*
G01Y226173D02*
X240727Y226157D01*
G01X240691Y226181D02*
X240716Y226173D01*
G01Y231173D02*
X240727Y231157D01*
G01X240691Y231181D02*
X240716Y231173D01*
G01Y236173D02*
X240727Y236157D01*
G01X240691Y236181D02*
X240716Y236173D01*
G01Y241173D02*
X240727Y241157D01*
G01X240691Y241181D02*
X240716Y241173D01*
G01Y246173D02*
X240727Y246157D01*
G01X240691Y246181D02*
X240716Y246173D01*
G01Y251173D02*
X240727Y251157D01*
G01X240691Y251181D02*
X240716Y251173D01*
G01Y256173D02*
X240727Y256157D01*
G01X240691Y256181D02*
X240716Y256173D01*
G01X227266Y218203D02*
X227267Y218189D01*
G01X227263Y218216D02*
X227266Y218203D01*
G01X227264Y218228D02*
X227263Y218216D01*
G01X227266Y215053D02*
X227267Y215040D01*
G01X227263Y215066D02*
X227266Y215053D01*
G01X227264Y215079D02*
X227263Y215066D01*
G01X226319Y213734D02*
Y213727D01*
G01X226318Y213739D02*
X226319Y213734D01*
G01X226317Y213732D02*
X226318Y213739D01*
G01X227263Y216666D02*
X227264Y216654D01*
G01X227266Y216679D02*
X227263Y216666D01*
G01X227267Y216693D02*
X227266Y216679D01*
G01X227263Y213517D02*
X227264Y213504D01*
G01X227266Y213530D02*
X227263Y213517D01*
G01X227267Y213543D02*
X227266Y213530D01*
G01X227294Y214880D02*
X227298Y214875D01*
G01X227289Y214885D02*
X227294Y214880D01*
G01X227283Y214889D02*
X227289Y214885D01*
G01X227277Y214891D02*
X227283Y214889D01*
G01X227270Y214893D02*
X227277Y214891D01*
G01X227264Y214893D02*
X227270D01*
G01X227294Y218030D02*
X227298Y218025D01*
G01X227289Y218034D02*
X227294Y218030D01*
G01X227283Y218038D02*
X227289Y218034D01*
G01X227277Y218041D02*
X227283Y218038D01*
G01X227270Y218043D02*
X227277Y218041D01*
G01X227264Y218043D02*
X227270D01*
G01X226320Y213719D02*
X226319Y213727D01*
G01X226322Y213713D02*
X226320Y213719D01*
G01X226326Y213706D02*
X226322Y213713D01*
G01X226330Y213700D02*
X226326Y213706D01*
G01X226337Y213696D02*
X226330Y213700D01*
G01X226343Y213693D02*
X226337Y213696D01*
G01X226351Y213691D02*
X226343Y213693D01*
G01X226358Y213690D02*
X226351Y213691D01*
G01X226320Y216869D02*
X226319Y216876D01*
G01X226322Y216862D02*
X226320Y216869D01*
G01X226326Y216856D02*
X226322Y216862D01*
G01X226330Y216850D02*
X226326Y216856D01*
G01X226337Y216845D02*
X226330Y216850D01*
G01X226343Y216842D02*
X226337Y216845D01*
G01X226351Y216840D02*
X226343Y216842D01*
G01X226358Y216839D02*
X226351Y216840D01*
G01X227273Y214881D02*
X227282Y214876D01*
G01X227262Y214882D02*
X227273Y214881D01*
G01Y218030D02*
X227282Y218026D01*
G01X227262Y218031D02*
X227273Y218030D01*
G01X226332Y218023D02*
X226356Y218031D01*
G01X226320Y218009D02*
X226332Y218023D01*
G01X226319Y218002D02*
X226320Y218009D01*
G01X226332Y214874D02*
X226356Y214882D01*
G01X226320Y214859D02*
X226332Y214874D01*
G01X226319Y214852D02*
X226320Y214859D01*
G01X226341Y214890D02*
X226338Y214888D01*
G01X226344Y214891D02*
X226341Y214890D01*
G01X226348Y214892D02*
X226344Y214891D01*
G01X226351Y214893D02*
X226348Y214892D01*
G01X226355Y214893D02*
X226351D01*
G01X226358D02*
X226355D01*
G01X227281Y216843D02*
X227284Y216844D01*
G01X227278Y216842D02*
X227281Y216843D01*
G01X227274Y216841D02*
X227278Y216842D01*
G01X227271Y216840D02*
X227274Y216841D01*
G01X227267Y216839D02*
X227271Y216840D01*
G01X227264Y216839D02*
X227267D01*
G01X226341Y218039D02*
X226338Y218038D01*
G01X226344Y218041D02*
X226341Y218039D01*
G01X226348Y218042D02*
X226344Y218041D01*
G01X226351Y218042D02*
X226348D01*
G01X226355Y218043D02*
X226351Y218042D01*
G01X226358Y218043D02*
X226355D01*
G01X227303Y217998D02*
Y218006D01*
G01Y217994D02*
Y217998D01*
G01X227302Y217992D02*
X227303Y217994D01*
G01Y214849D02*
Y214856D01*
G01Y214844D02*
Y214849D01*
G01X227302Y214843D02*
X227303Y214844D01*
G01X227302Y213719D02*
X227303Y213727D01*
G01X227300Y213713D02*
X227302Y213719D01*
G01X227296Y213706D02*
X227300Y213713D01*
G01X227292Y213700D02*
X227296Y213706D01*
G01X227285Y213696D02*
X227292Y213700D01*
G01X227279Y213693D02*
X227285Y213696D01*
G01X227271Y213691D02*
X227279Y213693D01*
G01X227264Y213690D02*
X227271Y213691D01*
G01X226322Y214862D02*
X226317Y214843D01*
G01X226336Y214877D02*
X226322Y214862D01*
G01X226356Y214882D02*
X226336Y214877D01*
G01X226322Y218012D02*
X226317Y217992D01*
G01X226336Y218026D02*
X226322Y218012D01*
G01X226356Y218031D02*
X226336Y218026D01*
G01X227296Y213720D02*
X227302Y213740D01*
G01X227282Y213706D02*
X227296Y213720D01*
G01X227262Y213701D02*
X227282Y213706D01*
G01X227296Y216870D02*
X227302Y216890D01*
G01X227282Y216856D02*
X227296Y216870D01*
G01X227262Y216850D02*
X227282Y216856D01*
G01X227264Y218037D02*
Y218043D01*
G01X227263Y218033D02*
X227264Y218037D01*
G01X227262Y218031D02*
X227263Y218033D01*
G01X227264Y214887D02*
Y214893D01*
G01X227263Y214883D02*
X227264Y214887D01*
G01X227262Y214882D02*
X227263Y214883D01*
G01X240729Y259796D02*
X240728Y259787D01*
G01X240730Y259802D02*
X240729Y259796D01*
G01X240731Y259803D02*
X240730Y259802D01*
G01X240729Y254796D02*
X240728Y254787D01*
G01X240730Y254802D02*
X240729Y254796D01*
G01X240731Y254803D02*
X240730Y254802D01*
G01X240729Y249796D02*
X240728Y249787D01*
G01X240730Y249802D02*
X240729Y249796D01*
G01X240731Y249803D02*
X240730Y249802D01*
G01X240729Y244796D02*
X240728Y244787D01*
G01X240730Y244802D02*
X240729Y244796D01*
G01X240731Y244803D02*
X240730Y244802D01*
G01X240729Y239796D02*
X240728Y239787D01*
G01X240730Y239802D02*
X240729Y239796D01*
G01X240731Y239803D02*
X240730Y239802D01*
G01X240729Y234796D02*
X240728Y234787D01*
G01X240730Y234802D02*
X240729Y234796D01*
G01X240731Y234803D02*
X240730Y234802D01*
G01X240729Y229796D02*
X240728Y229787D01*
G01X240730Y229802D02*
X240729Y229796D01*
G01X240731Y229803D02*
X240730Y229802D01*
G01X240729Y224796D02*
X240728Y224787D01*
G01X240730Y224802D02*
X240729Y224796D01*
G01X240731Y224803D02*
X240730Y224802D01*
G01X240729Y219796D02*
X240728Y219787D01*
G01X240730Y219802D02*
X240729Y219796D01*
G01X240731Y219803D02*
X240730Y219802D01*
G01X226319Y217998D02*
Y218006D01*
G01X226318Y217994D02*
X226319Y217998D01*
G01X226317Y217992D02*
X226318Y217994D01*
G01X226319Y214849D02*
Y214856D01*
G01X226318Y214844D02*
X226319Y214849D01*
G01X226317Y214843D02*
X226318Y214844D01*
G01X227301Y216864D02*
X227303Y216876D01*
G01X227294Y216853D02*
X227301Y216864D01*
G01X227284Y216844D02*
X227294Y216853D01*
G01X226357Y218037D02*
Y218043D01*
G01Y218033D02*
Y218037D01*
G01X226356Y218031D02*
X226357Y218033D01*
G01Y214887D02*
Y214893D01*
G01Y214883D02*
Y214887D01*
G01X226356Y214882D02*
X226357Y214883D01*
G01X226320Y218012D02*
X226319Y218006D01*
G01X226321Y218019D02*
X226320Y218012D01*
G01X226324Y218024D02*
X226321Y218019D01*
G01X226328Y218030D02*
X226324Y218024D01*
G01X226333Y218034D02*
X226328Y218030D01*
G01X226338Y218038D02*
X226333Y218034D01*
G01X226320Y214863D02*
X226319Y214856D01*
G01X226321Y214869D02*
X226320Y214863D01*
G01X226324Y214874D02*
X226321Y214869D01*
G01X226328Y214880D02*
X226324Y214874D01*
G01X226333Y214884D02*
X226328Y214880D01*
G01X226338Y214888D02*
X226333Y214884D01*
G01X227274Y216852D02*
X227262Y216850D01*
G01X227285Y216857D02*
X227274Y216852D01*
G01Y213703D02*
X227262Y213701D01*
G01X227285Y213708D02*
X227274Y213703D01*
G01X240157Y217854D02*
X241339Y219035D01*
G01X236220Y217854D02*
X237402Y219035D01*
G01X245079Y259803D02*
X239746D01*
G01X239744Y259311D02*
X240728D01*
G01Y256673D02*
X239744D01*
G01X240728Y259607D02*
X239744Y259606D01*
G01Y256377D02*
X240699Y256378D01*
G01X239746Y256181D02*
X245079D01*
G01Y256142D02*
X240731D01*
G01X245079Y254803D02*
X239746D01*
G01X239744Y254311D02*
X240728D01*
G01Y251673D02*
X239744D01*
G01X239746Y251181D02*
X245079D01*
G01Y251142D02*
X240731D01*
G01X245079Y249803D02*
X239746D01*
G01X239744Y249311D02*
X240728D01*
G01Y246673D02*
X239744D01*
G01X239746Y246181D02*
X245079D01*
G01Y246142D02*
X240731D01*
G01X245079Y244803D02*
X239746D01*
G01X239744Y244311D02*
X240728D01*
G01Y241673D02*
X239744D01*
G01X239746Y241181D02*
X245079D01*
G01Y241142D02*
X240731D01*
G01X245079Y239803D02*
X239746D01*
G01X239744Y239311D02*
X240728D01*
G01Y236673D02*
X239744D01*
G01X239746Y236181D02*
X245079D01*
G01Y236142D02*
X240731D01*
G01X245079Y234803D02*
X239746D01*
G01X239744Y234311D02*
X240728D01*
G01Y231673D02*
X239744D01*
G01X239746Y231181D02*
X245079D01*
G01Y231142D02*
X240731D01*
G01X245079Y229803D02*
X239746D01*
G01X239744Y229311D02*
X240728D01*
G01Y226673D02*
X239744D01*
G01X239746Y226181D02*
X245079D01*
G01Y226142D02*
X240731D01*
G01X245079Y224803D02*
X239746D01*
G01X239744Y224311D02*
X240728D01*
G01Y221673D02*
X239744D01*
G01X239746Y221181D02*
X245079D01*
G01Y221142D02*
X240731D01*
G01X227756Y220197D02*
X224409D01*
G01X245079Y219803D02*
X239746D01*
G01X239744Y219311D02*
X240728D01*
G01X237402Y219035D02*
X241339D01*
G01X227264Y218228D02*
X226358D01*
G01X227303Y218189D02*
X226319D01*
G01X227262Y218031D02*
X221378D01*
G01Y217992D02*
X227302D01*
G01X236220Y217854D02*
X240157D01*
G01X227302Y216890D02*
X221378D01*
G01X227262Y216850D02*
X221378D01*
G01X226319Y216693D02*
X227303D01*
G01X226358Y216654D02*
X227264D01*
G01Y215079D02*
X226358D01*
G01X227303Y215039D02*
X226319D01*
G01X227262Y214882D02*
X221378D01*
G01Y214843D02*
X227302D01*
G01Y213740D02*
X221378D01*
G01X227262Y213701D02*
X221378D01*
G01X226319Y213543D02*
X227303D01*
G01X226358Y213504D02*
X227264D01*
G01X240728Y254607D02*
X239744Y254606D01*
G01Y251377D02*
X240699Y251378D01*
G01X240728Y249607D02*
X239744Y249606D01*
G01Y246377D02*
X240699Y246378D01*
G01X240728Y244607D02*
X239744Y244606D01*
G01Y241377D02*
X240699Y241378D01*
G01X240728Y239607D02*
X239744Y239606D01*
G01Y236377D02*
X240699Y236378D01*
G01X240728Y234607D02*
X239744Y234606D01*
G01Y231377D02*
X240699Y231378D01*
G01X240728Y229607D02*
X239744Y229606D01*
G01Y226377D02*
X240699Y226378D01*
G01X240728Y224607D02*
X239744Y224606D01*
G01Y221377D02*
X240699Y221378D01*
G01X240728Y219607D02*
X239744Y219606D01*
G01X226206Y216890D02*
X226317Y216881D01*
G01X227303Y214845D02*
Y214856D01*
G01Y217994D02*
Y218006D01*
G01X240728Y221155D02*
X240729Y221164D01*
G01X240728Y226155D02*
X240729Y226164D01*
G01X240728Y231155D02*
X240729Y231164D01*
G01X240728Y236155D02*
X240729Y236164D01*
G01X240728Y241155D02*
X240729Y241164D01*
G01X240728Y246155D02*
X240729Y246164D01*
G01X240728Y251155D02*
X240729Y251164D01*
G01X240728Y256155D02*
X240729Y256164D01*
G01X245079Y259803D02*
Y261181D01*
G01Y254803D02*
Y256181D01*
G01Y249803D02*
Y251181D01*
G01Y244803D02*
Y246181D01*
G01Y239803D02*
Y241181D01*
G01Y234803D02*
Y236181D01*
G01Y229803D02*
Y231181D01*
G01Y224803D02*
Y226181D01*
G01Y219803D02*
Y221181D01*
G01X241909D02*
Y219803D01*
G01Y226181D02*
Y224803D01*
G01Y231181D02*
Y229803D01*
G01Y236181D02*
Y234803D01*
G01Y241181D02*
Y239803D01*
G01Y246181D02*
Y244803D01*
G01Y251181D02*
Y249803D01*
G01Y256181D02*
Y254803D01*
G01Y261181D02*
Y259803D01*
G01X240728Y221156D02*
Y221299D01*
G01Y231156D02*
Y231299D01*
G01Y226156D02*
Y226299D01*
G01Y241156D02*
Y241299D01*
G01Y236156D02*
Y236299D01*
G01Y251156D02*
Y251299D01*
G01Y246156D02*
Y246299D01*
G01Y256156D02*
Y256299D01*
G01Y259311D02*
Y261673D01*
G01Y254311D02*
Y256673D01*
G01Y249311D02*
Y251673D01*
G01Y244311D02*
Y246673D01*
G01Y239311D02*
Y241673D01*
G01Y234311D02*
Y236673D01*
G01Y229311D02*
Y231673D01*
G01Y224311D02*
Y226673D01*
G01Y219311D02*
Y221673D01*
G01X239744D02*
Y219311D01*
G01Y226673D02*
Y224311D01*
G01Y231673D02*
Y229311D01*
G01Y236673D02*
Y234311D01*
G01Y241673D02*
Y239311D01*
G01Y246673D02*
Y244311D01*
G01Y251673D02*
Y249311D01*
G01Y256673D02*
Y254311D01*
G01Y261673D02*
Y259311D01*
G01X237402Y295492D02*
Y219035D01*
G01X236220Y294311D02*
Y217854D01*
G01X227756Y299232D02*
Y220197D01*
G01X227303Y216693D02*
Y218189D01*
G01Y213543D02*
Y215039D01*
G01X227264Y216839D02*
Y216693D01*
G01Y213690D02*
Y213543D01*
G01Y215040D02*
Y214893D01*
G01Y218189D02*
Y218043D01*
G01X226358D02*
Y218190D01*
G01Y216692D02*
Y216839D01*
G01Y213543D02*
Y213690D01*
G01Y214893D02*
Y215040D01*
G01X226319Y215039D02*
Y213543D01*
G01Y218189D02*
Y216693D01*
G01X225138Y218031D02*
Y216850D01*
G01Y214882D02*
Y213701D01*
G01X221378Y216850D02*
Y218031D01*
G01Y213701D02*
Y214882D01*
G01X227303Y216876D02*
Y216887D01*
G01Y213727D02*
Y213738D01*
G01X227262Y213701D02*
X227266Y213690D01*
G01X240729Y261148D02*
X240728Y261156D01*
G01X240730Y261144D02*
X240729Y261148D01*
G01X240731Y261142D02*
X240730Y261144D01*
G01X240729Y266148D02*
X240728Y266156D01*
G01X240730Y266144D02*
X240729Y266148D01*
G01X240731Y266142D02*
X240730Y266144D01*
G01X240729Y271148D02*
X240728Y271156D01*
G01X240730Y271144D02*
X240729Y271148D01*
G01X240731Y271142D02*
X240730Y271144D01*
G01X240729Y276148D02*
X240728Y276156D01*
G01X240730Y276144D02*
X240729Y276148D01*
G01X240731Y276142D02*
X240730Y276144D01*
G01X240729Y281148D02*
X240728Y281156D01*
G01X240730Y281144D02*
X240729Y281148D01*
G01X240731Y281142D02*
X240730Y281144D01*
G01X240729Y286148D02*
X240728Y286156D01*
G01X240730Y286144D02*
X240729Y286148D01*
G01X240731Y286142D02*
X240730Y286144D01*
G01X240729Y291148D02*
X240728Y291156D01*
G01X240730Y291144D02*
X240729Y291148D01*
G01X240731Y291142D02*
X240730Y291144D01*
G01X239744Y261189D02*
Y261198D01*
G01X239745Y261183D02*
X239744Y261189D01*
G01X239746Y261181D02*
X239745Y261183D01*
G01X239744Y266189D02*
Y266198D01*
G01X239745Y266183D02*
X239744Y266189D01*
G01X239746Y266181D02*
X239745Y266183D01*
G01X239744Y271189D02*
Y271198D01*
G01X239745Y271183D02*
X239744Y271189D01*
G01X239746Y271181D02*
X239745Y271183D01*
G01X239744Y276189D02*
Y276198D01*
G01X239745Y276183D02*
X239744Y276189D01*
G01X239746Y276181D02*
X239745Y276183D01*
G01X239744Y281189D02*
Y281198D01*
G01X239745Y281183D02*
X239744Y281189D01*
G01X239746Y281181D02*
X239745Y281183D01*
G01X239744Y286189D02*
Y286198D01*
G01X239745Y286183D02*
X239744Y286189D01*
G01X239746Y286181D02*
X239745Y286183D01*
G01X239744Y291189D02*
Y291198D01*
G01X239745Y291183D02*
X239744Y291189D01*
G01X239746Y291181D02*
X239745Y291183D01*
G01X240720Y261325D02*
X240728Y261299D01*
G01X240711Y261352D02*
X240720Y261325D01*
G01X240699Y261378D02*
X240711Y261352D01*
G01X240720Y266325D02*
X240728Y266299D01*
G01X240711Y266352D02*
X240720Y266325D01*
G01X240699Y266378D02*
X240711Y266352D01*
G01X240720Y271325D02*
X240728Y271299D01*
G01X240711Y271352D02*
X240720Y271325D01*
G01X240699Y271378D02*
X240711Y271352D01*
G01X240720Y276325D02*
X240728Y276299D01*
G01X240711Y276352D02*
X240720Y276325D01*
G01X240699Y276378D02*
X240711Y276352D01*
G01X240720Y281325D02*
X240728Y281299D01*
G01X240711Y281352D02*
X240720Y281325D01*
G01X240699Y281378D02*
X240711Y281352D01*
G01X240720Y286325D02*
X240728Y286299D01*
G01X240711Y286352D02*
X240720Y286325D01*
G01X240699Y286378D02*
X240711Y286352D01*
G01X240720Y291325D02*
X240728Y291299D01*
G01X240711Y291352D02*
X240720Y291325D01*
G01X240699Y291378D02*
X240711Y291352D01*
G01Y261176D02*
X240692Y261181D01*
G01X240726Y261162D02*
X240711Y261176D01*
G01X240731Y261142D02*
X240726Y261162D01*
G01X240711Y266176D02*
X240692Y266181D01*
G01X240726Y266162D02*
X240711Y266176D01*
G01X240731Y266142D02*
X240726Y266162D01*
G01X240711Y271176D02*
X240692Y271181D01*
G01X240726Y271162D02*
X240711Y271176D01*
G01X240731Y271142D02*
X240726Y271162D01*
G01X240711Y276176D02*
X240692Y276181D01*
G01X240726Y276162D02*
X240711Y276176D01*
G01X240731Y276142D02*
X240726Y276162D01*
G01X240711Y281176D02*
X240692Y281181D01*
G01X240726Y281162D02*
X240711Y281176D01*
G01X240731Y281142D02*
X240726Y281162D01*
G01X240711Y286176D02*
X240692Y286181D01*
G01X240726Y286162D02*
X240711Y286176D01*
G01X240731Y286142D02*
X240726Y286162D01*
G01X240711Y291176D02*
X240692Y291181D01*
G01X240726Y291162D02*
X240711Y291176D01*
G01X240731Y291142D02*
X240726Y291162D01*
G01X240695Y261279D02*
X240699Y261378D01*
G01X240690Y261207D02*
X240695Y261279D01*
G01X240692Y261181D02*
X240690Y261207D01*
G01X240695Y266279D02*
X240699Y266378D01*
G01X240690Y266207D02*
X240695Y266279D01*
G01X240692Y266181D02*
X240690Y266207D01*
G01X240695Y271279D02*
X240699Y271378D01*
G01X240690Y271207D02*
X240695Y271279D01*
G01X240692Y271181D02*
X240690Y271207D01*
G01X240695Y276279D02*
X240699Y276378D01*
G01X240690Y276207D02*
X240695Y276279D01*
G01X240692Y276181D02*
X240690Y276207D01*
G01X240695Y281279D02*
X240699Y281378D01*
G01X240690Y281207D02*
X240695Y281279D01*
G01X240692Y281181D02*
X240690Y281207D01*
G01X240695Y286279D02*
X240699Y286378D01*
G01X240690Y286207D02*
X240695Y286279D01*
G01X240692Y286181D02*
X240690Y286207D01*
G01X240695Y291279D02*
X240699Y291378D01*
G01X240690Y291207D02*
X240695Y291279D01*
G01X240692Y291181D02*
X240690Y291207D01*
G01X239745Y289802D02*
X239746Y289803D01*
G01X239744Y289796D02*
X239745Y289802D01*
G01X239744Y289787D02*
Y289796D01*
G01X239745Y284802D02*
X239746Y284803D01*
G01X239744Y284796D02*
X239745Y284802D01*
G01X239744Y284787D02*
Y284796D01*
G01X239745Y279802D02*
X239746Y279803D01*
G01X239744Y279796D02*
X239745Y279802D01*
G01X239744Y279787D02*
Y279796D01*
G01X239745Y274802D02*
X239746Y274803D01*
G01X239744Y274796D02*
X239745Y274802D01*
G01X239744Y274787D02*
Y274796D01*
G01X239745Y269802D02*
X239746Y269803D01*
G01X239744Y269796D02*
X239745Y269802D01*
G01X239744Y269787D02*
Y269796D01*
G01X239745Y264802D02*
X239746Y264803D01*
G01X239744Y264796D02*
X239745Y264802D01*
G01X239744Y264787D02*
Y264796D01*
G01X240716Y261173D02*
X240727Y261157D01*
G01X240691Y261181D02*
X240716Y261173D01*
G01Y266173D02*
X240727Y266157D01*
G01X240691Y266181D02*
X240716Y266173D01*
G01Y271173D02*
X240727Y271157D01*
G01X240691Y271181D02*
X240716Y271173D01*
G01Y276173D02*
X240727Y276157D01*
G01X240691Y276181D02*
X240716Y276173D01*
G01Y281173D02*
X240727Y281157D01*
G01X240691Y281181D02*
X240716Y281173D01*
G01Y286173D02*
X240727Y286157D01*
G01X240691Y286181D02*
X240716Y286173D01*
G01Y291173D02*
X240727Y291157D01*
G01X240691Y291181D02*
X240716Y291173D01*
G01X240729Y289796D02*
X240728Y289787D01*
G01X240730Y289802D02*
X240729Y289796D01*
G01X240731Y289803D02*
X240730Y289802D01*
G01X240729Y284796D02*
X240728Y284787D01*
G01X240730Y284802D02*
X240729Y284796D01*
G01X240731Y284803D02*
X240730Y284802D01*
G01X240729Y279796D02*
X240728Y279787D01*
G01X240730Y279802D02*
X240729Y279796D01*
G01X240731Y279803D02*
X240730Y279802D01*
G01X240729Y274796D02*
X240728Y274787D01*
G01X240730Y274802D02*
X240729Y274796D01*
G01X240731Y274803D02*
X240730Y274802D01*
G01X240729Y269796D02*
X240728Y269787D01*
G01X240730Y269802D02*
X240729Y269796D01*
G01X240731Y269803D02*
X240730Y269802D01*
G01X240729Y264796D02*
X240728Y264787D01*
G01X240730Y264802D02*
X240729Y264796D01*
G01X240731Y264803D02*
X240730Y264802D01*
G01X232677Y307579D02*
G03X231496Y306398I0J-1181D01*
G01X238976D02*
G03X237795Y307579I-1181J0D01*
G01X237126Y302303D02*
G03I-1890J0D01*
G01X237598D02*
G03I-2362J0D01*
G01X246063Y300335D02*
X242717Y296988D01*
G01X236220Y294311D02*
X237402Y295492D01*
G01X232752Y299232D02*
X234055Y301201D01*
G01X238728Y307123D02*
X236417Y302894D01*
G01X246063Y307618D02*
X224409D01*
G01X232677Y307579D02*
X237795D01*
G01X234055Y302894D02*
X236417D01*
G01X234055Y301201D02*
X236417D01*
G01X227756Y299232D02*
X242126D01*
G01X227756Y297854D02*
X231496D01*
G01X242126D02*
X238976D01*
G01X227756Y296988D02*
X242717D01*
G01X229528Y295492D02*
X237402D01*
G01X230709Y294311D02*
X236220D01*
G01X240728Y291673D02*
X239744D01*
G01X239746Y291181D02*
X245079D01*
G01Y291142D02*
X240731D01*
G01X245079Y289803D02*
X239746D01*
G01X239744Y289311D02*
X240728D01*
G01Y286673D02*
X239744D01*
G01X239746Y286181D02*
X245079D01*
G01Y286142D02*
X240731D01*
G01X245079Y284803D02*
X239746D01*
G01X239744Y284311D02*
X240728D01*
G01Y281673D02*
X239744D01*
G01X239746Y281181D02*
X245079D01*
G01Y281142D02*
X240731D01*
G01X245079Y279803D02*
X239746D01*
G01X239744Y279311D02*
X240728D01*
G01Y276673D02*
X239744D01*
G01X239746Y276181D02*
X245079D01*
G01Y276142D02*
X240731D01*
G01X245079Y274803D02*
X239746D01*
G01X239744Y274311D02*
X240728D01*
G01Y271673D02*
X239744D01*
G01X239746Y271181D02*
X245079D01*
G01Y271142D02*
X240731D01*
G01X245079Y269803D02*
X239746D01*
G01X239744Y269311D02*
X240728D01*
G01Y266673D02*
X239744D01*
G01X239746Y266181D02*
X245079D01*
G01Y266142D02*
X240731D01*
G01X245079Y264803D02*
X239746D01*
G01X239744Y264311D02*
X240728D01*
G01Y261673D02*
X239744D01*
G01X239746Y261181D02*
X245079D01*
G01Y261142D02*
X240731D01*
G01X239744Y291377D02*
X240699Y291378D01*
G01X240728Y289607D02*
X239744Y289606D01*
G01Y286377D02*
X240699Y286378D01*
G01X240728Y284607D02*
X239744Y284606D01*
G01Y281377D02*
X240699Y281378D01*
G01X240728Y279607D02*
X239744Y279606D01*
G01Y276377D02*
X240699Y276378D01*
G01X240728Y274607D02*
X239744Y274606D01*
G01Y271377D02*
X240699Y271378D01*
G01X240728Y269607D02*
X239744Y269606D01*
G01Y266377D02*
X240699Y266378D01*
G01X240728Y264607D02*
X239744Y264606D01*
G01Y261377D02*
X240699Y261378D01*
G01X240728Y261155D02*
X240729Y261164D01*
G01X240728Y266155D02*
X240729Y266164D01*
G01X240728Y271155D02*
X240729Y271164D01*
G01X240728Y276155D02*
X240729Y276164D01*
G01X240728Y281155D02*
X240729Y281164D01*
G01X240728Y286155D02*
X240729Y286164D01*
G01X240728Y291155D02*
X240729Y291164D01*
G01X246063Y300335D02*
Y316083D01*
G01X245079Y289803D02*
Y291181D01*
G01Y284803D02*
Y286181D01*
G01Y279803D02*
Y281181D01*
G01Y274803D02*
Y276181D01*
G01Y269803D02*
Y271181D01*
G01Y264803D02*
Y266181D01*
G01X241909D02*
Y264803D01*
G01Y271181D02*
Y269803D01*
G01Y276181D02*
Y274803D01*
G01Y281181D02*
Y279803D01*
G01Y286181D02*
Y284803D01*
G01Y291181D02*
Y289803D01*
G01X240728Y261156D02*
Y261299D01*
G01Y271156D02*
Y271299D01*
G01Y266156D02*
Y266299D01*
G01Y281156D02*
Y281299D01*
G01Y276156D02*
Y276299D01*
G01Y291156D02*
Y291299D01*
G01Y286156D02*
Y286299D01*
G01Y289311D02*
Y291673D01*
G01Y284311D02*
Y286673D01*
G01Y279311D02*
Y281673D01*
G01Y274311D02*
Y276673D01*
G01Y269311D02*
Y271673D01*
G01Y264311D02*
Y266673D01*
G01X239744D02*
Y264311D01*
G01Y271673D02*
Y269311D01*
G01Y276673D02*
Y274311D01*
G01Y281673D02*
Y279311D01*
G01Y286673D02*
Y284311D01*
G01Y291673D02*
Y289311D01*
G01X238976Y306398D02*
Y297854D01*
G01X236417Y302894D02*
Y301201D01*
G01X234055D02*
Y302894D01*
G01X231496Y297854D02*
Y306398D01*
G01X224409Y316083D02*
Y300335D01*
G01X234055Y302894D02*
X231745Y307123D01*
G01X236417Y301201D02*
X237721Y299232D01*
G01X229528Y295492D02*
X230709Y294311D01*
G01X224409Y300335D02*
X227756Y296988D01*
G01X239173Y316673D02*
G03X238583Y317264I-590J1D01*
G01X231890D02*
G03X231299Y316673I0J-591D01*
G01X234055Y315492D02*
G03Y313524I0J-984D01*
G01X236417D02*
G03Y315492I0J984D01*
G01X246063Y316083D02*
G03X244094Y318051I-1968J0D01*
G01X226378D02*
G03X224409Y316083I0J-1969D01*
G01X244094Y318051D02*
X226378D01*
G01X238583Y317264D02*
X231890D01*
G01X236417Y315492D02*
X234055D01*
G01Y313524D02*
X236417D01*
G01X239173Y312146D02*
X231299D01*
G01Y310571D02*
X239173D01*
G01D02*
Y316673D01*
G01X231299Y310571D02*
Y316673D01*
G01Y592067D02*
G03X231890Y591476I591J0D01*
G01X238583D02*
G03X239173Y592067I-1J591D01*
G01X236417Y593248D02*
G03Y595217I0J985D01*
G01X234055D02*
G03Y593248I0J-985D01*
G01X224409Y592657D02*
G03X226378Y590689I1969J1D01*
G01X244094D02*
G03X246063Y592657I0J1969D01*
G01X239173Y598169D02*
X231299D01*
G01Y596594D02*
X239173D01*
G01X236417Y595217D02*
X234055D01*
G01Y593248D02*
X236417D01*
G01X238583Y591476D02*
X231890D01*
G01X244094Y590689D02*
X226378D01*
G01X246063Y592657D02*
Y608406D01*
G01X239173Y598169D02*
Y592067D01*
G01X231299Y598169D02*
Y592067D01*
G01X224409Y608406D02*
Y592657D01*
G01X240695Y619035D02*
X240699Y619134D01*
G01X240690Y618963D02*
X240695Y619035D01*
G01X240692Y618937D02*
X240690Y618963D01*
G01X240695Y624035D02*
X240699Y624134D01*
G01X240690Y623963D02*
X240695Y624035D01*
G01X240692Y623937D02*
X240690Y623963D01*
G01X240695Y629035D02*
X240699Y629134D01*
G01X240690Y628963D02*
X240695Y629035D01*
G01X240692Y628937D02*
X240690Y628963D01*
G01X240695Y634035D02*
X240699Y634134D01*
G01X240690Y633963D02*
X240695Y634035D01*
G01X240692Y633937D02*
X240690Y633963D01*
G01X240695Y639035D02*
X240699Y639134D01*
G01X240690Y638963D02*
X240695Y639035D01*
G01X240692Y638937D02*
X240690Y638963D01*
G01X240695Y644035D02*
X240699Y644134D01*
G01X240690Y643963D02*
X240695Y644035D01*
G01X240692Y643937D02*
X240690Y643963D01*
G01X239745Y647557D02*
X239746Y647559D01*
G01X239744Y647552D02*
X239745Y647557D01*
G01X239744Y647543D02*
Y647552D01*
G01X239745Y642557D02*
X239746Y642559D01*
G01X239744Y642552D02*
X239745Y642557D01*
G01X239744Y642543D02*
Y642552D01*
G01X239745Y637557D02*
X239746Y637559D01*
G01X239744Y637552D02*
X239745Y637557D01*
G01X239744Y637543D02*
Y637552D01*
G01X239745Y632557D02*
X239746Y632559D01*
G01X239744Y632552D02*
X239745Y632557D01*
G01X239744Y632543D02*
Y632552D01*
G01X239745Y627557D02*
X239746Y627559D01*
G01X239744Y627552D02*
X239745Y627557D01*
G01X239744Y627543D02*
Y627552D01*
G01X239745Y622557D02*
X239746Y622559D01*
G01X239744Y622552D02*
X239745Y622557D01*
G01X239744Y622543D02*
Y622552D01*
G01X239745Y617557D02*
X239746Y617559D01*
G01X239744Y617552D02*
X239745Y617557D01*
G01X239744Y617543D02*
Y617552D01*
G01Y618944D02*
Y618954D01*
G01X239745Y618939D02*
X239744Y618944D01*
G01X239746Y618937D02*
X239745Y618939D01*
G01X239744Y623944D02*
Y623954D01*
G01X239745Y623939D02*
X239744Y623944D01*
G01X239746Y623937D02*
X239745Y623939D01*
G01X239744Y628944D02*
Y628954D01*
G01X239745Y628939D02*
X239744Y628944D01*
G01X239746Y628937D02*
X239745Y628939D01*
G01X239744Y633944D02*
Y633954D01*
G01X239745Y633939D02*
X239744Y633944D01*
G01X239746Y633937D02*
X239745Y633939D01*
G01X239744Y638944D02*
Y638954D01*
G01X239745Y638939D02*
X239744Y638944D01*
G01X239746Y638937D02*
X239745Y638939D01*
G01X239744Y643944D02*
Y643954D01*
G01X239745Y643939D02*
X239744Y643944D01*
G01X239746Y643937D02*
X239745Y643939D01*
G01X240720Y619081D02*
X240728Y619055D01*
G01X240711Y619107D02*
X240720Y619081D01*
G01X240699Y619134D02*
X240711Y619107D01*
G01X240720Y624081D02*
X240728Y624055D01*
G01X240711Y624107D02*
X240720Y624081D01*
G01X240699Y624134D02*
X240711Y624107D01*
G01X240720Y629081D02*
X240728Y629055D01*
G01X240711Y629107D02*
X240720Y629081D01*
G01X240699Y629134D02*
X240711Y629107D01*
G01X240720Y634081D02*
X240728Y634055D01*
G01X240711Y634107D02*
X240720Y634081D01*
G01X240699Y634134D02*
X240711Y634107D01*
G01X240720Y639081D02*
X240728Y639055D01*
G01X240711Y639107D02*
X240720Y639081D01*
G01X240699Y639134D02*
X240711Y639107D01*
G01X240720Y644081D02*
X240728Y644055D01*
G01X240711Y644107D02*
X240720Y644081D01*
G01X240699Y644134D02*
X240711Y644107D01*
G01Y618932D02*
X240692Y618937D01*
G01X240726Y618918D02*
X240711Y618932D01*
G01X240731Y618898D02*
X240726Y618918D01*
G01X240711Y623932D02*
X240692Y623937D01*
G01X240726Y623918D02*
X240711Y623932D01*
G01X240731Y623898D02*
X240726Y623918D01*
G01X240711Y628932D02*
X240692Y628937D01*
G01X240726Y628918D02*
X240711Y628932D01*
G01X240731Y628898D02*
X240726Y628918D01*
G01X240711Y633932D02*
X240692Y633937D01*
G01X240726Y633918D02*
X240711Y633932D01*
G01X240731Y633898D02*
X240726Y633918D01*
G01X240711Y638932D02*
X240692Y638937D01*
G01X240726Y638918D02*
X240711Y638932D01*
G01X240731Y638898D02*
X240726Y638918D01*
G01X240711Y643932D02*
X240692Y643937D01*
G01X240726Y643918D02*
X240711Y643932D01*
G01X240731Y643898D02*
X240726Y643918D01*
G01X240729Y618904D02*
X240728Y618911D01*
G01X240730Y618900D02*
X240729Y618904D01*
G01X240731Y618898D02*
X240730Y618900D01*
G01X240729Y623904D02*
X240728Y623911D01*
G01X240730Y623900D02*
X240729Y623904D01*
G01X240731Y623898D02*
X240730Y623900D01*
G01X240729Y628904D02*
X240728Y628911D01*
G01X240730Y628900D02*
X240729Y628904D01*
G01X240731Y628898D02*
X240730Y628900D01*
G01X240729Y633904D02*
X240728Y633911D01*
G01X240730Y633900D02*
X240729Y633904D01*
G01X240731Y633898D02*
X240730Y633900D01*
G01X240729Y638904D02*
X240728Y638911D01*
G01X240730Y638900D02*
X240729Y638904D01*
G01X240731Y638898D02*
X240730Y638900D01*
G01X240729Y643904D02*
X240728Y643911D01*
G01X240730Y643900D02*
X240729Y643904D01*
G01X240731Y643898D02*
X240730Y643900D01*
G01X240729Y647552D02*
X240728Y647543D01*
G01X240730Y647557D02*
X240729Y647552D01*
G01X240731Y647559D02*
X240730Y647557D01*
G01X240729Y642552D02*
X240728Y642543D01*
G01X240730Y642557D02*
X240729Y642552D01*
G01X240731Y642559D02*
X240730Y642557D01*
G01X240729Y637552D02*
X240728Y637543D01*
G01X240730Y637557D02*
X240729Y637552D01*
G01X240731Y637559D02*
X240730Y637557D01*
G01X240729Y632552D02*
X240728Y632543D01*
G01X240730Y632557D02*
X240729Y632552D01*
G01X240731Y632559D02*
X240730Y632557D01*
G01X240729Y627552D02*
X240728Y627543D01*
G01X240730Y627557D02*
X240729Y627552D01*
G01X240731Y627559D02*
X240730Y627557D01*
G01X240729Y622552D02*
X240728Y622543D01*
G01X240730Y622557D02*
X240729Y622552D01*
G01X240731Y622559D02*
X240730Y622557D01*
G01X240729Y617552D02*
X240728Y617543D01*
G01X240730Y617557D02*
X240729Y617552D01*
G01X240731Y617559D02*
X240730Y617557D01*
G01X240716Y618929D02*
X240727Y618913D01*
G01X240691Y618937D02*
X240716Y618929D01*
G01Y623929D02*
X240727Y623913D01*
G01X240691Y623937D02*
X240716Y623929D01*
G01Y628929D02*
X240727Y628913D01*
G01X240691Y628937D02*
X240716Y628929D01*
G01Y633929D02*
X240727Y633913D01*
G01X240691Y633937D02*
X240716Y633929D01*
G01Y638929D02*
X240727Y638913D01*
G01X240691Y638937D02*
X240716Y638929D01*
G01Y643929D02*
X240727Y643913D01*
G01X240691Y643937D02*
X240716Y643929D01*
G01X236339Y606437D02*
G03I-1103J0D01*
G01X237795Y601161D02*
G03X238976Y602343I0J1181D01*
G01X231496D02*
G03X232677Y601161I1181J-1D01*
G01X236811Y606437D02*
G03I-1575J0D01*
G01X245079Y647559D02*
X239746D01*
G01X239744Y647067D02*
X240728D01*
G01Y644429D02*
X239744D01*
G01X239746Y643937D02*
X245079D01*
G01Y643898D02*
X240731D01*
G01X245079Y642559D02*
X239746D01*
G01X239744Y642067D02*
X240728D01*
G01Y639429D02*
X239744D01*
G01X239746Y638937D02*
X245079D01*
G01Y638898D02*
X240731D01*
G01X245079Y637559D02*
X239746D01*
G01X239744Y637067D02*
X240728D01*
G01Y634429D02*
X239744D01*
G01X239746Y633937D02*
X245079D01*
G01Y633898D02*
X240731D01*
G01X245079Y632559D02*
X239746D01*
G01X239744Y632067D02*
X240728D01*
G01Y629429D02*
X239744D01*
G01X239746Y628937D02*
X245079D01*
G01Y628898D02*
X240731D01*
G01X245079Y627559D02*
X239746D01*
G01X239744Y627067D02*
X240728D01*
G01Y624429D02*
X239744D01*
G01X239746Y623937D02*
X245079D01*
G01Y623898D02*
X240731D01*
G01X245079Y622559D02*
X239746D01*
G01X239744Y622067D02*
X240728D01*
G01Y619429D02*
X239744D01*
G01X239746Y618937D02*
X245079D01*
G01Y618898D02*
X240731D01*
G01X245079Y617559D02*
X239746D01*
G01X239744Y617067D02*
X240728D01*
G01Y647363D02*
X239744Y647362D01*
G01Y644133D02*
X240699Y644134D01*
G01X240728Y642363D02*
X239744Y642362D01*
G01Y639133D02*
X240699Y639134D01*
G01X240728Y637363D02*
X239744Y637362D01*
G01Y634133D02*
X240699Y634134D01*
G01X240728Y632363D02*
X239744Y632362D01*
G01Y629133D02*
X240699Y629134D01*
G01X240728Y627363D02*
X239744Y627362D01*
G01Y624133D02*
X240699Y624134D01*
G01X240728Y622363D02*
X239744Y622362D01*
G01Y619133D02*
X240699Y619134D01*
G01X240728Y617363D02*
X239744Y617362D01*
G01X236220Y614429D02*
X230709D01*
G01X237402Y613248D02*
X229528D01*
G01X242717Y611752D02*
X227756D01*
G01X238976Y610886D02*
X242126D01*
G01X231496D02*
X227756D01*
G01Y609508D02*
X242126D01*
G01X236417Y607539D02*
X234055D01*
G01X236417Y605846D02*
X234055D01*
G01X237795Y601161D02*
X232677D01*
G01X246063Y601122D02*
X224409D01*
G01X230709Y614429D02*
X229528Y613248D01*
G01X227756Y611752D02*
X224409Y608406D01*
G01X237721Y609508D02*
X236417Y607539D01*
G01X231745Y601617D02*
X234055Y605846D01*
G01X242717Y611752D02*
X246063Y608406D01*
G01X236220Y614429D02*
X237402Y613248D01*
G01X236417Y605846D02*
X238728Y601617D01*
G01X234055Y607539D02*
X232752Y609508D01*
G01X240728Y618911D02*
X240729Y618920D01*
G01X240728Y623911D02*
X240729Y623920D01*
G01X240728Y628911D02*
X240729Y628920D01*
G01X240728Y633911D02*
X240729Y633920D01*
G01X240728Y638911D02*
X240729Y638920D01*
G01X240728Y643911D02*
X240729Y643920D01*
G01X245079Y647559D02*
Y648937D01*
G01Y642559D02*
Y643937D01*
G01Y637559D02*
Y638937D01*
G01Y632559D02*
Y633937D01*
G01Y627559D02*
Y628937D01*
G01Y622559D02*
Y623937D01*
G01Y617559D02*
Y618937D01*
G01X242717Y749744D02*
Y611752D01*
G01X242126Y751988D02*
Y609508D01*
G01X241909Y618937D02*
Y617559D01*
G01Y623937D02*
Y622559D01*
G01Y628937D02*
Y627559D01*
G01Y633937D02*
Y632559D01*
G01Y638937D02*
Y637559D01*
G01Y643937D02*
Y642559D01*
G01Y648937D02*
Y647559D01*
G01X240728Y647067D02*
Y649429D01*
G01Y642067D02*
Y644429D01*
G01Y637067D02*
Y639429D01*
G01Y632067D02*
Y634429D01*
G01Y627067D02*
Y629429D01*
G01Y622067D02*
Y624429D01*
G01Y617067D02*
Y619429D01*
G01X239744D02*
Y617067D01*
G01Y624429D02*
Y622067D01*
G01Y629429D02*
Y627067D01*
G01Y634429D02*
Y632067D01*
G01Y639429D02*
Y637067D01*
G01Y644429D02*
Y642067D01*
G01Y649429D02*
Y647067D01*
G01X238976Y610886D02*
Y602343D01*
G01X237402Y649705D02*
Y613248D01*
G01X236417Y607539D02*
Y605846D01*
G01X236220Y650886D02*
Y614429D01*
G01X234055Y605846D02*
Y607539D01*
G01X231496Y602343D02*
Y610886D01*
G01X230709Y614429D02*
Y747067D01*
G01X229528Y613248D02*
Y748248D01*
G01X227756Y648543D02*
Y609508D01*
G01X240695Y649035D02*
X240699Y649134D01*
G01X240690Y648963D02*
X240695Y649035D01*
G01X240692Y648937D02*
X240690Y648963D01*
G01X240695Y674035D02*
X240699Y674134D01*
G01X240690Y673963D02*
X240695Y674035D01*
G01X240692Y673937D02*
X240690Y673963D01*
G01X240695Y679035D02*
X240699Y679134D01*
G01X240690Y678963D02*
X240695Y679035D01*
G01X240692Y678937D02*
X240690Y678963D01*
G01X240695Y684035D02*
X240699Y684134D01*
G01X240690Y683963D02*
X240695Y684035D01*
G01X240692Y683937D02*
X240690Y683963D01*
G01X240695Y689035D02*
X240699Y689134D01*
G01X240690Y688963D02*
X240695Y689035D01*
G01X240692Y688937D02*
X240690Y688963D01*
G01X240695Y694035D02*
X240699Y694134D01*
G01X240690Y693963D02*
X240695Y694035D01*
G01X240692Y693937D02*
X240690Y693963D01*
G01X226319Y663341D02*
Y663333D01*
G01X226318Y663345D02*
X226319Y663341D01*
G01X226318Y663336D02*
Y663345D01*
G01X226359Y670972D02*
X226358Y670984D01*
G01X226356Y670959D02*
X226359Y670972D01*
G01X226356Y670945D02*
Y670959D01*
G01X226359Y667822D02*
X226358Y667835D01*
G01X226356Y667809D02*
X226359Y667822D01*
G01X226356Y667796D02*
Y667809D01*
G01X226359Y664673D02*
X226358Y664685D01*
G01X226356Y664660D02*
X226359Y664673D01*
G01X226356Y664646D02*
Y664660D01*
G01X226359Y661523D02*
X226358Y661535D01*
G01X226356Y661510D02*
X226359Y661523D01*
G01X226356Y661496D02*
Y661510D01*
G01X226359Y658374D02*
X226358Y658386D01*
G01X226356Y658361D02*
X226359Y658374D01*
G01X226356Y658347D02*
Y658361D01*
G01X226359Y655224D02*
X226358Y655236D01*
G01X226356Y655211D02*
X226359Y655224D01*
G01X226356Y655197D02*
Y655211D01*
G01X226359Y652074D02*
X226358Y652087D01*
G01X226356Y652061D02*
X226359Y652074D01*
G01X226356Y652048D02*
Y652061D01*
G01X239745Y692557D02*
X239746Y692559D01*
G01X239744Y692552D02*
X239745Y692557D01*
G01X239744Y692543D02*
Y692552D01*
G01X239745Y687557D02*
X239746Y687559D01*
G01X239744Y687552D02*
X239745Y687557D01*
G01X239744Y687543D02*
Y687552D01*
G01X239745Y682557D02*
X239746Y682559D01*
G01X239744Y682552D02*
X239745Y682557D01*
G01X239744Y682543D02*
Y682552D01*
G01X239745Y677557D02*
X239746Y677559D01*
G01X239744Y677552D02*
X239745Y677557D01*
G01X239744Y677543D02*
Y677552D01*
G01X239745Y672557D02*
X239746Y672559D01*
G01X239744Y672552D02*
X239745Y672557D01*
G01X239744Y672543D02*
Y672552D01*
G01X226319Y669640D02*
Y669632D01*
G01X226318Y669644D02*
X226319Y669640D01*
G01X226318Y669637D02*
Y669644D01*
G01X226356Y669435D02*
X226355Y669448D01*
G01X226359Y669422D02*
X226356Y669435D01*
G01X226358Y669409D02*
X226359Y669422D01*
G01X226356Y666285D02*
X226355Y666299D01*
G01X226359Y666272D02*
X226356Y666285D01*
G01X226358Y666260D02*
X226359Y666272D01*
G01X226356Y663136D02*
X226355Y663149D01*
G01X226359Y663123D02*
X226356Y663136D01*
G01X226358Y663110D02*
X226359Y663123D01*
G01X226356Y659986D02*
X226355Y660000D01*
G01X226359Y659973D02*
X226356Y659986D01*
G01X226358Y659961D02*
X226359Y659973D01*
G01X226356Y656837D02*
X226355Y656850D01*
G01X226359Y656824D02*
X226356Y656837D01*
G01X226358Y656811D02*
X226359Y656824D01*
G01X226356Y653687D02*
X226355Y653700D01*
G01X226359Y653674D02*
X226356Y653687D01*
G01X226358Y653661D02*
X226359Y653674D01*
G01X226356Y650537D02*
X226355Y650551D01*
G01X226359Y650524D02*
X226356Y650537D01*
G01X226358Y650512D02*
X226359Y650524D01*
G01X227266Y670959D02*
X227267Y670945D01*
G01X227263Y670972D02*
X227266Y670959D01*
G01X227264Y670984D02*
X227263Y670972D01*
G01X227266Y667809D02*
X227267Y667796D01*
G01X227263Y667822D02*
X227266Y667809D01*
G01X227264Y667835D02*
X227263Y667822D01*
G01X227266Y664659D02*
X227267Y664646D01*
G01X227263Y664672D02*
X227266Y664659D01*
G01X227264Y664685D02*
X227263Y664672D01*
G01X227266Y661510D02*
X227267Y661496D01*
G01X227263Y661523D02*
X227266Y661510D01*
G01X227264Y661535D02*
X227263Y661523D01*
G01X227266Y658360D02*
X227267Y658347D01*
G01X227263Y658373D02*
X227266Y658360D01*
G01X227264Y658386D02*
X227263Y658373D01*
G01X227266Y655211D02*
X227267Y655197D01*
G01X227263Y655224D02*
X227266Y655211D01*
G01X227264Y655236D02*
X227263Y655224D01*
G01X227266Y652061D02*
X227267Y652048D01*
G01X227263Y652074D02*
X227266Y652061D01*
G01X227264Y652087D02*
X227263Y652074D01*
G01X226319Y657041D02*
Y657034D01*
G01X226318Y657046D02*
X226319Y657041D01*
G01X226317Y657039D02*
X226318Y657046D01*
G01X226319Y666490D02*
Y666483D01*
G01X226318Y666495D02*
X226319Y666490D01*
G01X226317Y666488D02*
X226318Y666495D01*
G01X227263Y669422D02*
X227264Y669409D01*
G01X227266Y669435D02*
X227263Y669422D01*
G01X227267Y669448D02*
X227266Y669435D01*
G01X227263Y666272D02*
X227264Y666260D01*
G01X227266Y666285D02*
X227263Y666272D01*
G01X227267Y666299D02*
X227266Y666285D01*
G01X227263Y663123D02*
X227264Y663110D01*
G01X227266Y663136D02*
X227263Y663123D01*
G01X227267Y663149D02*
X227266Y663136D01*
G01X227263Y659973D02*
X227264Y659961D01*
G01X227266Y659986D02*
X227263Y659973D01*
G01X227267Y660000D02*
X227266Y659986D01*
G01X227263Y656824D02*
X227264Y656811D01*
G01X227266Y656837D02*
X227263Y656824D01*
G01X227267Y656850D02*
X227266Y656837D01*
G01X227263Y653674D02*
X227264Y653661D01*
G01X227266Y653687D02*
X227263Y653674D01*
G01X227267Y653700D02*
X227266Y653687D01*
G01X227263Y650524D02*
X227264Y650512D01*
G01X227266Y650537D02*
X227263Y650524D01*
G01X227267Y650551D02*
X227266Y650537D01*
G01X226319Y650743D02*
Y650735D01*
G01X226318Y650747D02*
X226319Y650743D01*
G01X226317Y650741D02*
X226318Y650747D01*
G01X227303Y650742D02*
Y650735D01*
G01X227302Y650747D02*
X227303Y650742D01*
G01X227302Y650748D02*
Y650747D01*
G01X227303Y653892D02*
Y653884D01*
G01X227302Y653896D02*
X227303Y653892D01*
G01X227302Y653898D02*
Y653896D01*
G01X226341Y650712D02*
X226356Y650709D01*
G01X226328Y650720D02*
X226341Y650712D01*
G01X226317Y650741D02*
X226328Y650720D01*
G01X227302Y651871D02*
X227303Y651864D01*
G01X227301Y651877D02*
X227302Y651871D01*
G01X227298Y651883D02*
X227301Y651877D01*
G01X227302Y655020D02*
X227303Y655014D01*
G01X227301Y655027D02*
X227302Y655020D01*
G01X227298Y655033D02*
X227301Y655027D01*
G01X227302Y658170D02*
X227303Y658163D01*
G01X227301Y658176D02*
X227302Y658170D01*
G01X227298Y658182D02*
X227301Y658176D01*
G01X227302Y661320D02*
X227303Y661313D01*
G01X227301Y661326D02*
X227302Y661320D01*
G01X227298Y661332D02*
X227301Y661326D01*
G01X227302Y664469D02*
X227303Y664463D01*
G01X227301Y664476D02*
X227302Y664469D01*
G01X227298Y664481D02*
X227301Y664476D01*
G01X227302Y667619D02*
X227303Y667612D01*
G01X227301Y667625D02*
X227302Y667619D01*
G01X227298Y667631D02*
X227301Y667625D01*
G01X227302Y670769D02*
X227303Y670762D01*
G01X227301Y670775D02*
X227302Y670769D01*
G01X227298Y670781D02*
X227301Y670775D01*
G01X227264Y650704D02*
X227265Y650698D01*
G01X227263Y650707D02*
X227264Y650704D01*
G01X227262Y650709D02*
X227263Y650707D01*
G01X227264Y653853D02*
X227265Y653847D01*
G01X227263Y653857D02*
X227264Y653853D01*
G01X227262Y653858D02*
X227263Y653857D01*
G01X227264Y657003D02*
X227265Y656997D01*
G01X227263Y657007D02*
X227264Y657003D01*
G01X227262Y657008D02*
X227263Y657007D01*
G01X227264Y660152D02*
X227265Y660146D01*
G01X227263Y660156D02*
X227264Y660152D01*
G01X227262Y660157D02*
X227263Y660156D01*
G01X227264Y663302D02*
X227265Y663296D01*
G01X227263Y663306D02*
X227264Y663302D01*
G01X227262Y663307D02*
X227263Y663306D01*
G01X227264Y669601D02*
X227265Y669595D01*
G01X227263Y669605D02*
X227264Y669601D01*
G01X227262Y669606D02*
X227263Y669605D01*
G01X239744Y648944D02*
Y648954D01*
G01X239745Y648939D02*
X239744Y648944D01*
G01X239746Y648937D02*
X239745Y648939D01*
G01X239744Y673944D02*
Y673954D01*
G01X239745Y673939D02*
X239744Y673944D01*
G01X239746Y673937D02*
X239745Y673939D01*
G01X239744Y678944D02*
Y678954D01*
G01X239745Y678939D02*
X239744Y678944D01*
G01X239746Y678937D02*
X239745Y678939D01*
G01X239744Y683944D02*
Y683954D01*
G01X239745Y683939D02*
X239744Y683944D01*
G01X239746Y683937D02*
X239745Y683939D01*
G01X240720Y649081D02*
X240728Y649055D01*
G01X240711Y649107D02*
X240720Y649081D01*
G01X240699Y649134D02*
X240711Y649107D01*
G01X240720Y674081D02*
X240728Y674055D01*
G01X240711Y674107D02*
X240720Y674081D01*
G01X240699Y674134D02*
X240711Y674107D01*
G01X240720Y679081D02*
X240728Y679055D01*
G01X240711Y679107D02*
X240720Y679081D01*
G01X240699Y679134D02*
X240711Y679107D01*
G01X240720Y684081D02*
X240728Y684055D01*
G01X240711Y684107D02*
X240720Y684081D01*
G01X240699Y684134D02*
X240711Y684107D01*
G01X226337Y660163D02*
X226356Y660157D01*
G01X226323Y660175D02*
X226337Y660163D01*
G01X226317Y660193D02*
X226323Y660175D01*
G01X240711Y648932D02*
X240692Y648937D01*
G01X240726Y648918D02*
X240711Y648932D01*
G01X240731Y648898D02*
X240726Y648918D01*
G01X240711Y673932D02*
X240692Y673937D01*
G01X240726Y673918D02*
X240711Y673932D01*
G01X240731Y673898D02*
X240726Y673918D01*
G01X240711Y678932D02*
X240692Y678937D01*
G01X240726Y678918D02*
X240711Y678932D01*
G01X240731Y678898D02*
X240726Y678918D01*
G01X240711Y683932D02*
X240692Y683937D01*
G01X240726Y683918D02*
X240711Y683932D01*
G01X240731Y683898D02*
X240726Y683918D01*
G01X240711Y688932D02*
X240692Y688937D01*
G01X240726Y688918D02*
X240711Y688932D01*
G01X240731Y688898D02*
X240726Y688918D01*
G01X240711Y693932D02*
X240692Y693937D01*
G01X240726Y693918D02*
X240711Y693932D01*
G01X240731Y693898D02*
X240726Y693918D01*
G01X227296Y658171D02*
X227288Y658180D01*
G01X227300Y658161D02*
X227296Y658171D01*
G01X227302Y658150D02*
X227300Y658161D01*
G01X227296Y651872D02*
X227288Y651880D01*
G01X227300Y651861D02*
X227296Y651872D01*
G01X227302Y651850D02*
X227300Y651861D01*
G01X227296Y655021D02*
X227288Y655030D01*
G01X227300Y655011D02*
X227296Y655021D01*
G01X227302Y655000D02*
X227300Y655011D01*
G01X227296Y661320D02*
X227288Y661329D01*
G01X227300Y661310D02*
X227296Y661320D01*
G01X227302Y661299D02*
X227300Y661310D01*
G01X227296Y664470D02*
X227288Y664479D01*
G01X227300Y664460D02*
X227296Y664470D01*
G01X227302Y664449D02*
X227300Y664460D01*
G01X227296Y667620D02*
X227288Y667628D01*
G01X227300Y667609D02*
X227296Y667620D01*
G01X227302Y667598D02*
X227300Y667609D01*
G01X227296Y670769D02*
X227288Y670778D01*
G01X227300Y670759D02*
X227296Y670769D01*
G01X227302Y670748D02*
X227300Y670759D01*
G01X226332Y670779D02*
X226356Y670787D01*
G01X226320Y670765D02*
X226332Y670779D01*
G01X226319Y670758D02*
X226320Y670765D01*
G01X226332Y667630D02*
X226356Y667638D01*
G01X226320Y667615D02*
X226332Y667630D01*
G01X226319Y667608D02*
X226320Y667615D01*
G01X226332Y664480D02*
X226356Y664488D01*
G01X226320Y664465D02*
X226332Y664480D01*
G01X226319Y664459D02*
X226320Y664465D01*
G01X226332Y661330D02*
X226356Y661339D01*
G01X226320Y661316D02*
X226332Y661330D01*
G01X226319Y661309D02*
X226320Y661316D01*
G01X226332Y658181D02*
X226356Y658189D01*
G01X226320Y658166D02*
X226332Y658181D01*
G01X226319Y658159D02*
X226320Y658166D01*
G01X226332Y655031D02*
X226356Y655039D01*
G01X226320Y655017D02*
X226332Y655031D01*
G01X226319Y655010D02*
X226320Y655017D01*
G01X226332Y651881D02*
X226356Y651890D01*
G01X226320Y651867D02*
X226332Y651881D01*
G01X226319Y651860D02*
X226320Y651867D01*
G01X227303Y670754D02*
Y670761D01*
G01Y670750D02*
Y670754D01*
G01X227302Y670748D02*
X227303Y670750D01*
G01Y667605D02*
Y667612D01*
G01Y667600D02*
Y667605D01*
G01X227302Y667598D02*
X227303Y667600D01*
G01Y664455D02*
Y664462D01*
G01Y664451D02*
Y664455D01*
G01X227302Y664449D02*
X227303Y664451D01*
G01Y661306D02*
Y661313D01*
G01Y661301D02*
Y661306D01*
G01X227302Y661299D02*
X227303Y661301D01*
G01Y658156D02*
Y658163D01*
G01Y658152D02*
Y658156D01*
G01X227302Y658150D02*
X227303Y658152D01*
G01Y655006D02*
Y655013D01*
G01Y655002D02*
Y655006D01*
G01X227302Y655000D02*
X227303Y655002D01*
G01Y651857D02*
Y651864D01*
G01Y651852D02*
Y651857D01*
G01X227302Y651850D02*
X227303Y651852D01*
G01X226319Y660191D02*
Y660183D01*
G01X226318Y660196D02*
X226319Y660191D01*
G01X226317Y660193D02*
X226318Y660196D01*
G01X240729Y648904D02*
X240728Y648911D01*
G01X240730Y648900D02*
X240729Y648904D01*
G01X240731Y648898D02*
X240730Y648900D01*
G01X240729Y673904D02*
X240728Y673911D01*
G01X240730Y673900D02*
X240729Y673904D01*
G01X240731Y673898D02*
X240730Y673900D01*
G01X240729Y678904D02*
X240728Y678911D01*
G01X240730Y678900D02*
X240729Y678904D01*
G01X240731Y678898D02*
X240730Y678900D01*
G01X240729Y683904D02*
X240728Y683911D01*
G01X240730Y683900D02*
X240729Y683904D01*
G01X240731Y683898D02*
X240730Y683900D01*
G01X240729Y688904D02*
X240728Y688911D01*
G01X240730Y688900D02*
X240729Y688904D01*
G01X240731Y688898D02*
X240730Y688900D01*
G01X240729Y693904D02*
X240728Y693911D01*
G01X240730Y693900D02*
X240729Y693904D01*
G01X240731Y693898D02*
X240730Y693900D01*
G01X226342Y653861D02*
X226356Y653858D01*
G01X226330Y653868D02*
X226342Y653861D01*
G01X226318Y653887D02*
X226330Y653868D01*
G01X226342Y663310D02*
X226356Y663307D01*
G01X226330Y663317D02*
X226342Y663310D01*
G01X226318Y663335D02*
X226330Y663317D01*
G01X226341Y657011D02*
X226356Y657008D01*
G01X226329Y657019D02*
X226341Y657011D01*
G01X226317Y657039D02*
X226329Y657019D01*
G01X226341Y666459D02*
X226356Y666457D01*
G01X226329Y666467D02*
X226341Y666459D01*
G01X226317Y666487D02*
X226329Y666467D01*
G01X227303Y657041D02*
Y657034D01*
G01X227302Y657046D02*
X227303Y657041D01*
G01X227302Y657047D02*
Y657046D01*
G01X227303Y660191D02*
Y660183D01*
G01X227302Y660196D02*
X227303Y660191D01*
G01X227302Y660197D02*
Y660196D01*
G01X227303Y663341D02*
Y663333D01*
G01X227302Y663345D02*
X227303Y663341D01*
G01X227302Y663346D02*
Y663345D01*
G01X227303Y666490D02*
Y666483D01*
G01X227302Y666495D02*
X227303Y666490D01*
G01X227302Y666496D02*
Y666495D01*
G01X227303Y669640D02*
Y669632D01*
G01X227302Y669644D02*
X227303Y669640D01*
G01X227302Y669646D02*
Y669644D01*
G01X226341Y669609D02*
X226356Y669606D01*
G01X226329Y669617D02*
X226341Y669609D01*
G01X226317Y669637D02*
X226329Y669617D01*
G01X239744Y688944D02*
Y688954D01*
G01X239745Y688939D02*
X239744Y688944D01*
G01X239746Y688937D02*
X239745Y688939D01*
G01X239744Y693944D02*
Y693954D01*
G01X239745Y693939D02*
X239744Y693944D01*
G01X239746Y693937D02*
X239745Y693939D01*
G01X240720Y689081D02*
X240728Y689055D01*
G01X240711Y689107D02*
X240720Y689081D01*
G01X240699Y689134D02*
X240711Y689107D01*
G01X240720Y694081D02*
X240728Y694055D01*
G01X240711Y694107D02*
X240720Y694081D01*
G01X240699Y694134D02*
X240711Y694107D01*
G01X226319Y653892D02*
Y653884D01*
G01X226318Y653896D02*
X226319Y653892D01*
G01X226317Y653894D02*
X226318Y653896D01*
G01X227264Y670793D02*
Y670799D01*
G01X227263Y670789D02*
X227264Y670793D01*
G01X227262Y670787D02*
X227263Y670789D01*
G01X227264Y667643D02*
Y667649D01*
G01X227263Y667639D02*
X227264Y667643D01*
G01X227262Y667638D02*
X227263Y667639D01*
G01X227264Y664493D02*
Y664500D01*
G01X227263Y664490D02*
X227264Y664493D01*
G01X227262Y664488D02*
X227263Y664490D01*
G01X227264Y661344D02*
Y661350D01*
G01X227263Y661340D02*
X227264Y661344D01*
G01X227262Y661339D02*
X227263Y661340D01*
G01X227264Y658194D02*
Y658200D01*
G01X227263Y658191D02*
X227264Y658194D01*
G01X227262Y658189D02*
X227263Y658191D01*
G01X227264Y655044D02*
Y655051D01*
G01X227263Y655041D02*
X227264Y655044D01*
G01X227262Y655039D02*
X227263Y655041D01*
G01X227264Y651895D02*
Y651901D01*
G01X227263Y651891D02*
X227264Y651895D01*
G01X227262Y651890D02*
X227263Y651891D01*
G01X226358Y650704D02*
Y650698D01*
G01X226357Y650707D02*
X226358Y650704D01*
G01X226356Y650709D02*
X226357Y650707D01*
G01X226358Y653854D02*
Y653847D01*
G01X226357Y653857D02*
X226358Y653854D01*
G01X226356Y653858D02*
X226357Y653857D01*
G01X226358Y657003D02*
Y656997D01*
G01X226357Y657007D02*
X226358Y657003D01*
G01X226356Y657008D02*
X226357Y657007D01*
G01X226358Y660153D02*
Y660146D01*
G01X226357Y660156D02*
X226358Y660153D01*
G01X226356Y660157D02*
X226357Y660156D01*
G01X226358Y663302D02*
Y663296D01*
G01X226357Y663306D02*
X226358Y663302D01*
G01X226356Y663307D02*
X226357Y663306D01*
G01X226358Y666452D02*
Y666446D01*
G01X226357Y666456D02*
X226358Y666452D01*
G01X226356Y666457D02*
X226357Y666456D01*
G01X226358Y669602D02*
Y669595D01*
G01X226357Y669605D02*
X226358Y669602D01*
G01X226356Y669606D02*
X226357Y669605D01*
G01X240729Y692552D02*
X240728Y692543D01*
G01X240730Y692557D02*
X240729Y692552D01*
G01X240731Y692559D02*
X240730Y692557D01*
G01X240729Y687552D02*
X240728Y687543D01*
G01X240730Y687557D02*
X240729Y687552D01*
G01X240731Y687559D02*
X240730Y687557D01*
G01X240729Y682552D02*
X240728Y682543D01*
G01X240730Y682557D02*
X240729Y682552D01*
G01X240731Y682559D02*
X240730Y682557D01*
G01X240729Y677552D02*
X240728Y677543D01*
G01X240730Y677557D02*
X240729Y677552D01*
G01X240731Y677559D02*
X240730Y677557D01*
G01X240729Y672552D02*
X240728Y672543D01*
G01X240730Y672557D02*
X240729Y672552D01*
G01X240731Y672559D02*
X240730Y672557D01*
G01X226319Y670754D02*
Y670762D01*
G01X226318Y670750D02*
X226319Y670754D01*
G01X226317Y670748D02*
X226318Y670750D01*
G01X226319Y667605D02*
Y667612D01*
G01X226318Y667600D02*
X226319Y667605D01*
G01X226317Y667598D02*
X226318Y667600D01*
G01X226319Y664455D02*
Y664463D01*
G01X226318Y664450D02*
X226319Y664455D01*
G01X226317Y664449D02*
X226318Y664450D01*
G01X226319Y661306D02*
Y661313D01*
G01X226318Y661301D02*
X226319Y661306D01*
G01X226317Y661299D02*
X226318Y661301D01*
G01X226319Y658156D02*
Y658163D01*
G01X226318Y658151D02*
X226319Y658156D01*
G01X226317Y658150D02*
X226318Y658151D01*
G01X226319Y655006D02*
Y655014D01*
G01X226318Y655002D02*
X226319Y655006D01*
G01X226317Y655000D02*
X226318Y655002D01*
G01X226319Y651857D02*
Y651864D01*
G01X226318Y651852D02*
X226319Y651857D01*
G01X226317Y651850D02*
X226318Y651852D01*
G01X227272Y658188D02*
X227262Y658189D01*
G01X227280Y658185D02*
X227272Y658188D01*
G01X227288Y658180D02*
X227280Y658185D01*
G01X227272Y651889D02*
X227262Y651890D01*
G01X227281Y651885D02*
X227272Y651889D01*
G01X227288Y651880D02*
X227281Y651885D01*
G01X227272Y655038D02*
X227262Y655039D01*
G01X227281Y655035D02*
X227272Y655038D01*
G01X227288Y655030D02*
X227281Y655035D01*
G01X227272Y661337D02*
X227262Y661339D01*
G01X227281Y661334D02*
X227272Y661337D01*
G01X227288Y661329D02*
X227281Y661334D01*
G01X227272Y664487D02*
X227262Y664488D01*
G01X227281Y664484D02*
X227272Y664487D01*
G01X227288Y664479D02*
X227281Y664484D01*
G01X227272Y667637D02*
X227262Y667638D01*
G01X227281Y667633D02*
X227272Y667637D01*
G01X227288Y667628D02*
X227281Y667633D01*
G01X227272Y670786D02*
X227262Y670787D01*
G01X227281Y670783D02*
X227272Y670786D01*
G01X227288Y670778D02*
X227281Y670783D01*
G01X227301Y669620D02*
X227303Y669632D01*
G01X227294Y669609D02*
X227301Y669620D01*
G01X227284Y669600D02*
X227294Y669609D01*
G01X227301Y663320D02*
X227303Y663333D01*
G01X227294Y663309D02*
X227301Y663320D01*
G01X227284Y663301D02*
X227294Y663309D01*
G01X227301Y660171D02*
X227303Y660183D01*
G01X227294Y660160D02*
X227301Y660171D01*
G01X227284Y660152D02*
X227294Y660160D01*
G01X227301Y657021D02*
X227303Y657034D01*
G01X227294Y657010D02*
X227301Y657021D01*
G01X227284Y657002D02*
X227294Y657010D01*
G01X227301Y653872D02*
X227303Y653884D01*
G01X227294Y653861D02*
X227301Y653872D01*
G01X227284Y653852D02*
X227294Y653861D01*
G01X227301Y650722D02*
X227303Y650735D01*
G01X227294Y650711D02*
X227301Y650722D01*
G01X227284Y650703D02*
X227294Y650711D01*
G01X226319Y653888D02*
Y653884D01*
G01X226320Y653882D02*
X226319Y653888D01*
G01X226332Y653867D02*
X226320Y653882D01*
G01X226357Y653858D02*
X226332Y653867D01*
G01X226319Y657038D02*
Y657034D01*
G01X226320Y657031D02*
X226319Y657038D01*
G01X226332Y657016D02*
X226320Y657031D01*
G01X226356Y657008D02*
X226332Y657016D01*
G01X226319Y663337D02*
Y663333D01*
G01X226320Y663331D02*
X226319Y663337D01*
G01X226332Y663315D02*
X226320Y663331D01*
G01X226356Y663307D02*
X226332Y663315D01*
G01X226319Y650739D02*
Y650735D01*
G01X226320Y650732D02*
X226319Y650739D01*
G01X226332Y650717D02*
X226320Y650732D01*
G01X226356Y650709D02*
X226332Y650717D01*
G01X240716Y648929D02*
X240727Y648913D01*
G01X240691Y648937D02*
X240716Y648929D01*
G01X226319Y660187D02*
Y660183D01*
G01X226320Y660182D02*
X226319Y660187D01*
G01X226330Y660167D02*
X226320Y660182D01*
G01X226354Y660158D02*
X226330Y660167D01*
G01X226357Y670793D02*
Y670799D01*
G01Y670789D02*
Y670793D01*
G01X226356Y670787D02*
X226357Y670789D01*
G01Y667643D02*
Y667649D01*
G01Y667639D02*
Y667643D01*
G01X226356Y667638D02*
X226357Y667639D01*
G01Y664493D02*
Y664500D01*
G01Y664489D02*
Y664493D01*
G01X226356Y664488D02*
X226357Y664489D01*
G01Y661344D02*
Y661350D01*
G01Y661340D02*
Y661344D01*
G01X226356Y661339D02*
X226357Y661340D01*
G01Y658194D02*
Y658200D01*
G01Y658190D02*
Y658194D01*
G01X226356Y658189D02*
X226357Y658190D01*
G01Y655044D02*
Y655051D01*
G01Y655041D02*
Y655044D01*
G01X226356Y655039D02*
X226357Y655041D01*
G01Y651895D02*
Y651901D01*
G01Y651891D02*
Y651895D01*
G01X226356Y651890D02*
X226357Y651891D01*
G01X226320Y670768D02*
X226319Y670762D01*
G01X226321Y670774D02*
X226320Y670768D01*
G01X226324Y670780D02*
X226321Y670774D01*
G01X226328Y670785D02*
X226324Y670780D01*
G01X226333Y670790D02*
X226328Y670785D01*
G01X226338Y670794D02*
X226333Y670790D01*
G01X226320Y667619D02*
X226319Y667612D01*
G01X226321Y667625D02*
X226320Y667619D01*
G01X226324Y667630D02*
X226321Y667625D01*
G01X226328Y667636D02*
X226324Y667630D01*
G01X226333Y667640D02*
X226328Y667636D01*
G01X226338Y667644D02*
X226333Y667640D01*
G01X226320Y664469D02*
X226319Y664463D01*
G01X226321Y664475D02*
X226320Y664469D01*
G01X226324Y664481D02*
X226321Y664475D01*
G01X226328Y664486D02*
X226324Y664481D01*
G01X226333Y664491D02*
X226328Y664486D01*
G01X226338Y664494D02*
X226333Y664491D01*
G01X226320Y661319D02*
X226319Y661313D01*
G01X226321Y661326D02*
X226320Y661319D01*
G01X226324Y661331D02*
X226321Y661326D01*
G01X226328Y661337D02*
X226324Y661331D01*
G01X226333Y661341D02*
X226328Y661337D01*
G01X226338Y661345D02*
X226333Y661341D01*
G01X226320Y658170D02*
X226319Y658163D01*
G01X226321Y658176D02*
X226320Y658170D01*
G01X226324Y658181D02*
X226321Y658176D01*
G01X226328Y658187D02*
X226324Y658181D01*
G01X226333Y658191D02*
X226328Y658187D01*
G01X226338Y658195D02*
X226333Y658191D01*
G01X226320Y655020D02*
X226319Y655014D01*
G01X226321Y655026D02*
X226320Y655020D01*
G01X226324Y655032D02*
X226321Y655026D01*
G01X226328Y655037D02*
X226324Y655032D01*
G01X226333Y655042D02*
X226328Y655037D01*
G01X226338Y655046D02*
X226333Y655042D01*
G01X226320Y651870D02*
X226319Y651864D01*
G01X226321Y651877D02*
X226320Y651870D01*
G01X226324Y651882D02*
X226321Y651877D01*
G01X226328Y651888D02*
X226324Y651882D01*
G01X226333Y651892D02*
X226328Y651888D01*
G01X226338Y651896D02*
X226333Y651892D01*
G01X226319Y666487D02*
Y666483D01*
G01X226320Y666480D02*
X226319Y666487D01*
G01X226332Y666465D02*
X226320Y666480D01*
G01X226356Y666457D02*
X226332Y666465D01*
G01X226319Y669636D02*
Y669632D01*
G01X226320Y669630D02*
X226319Y669636D01*
G01X226332Y669615D02*
X226320Y669630D01*
G01X226356Y669606D02*
X226332Y669615D01*
G01X240716Y673929D02*
X240727Y673913D01*
G01X240691Y673937D02*
X240716Y673929D01*
G01Y678929D02*
X240727Y678913D01*
G01X240691Y678937D02*
X240716Y678929D01*
G01Y683929D02*
X240727Y683913D01*
G01X240691Y683937D02*
X240716Y683929D01*
G01Y688929D02*
X240727Y688913D01*
G01X240691Y688937D02*
X240716Y688929D01*
G01Y693929D02*
X240727Y693913D01*
G01X240691Y693937D02*
X240716Y693929D01*
G01X227274Y669608D02*
X227262Y669606D01*
G01X227285Y669613D02*
X227274Y669608D01*
G01Y666459D02*
X227262Y666457D01*
G01X227285Y666464D02*
X227274Y666459D01*
G01Y663309D02*
X227262Y663307D01*
G01X227285Y663314D02*
X227274Y663309D01*
G01Y660159D02*
X227262Y660157D01*
G01X227285Y660165D02*
X227274Y660159D01*
G01Y657010D02*
X227262Y657008D01*
G01X227285Y657015D02*
X227274Y657010D01*
G01Y653860D02*
X227262Y653858D01*
G01X227285Y653865D02*
X227274Y653860D01*
G01Y650711D02*
X227262Y650709D01*
G01X227285Y650716D02*
X227274Y650711D01*
G01X227294Y651888D02*
X227298Y651883D01*
G01X227289Y651893D02*
X227294Y651888D01*
G01X227283Y651896D02*
X227289Y651893D01*
G01X227277Y651899D02*
X227283Y651896D01*
G01X227270Y651901D02*
X227277Y651899D01*
G01X227264Y651901D02*
X227270D01*
G01X227294Y655038D02*
X227298Y655033D01*
G01X227289Y655042D02*
X227294Y655038D01*
G01X227283Y655046D02*
X227289Y655042D01*
G01X227277Y655048D02*
X227283Y655046D01*
G01X227270Y655050D02*
X227277Y655048D01*
G01X227264Y655051D02*
X227270Y655050D01*
G01X227294Y658187D02*
X227298Y658182D01*
G01X227289Y658192D02*
X227294Y658187D01*
G01X227283Y658196D02*
X227289Y658192D01*
G01X227277Y658198D02*
X227283Y658196D01*
G01X227270Y658200D02*
X227277Y658198D01*
G01X227264Y658200D02*
X227270D01*
G01X227294Y661337D02*
X227298Y661332D01*
G01X227289Y661341D02*
X227294Y661337D01*
G01X227283Y661345D02*
X227289Y661341D01*
G01X227277Y661348D02*
X227283Y661345D01*
G01X227270Y661350D02*
X227277Y661348D01*
G01X227264Y661350D02*
X227270D01*
G01X227294Y664487D02*
X227298Y664481D01*
G01X227289Y664491D02*
X227294Y664487D01*
G01X227283Y664495D02*
X227289Y664491D01*
G01X227277Y664497D02*
X227283Y664495D01*
G01X227270Y664499D02*
X227277Y664497D01*
G01X227264Y664500D02*
X227270Y664499D01*
G01X227294Y667636D02*
X227298Y667631D01*
G01X227289Y667641D02*
X227294Y667636D01*
G01X227283Y667644D02*
X227289Y667641D01*
G01X227277Y667647D02*
X227283Y667644D01*
G01X227270Y667649D02*
X227277Y667647D01*
G01X227264Y667649D02*
X227270D01*
G01X227294Y670786D02*
X227298Y670781D01*
G01X227289Y670790D02*
X227294Y670786D01*
G01X227283Y670794D02*
X227289Y670790D01*
G01X227277Y670796D02*
X227283Y670794D01*
G01X227270Y670798D02*
X227277Y670796D01*
G01X227264Y670799D02*
X227270Y670798D01*
G01X226320Y650727D02*
X226319Y650735D01*
G01X226322Y650720D02*
X226320Y650727D01*
G01X226326Y650714D02*
X226322Y650720D01*
G01X226330Y650708D02*
X226326Y650714D01*
G01X226337Y650704D02*
X226330Y650708D01*
G01X226343Y650700D02*
X226337Y650704D01*
G01X226351Y650698D02*
X226343Y650700D01*
G01X226358Y650698D02*
X226351D01*
G01X226320Y653877D02*
X226319Y653884D01*
G01X226322Y653870D02*
X226320Y653877D01*
G01X226326Y653864D02*
X226322Y653870D01*
G01X226330Y653858D02*
X226326Y653864D01*
G01X226337Y653853D02*
X226330Y653858D01*
G01X226343Y653850D02*
X226337Y653853D01*
G01X226351Y653848D02*
X226343Y653850D01*
G01X226358Y653847D02*
X226351Y653848D01*
G01X226320Y657026D02*
X226319Y657034D01*
G01X226322Y657020D02*
X226320Y657026D01*
G01X226326Y657013D02*
X226322Y657020D01*
G01X226330Y657007D02*
X226326Y657013D01*
G01X226337Y657003D02*
X226330Y657007D01*
G01X226343Y657000D02*
X226337Y657003D01*
G01X226351Y656998D02*
X226343Y657000D01*
G01X226358Y656997D02*
X226351Y656998D01*
G01X226320Y660176D02*
X226319Y660183D01*
G01X226322Y660169D02*
X226320Y660176D01*
G01X226326Y660163D02*
X226322Y660169D01*
G01X226330Y660157D02*
X226326Y660163D01*
G01X226337Y660152D02*
X226330Y660157D01*
G01X226343Y660149D02*
X226337Y660152D01*
G01X226351Y660147D02*
X226343Y660149D01*
G01X226358Y660146D02*
X226351Y660147D01*
G01X226320Y663326D02*
X226319Y663333D01*
G01X226322Y663319D02*
X226320Y663326D01*
G01X226326Y663313D02*
X226322Y663319D01*
G01X226330Y663307D02*
X226326Y663313D01*
G01X226337Y663302D02*
X226330Y663307D01*
G01X226343Y663299D02*
X226337Y663302D01*
G01X226351Y663297D02*
X226343Y663299D01*
G01X226358Y663296D02*
X226351Y663297D01*
G01X226320Y666475D02*
X226319Y666483D01*
G01X226322Y666469D02*
X226320Y666475D01*
G01X226326Y666462D02*
X226322Y666469D01*
G01X226330Y666456D02*
X226326Y666462D01*
G01X226337Y666452D02*
X226330Y666456D01*
G01X226343Y666448D02*
X226337Y666452D01*
G01X226351Y666446D02*
X226343Y666448D01*
G01X226358Y666446D02*
X226351D01*
G01X226320Y669625D02*
X226319Y669632D01*
G01X226322Y669618D02*
X226320Y669625D01*
G01X226326Y669612D02*
X226322Y669618D01*
G01X226330Y669606D02*
X226326Y669612D01*
G01X226337Y669601D02*
X226330Y669606D01*
G01X226343Y669598D02*
X226337Y669601D01*
G01X226351Y669596D02*
X226343Y669598D01*
G01X226358Y669595D02*
X226351Y669596D01*
G01X227273Y651889D02*
X227282Y651884D01*
G01X227262Y651890D02*
X227273Y651889D01*
G01Y655038D02*
X227282Y655034D01*
G01X227262Y655039D02*
X227273Y655038D01*
G01Y658188D02*
X227282Y658183D01*
G01X227262Y658189D02*
X227273Y658188D01*
G01Y661337D02*
X227282Y661333D01*
G01X227262Y661339D02*
X227273Y661337D01*
G01Y664487D02*
X227282Y664483D01*
G01X227262Y664488D02*
X227273Y664487D01*
G01Y667637D02*
X227282Y667632D01*
G01X227262Y667638D02*
X227273Y667637D01*
G01Y670786D02*
X227282Y670782D01*
G01X227262Y670787D02*
X227273Y670786D01*
G01X227281Y650701D02*
X227284Y650703D01*
G01X227278Y650700D02*
X227281Y650701D01*
G01X227274Y650699D02*
X227278Y650700D01*
G01X227271Y650698D02*
X227274Y650699D01*
G01X227267Y650698D02*
X227271D01*
G01X227264D02*
X227267D01*
G01X226341Y651898D02*
X226338Y651896D01*
G01X226344Y651899D02*
X226341Y651898D01*
G01X226348Y651900D02*
X226344Y651899D01*
G01X226351Y651900D02*
X226348D01*
G01X226355Y651901D02*
X226351Y651900D01*
G01X226358Y651901D02*
X226355D01*
G01X227281Y653851D02*
X227284Y653852D01*
G01X227278Y653850D02*
X227281Y653851D01*
G01X227274Y653848D02*
X227278Y653850D01*
G01X227271Y653848D02*
X227274D01*
G01X227267Y653847D02*
X227271Y653848D01*
G01X227264Y653847D02*
X227267D01*
G01X226341Y655047D02*
X226338Y655046D01*
G01X226344Y655048D02*
X226341Y655047D01*
G01X226348Y655050D02*
X226344Y655048D01*
G01X226351Y655050D02*
X226348D01*
G01X226355Y655051D02*
X226351Y655050D01*
G01X226358Y655051D02*
X226355D01*
G01X227281Y657000D02*
X227284Y657002D01*
G01X227278Y656999D02*
X227281Y657000D01*
G01X227274Y656998D02*
X227278Y656999D01*
G01X227271Y656997D02*
X227274Y656998D01*
G01X227267Y656997D02*
X227271D01*
G01X227264D02*
X227267D01*
G01X226341Y658197D02*
X226338Y658195D01*
G01X226344Y658198D02*
X226341Y658197D01*
G01X226348Y658199D02*
X226344Y658198D01*
G01X226351Y658200D02*
X226348Y658199D01*
G01X226355Y658200D02*
X226351D01*
G01X226358D02*
X226355D01*
G01X227281Y660150D02*
X227284Y660152D01*
G01X227278Y660149D02*
X227281Y660150D01*
G01X227274Y660148D02*
X227278Y660149D01*
G01X227271Y660147D02*
X227274Y660148D01*
G01X227267Y660146D02*
X227271Y660147D01*
G01X227264Y660146D02*
X227267D01*
G01X226341Y661346D02*
X226338Y661345D01*
G01X226344Y661348D02*
X226341Y661346D01*
G01X226348Y661349D02*
X226344Y661348D01*
G01X226351Y661349D02*
X226348D01*
G01X226355Y661350D02*
X226351Y661349D01*
G01X226358Y661350D02*
X226355D01*
G01X227281Y663300D02*
X227284Y663301D01*
G01X227278Y663298D02*
X227281Y663300D01*
G01X227274Y663297D02*
X227278Y663298D01*
G01X227271Y663296D02*
X227274Y663297D01*
G01X227267Y663296D02*
X227271D01*
G01X227264D02*
X227267D01*
G01X226341Y664496D02*
X226338Y664494D01*
G01X226344Y664497D02*
X226341Y664496D01*
G01X226348Y664498D02*
X226344Y664497D01*
G01X226351Y664499D02*
X226348Y664498D01*
G01X226355Y664500D02*
X226351Y664499D01*
G01X226358Y664500D02*
X226355D01*
G01X226341Y667646D02*
X226338Y667644D01*
G01X226344Y667647D02*
X226341Y667646D01*
G01X226348Y667648D02*
X226344Y667647D01*
G01X226351Y667648D02*
X226348D01*
G01X226355Y667649D02*
X226351Y667648D01*
G01X226358Y667649D02*
X226355D01*
G01X227281Y669599D02*
X227284Y669600D01*
G01X227278Y669598D02*
X227281Y669599D01*
G01X227274Y669596D02*
X227278Y669598D01*
G01X227271Y669596D02*
X227274D01*
G01X227267Y669595D02*
X227271Y669596D01*
G01X227264Y669595D02*
X227267D01*
G01X226341Y670795D02*
X226338Y670794D01*
G01X226344Y670796D02*
X226341Y670795D01*
G01X226348Y670798D02*
X226344Y670796D01*
G01X226351Y670798D02*
X226348D01*
G01X226355Y670799D02*
X226351Y670798D01*
G01X226358Y670799D02*
X226355D01*
G01X225572Y653898D02*
X225138D01*
G01X225945D02*
X225572D01*
G01Y660197D02*
X225138D01*
G01X225945D02*
X225572D01*
G01Y663346D02*
X225138D01*
G01X225945D02*
X225572D01*
G01X227302Y666475D02*
X227303Y666483D01*
G01X227300Y666469D02*
X227302Y666475D01*
G01X227296Y666462D02*
X227300Y666469D01*
G01X227292Y666456D02*
X227296Y666462D01*
G01X227285Y666452D02*
X227292Y666456D01*
G01X227279Y666448D02*
X227285Y666452D01*
G01X227271Y666446D02*
X227279Y666448D01*
G01X227264Y666446D02*
X227271D01*
G01X226322Y651870D02*
X226317Y651850D01*
G01X226336Y651885D02*
X226322Y651870D01*
G01X226356Y651890D02*
X226336Y651885D01*
G01X226322Y655020D02*
X226317Y655000D01*
G01X226336Y655034D02*
X226322Y655020D01*
G01X226356Y655039D02*
X226336Y655034D01*
G01X226322Y658169D02*
X226317Y658150D01*
G01X226336Y658184D02*
X226322Y658169D01*
G01X226356Y658189D02*
X226336Y658184D01*
G01X226322Y661319D02*
X226317Y661299D01*
G01X226336Y661333D02*
X226322Y661319D01*
G01X226356Y661339D02*
X226336Y661333D01*
G01X226322Y664469D02*
X226317Y664449D01*
G01X226336Y664483D02*
X226322Y664469D01*
G01X226356Y664488D02*
X226336Y664483D01*
G01X226322Y667618D02*
X226317Y667598D01*
G01X226336Y667633D02*
X226322Y667618D01*
G01X226356Y667638D02*
X226336Y667633D01*
G01X226322Y670768D02*
X226317Y670748D01*
G01X226336Y670782D02*
X226322Y670768D01*
G01X226356Y670787D02*
X226336Y670782D01*
G01X227296Y650728D02*
X227302Y650748D01*
G01X227282Y650714D02*
X227296Y650728D01*
G01X227262Y650709D02*
X227282Y650714D01*
G01X227296Y653878D02*
X227302Y653898D01*
G01X227282Y653864D02*
X227296Y653878D01*
G01X227262Y653858D02*
X227282Y653864D01*
G01X227296Y657028D02*
X227302Y657047D01*
G01X227282Y657013D02*
X227296Y657028D01*
G01X227262Y657008D02*
X227282Y657013D01*
G01X227296Y660177D02*
X227302Y660197D01*
G01X227282Y660163D02*
X227296Y660177D01*
G01X227262Y660157D02*
X227282Y660163D01*
G01X227296Y663327D02*
X227302Y663346D01*
G01X227282Y663313D02*
X227296Y663327D01*
G01X227262Y663307D02*
X227282Y663313D01*
G01X227296Y666476D02*
X227302Y666496D01*
G01X227282Y666462D02*
X227296Y666476D01*
G01X227262Y666457D02*
X227282Y666462D01*
G01X227296Y669626D02*
X227302Y669646D01*
G01X227282Y669612D02*
X227296Y669626D01*
G01X227262Y669606D02*
X227282Y669612D01*
G01X226317Y660193D02*
X226206Y660197D01*
G01X226317Y653894D02*
X226206Y653898D01*
G01X226317Y663343D02*
X226206Y663346D01*
G01X240728Y694429D02*
X239744D01*
G01X239746Y693937D02*
X245079D01*
G01Y693898D02*
X240731D01*
G01X245079Y692559D02*
X239746D01*
G01X239744Y692067D02*
X240728D01*
G01Y689429D02*
X239744D01*
G01X239746Y688937D02*
X245079D01*
G01Y688898D02*
X240731D01*
G01X245079Y687559D02*
X239746D01*
G01X239744Y687067D02*
X240728D01*
G01Y684429D02*
X239744D01*
G01X239746Y683937D02*
X245079D01*
G01Y683898D02*
X240731D01*
G01X245079Y682559D02*
X239746D01*
G01X239744Y682067D02*
X240728D01*
G01Y679429D02*
X239744D01*
G01X239746Y678937D02*
X245079D01*
G01Y678898D02*
X240731D01*
G01X245079Y677559D02*
X239746D01*
G01X239744Y677067D02*
X240728D01*
G01Y674429D02*
X239744D01*
G01X239746Y673937D02*
X245079D01*
G01Y673898D02*
X240731D01*
G01X227756Y672953D02*
X224409D01*
G01X245079Y672559D02*
X239746D01*
G01X239744Y672067D02*
X240728D01*
G01X237402Y671791D02*
X241339D01*
G01X227264Y670984D02*
X226358D01*
G01X227303Y670945D02*
X226319D01*
G01X227262Y670787D02*
X221378D01*
G01Y670748D02*
X227302D01*
G01X236220Y670610D02*
X240157D01*
G01X227302Y669646D02*
X221378D01*
G01X227262Y669606D02*
X221378D01*
G01X226319Y669449D02*
X227303D01*
G01X226358Y669409D02*
X227264D01*
G01Y667835D02*
X226358D01*
G01X227303Y667795D02*
X226319D01*
G01X227262Y667638D02*
X221378D01*
G01Y667598D02*
X227302D01*
G01Y666496D02*
X221378D01*
G01X227262Y666457D02*
X221378D01*
G01X226319Y666299D02*
X227303D01*
G01X226358Y666260D02*
X227264D01*
G01Y664685D02*
X226358D01*
G01X227303Y664646D02*
X226319D01*
G01X227262Y664488D02*
X221378D01*
G01Y664449D02*
X227302D01*
G01Y663346D02*
X221378D01*
G01X227262Y663307D02*
X221378D01*
G01X226319Y663150D02*
X227303D01*
G01X226358Y663110D02*
X227264D01*
G01Y661535D02*
X226358D01*
G01X227303Y661496D02*
X226319D01*
G01X227262Y661339D02*
X221378D01*
G01Y661299D02*
X227302D01*
G01Y660197D02*
X221378D01*
G01X227262Y660157D02*
X221378D01*
G01X226319Y660000D02*
X227303D01*
G01X226358Y659961D02*
X227264D01*
G01Y658386D02*
X226358D01*
G01X227303Y658346D02*
X226319D01*
G01X227262Y658189D02*
X221378D01*
G01Y658150D02*
X227302D01*
G01Y657047D02*
X221378D01*
G01X227262Y657008D02*
X221378D01*
G01X226319Y656850D02*
X227303D01*
G01X226358Y656811D02*
X227264D01*
G01Y655236D02*
X226358D01*
G01X227303Y655197D02*
X226319D01*
G01X227262Y655039D02*
X221378D01*
G01Y655000D02*
X227302D01*
G01Y653898D02*
X221378D01*
G01X227262Y653858D02*
X221378D01*
G01X226319Y653701D02*
X227303D01*
G01X226358Y653661D02*
X227264D01*
G01Y652087D02*
X226358D01*
G01X227303Y652047D02*
X226319D01*
G01X227262Y651890D02*
X221378D01*
G01Y651850D02*
X227302D01*
G01X240157Y650886D02*
X236220D01*
G01X227302Y650748D02*
X221378D01*
G01X227262Y650709D02*
X221378D01*
G01X226319Y650551D02*
X227303D01*
G01X226358Y650512D02*
X227264D01*
G01X241339Y649705D02*
X237402D01*
G01X240728Y649429D02*
X239744D01*
G01X239746Y648937D02*
X245079D01*
G01Y648898D02*
X240731D01*
G01X227756Y648543D02*
X224409D01*
G01X239744Y694133D02*
X240699Y694134D01*
G01X240728Y692363D02*
X239744Y692362D01*
G01Y689133D02*
X240699Y689134D01*
G01X240728Y687363D02*
X239744Y687362D01*
G01Y684133D02*
X240699Y684134D01*
G01X240728Y682363D02*
X239744Y682362D01*
G01Y679133D02*
X240699Y679134D01*
G01X240728Y677363D02*
X239744Y677362D01*
G01Y674133D02*
X240699Y674134D01*
G01X240728Y672363D02*
X239744Y672362D01*
G01Y649133D02*
X240699Y649134D01*
G01X226206Y669646D02*
X226317Y669637D01*
G01X240157Y670610D02*
X241339Y671791D01*
G01X236220Y670610D02*
X237402Y671791D01*
G01X240157Y650886D02*
X241339Y649705D01*
G01X236220Y650886D02*
X237402Y649705D01*
G01X227262Y666457D02*
X227266Y666446D01*
G01X227303Y651853D02*
Y651864D01*
G01Y655002D02*
Y655013D01*
G01Y658152D02*
Y658163D01*
G01Y661302D02*
Y661313D01*
G01Y664451D02*
Y664462D01*
G01Y667601D02*
Y667612D01*
G01Y670750D02*
Y670761D01*
G01X240728Y648911D02*
X240729Y648920D01*
G01X240728Y673911D02*
X240729Y673920D01*
G01X240728Y678911D02*
X240729Y678920D01*
G01X240728Y683911D02*
X240729Y683920D01*
G01X240728Y688911D02*
X240729Y688920D01*
G01X240728Y693911D02*
X240729Y693920D01*
G01X245079Y692559D02*
Y693937D01*
G01Y687559D02*
Y688937D01*
G01Y682559D02*
Y683937D01*
G01Y677559D02*
Y678937D01*
G01Y672559D02*
Y673937D01*
G01X241909D02*
Y672559D01*
G01Y678937D02*
Y677559D01*
G01Y683937D02*
Y682559D01*
G01Y688937D02*
Y687559D01*
G01Y693937D02*
Y692559D01*
G01X241339Y671791D02*
Y649705D01*
G01X240728Y692067D02*
Y694429D01*
G01Y687067D02*
Y689429D01*
G01Y682067D02*
Y684429D01*
G01Y677067D02*
Y679429D01*
G01Y672067D02*
Y674429D01*
G01X240157Y670610D02*
Y650886D01*
G01X239744Y674429D02*
Y672067D01*
G01Y679429D02*
Y677067D01*
G01Y684429D02*
Y682067D01*
G01Y689429D02*
Y687067D01*
G01Y694429D02*
Y692067D01*
G01X237402Y748248D02*
Y671791D01*
G01X236220Y747067D02*
Y670610D01*
G01X227756Y751988D02*
Y672953D01*
G01X227303Y669449D02*
Y670945D01*
G01Y666299D02*
Y667795D01*
G01Y663150D02*
Y664646D01*
G01Y660000D02*
Y661496D01*
G01Y656850D02*
Y658346D01*
G01Y653701D02*
Y655197D01*
G01Y650551D02*
Y652047D01*
G01X227264Y650698D02*
Y650551D01*
G01Y652048D02*
Y651901D01*
G01Y656997D02*
Y656850D01*
G01Y653847D02*
Y653700D01*
G01Y655197D02*
Y655051D01*
G01Y660146D02*
Y660000D01*
G01Y661496D02*
Y661350D01*
G01Y658347D02*
Y658200D01*
G01Y666446D02*
Y666299D01*
G01Y663296D02*
Y663149D01*
G01Y664646D02*
Y664500D01*
G01Y669595D02*
Y669448D01*
G01Y670945D02*
Y670799D01*
G01Y667796D02*
Y667649D01*
G01X226358Y669448D02*
Y669595D01*
G01Y670799D02*
Y670946D01*
G01Y667649D02*
Y667796D01*
G01Y666298D02*
Y666446D01*
G01Y663149D02*
Y663296D01*
G01Y664500D02*
Y664646D01*
G01Y659999D02*
Y660146D01*
G01Y661350D02*
Y661497D01*
G01Y658200D02*
Y658347D01*
G01Y656850D02*
Y656997D01*
G01Y653700D02*
Y653847D01*
G01Y655051D02*
Y655198D01*
G01Y650550D02*
Y650698D01*
G01Y651901D02*
Y652048D01*
G01X226319Y652047D02*
Y650551D01*
G01Y655197D02*
Y653701D01*
G01Y661496D02*
Y660000D01*
G01Y658346D02*
Y656850D01*
G01Y664646D02*
Y663150D01*
G01Y670945D02*
Y669449D01*
G01Y667795D02*
Y666299D01*
G01X225138Y651890D02*
Y650709D01*
G01Y658189D02*
Y657008D01*
G01Y655039D02*
Y653858D01*
G01Y661339D02*
Y660157D01*
G01Y667638D02*
Y666457D01*
G01Y664488D02*
Y663307D01*
G01Y670787D02*
Y669606D01*
G01X224803Y672953D02*
Y648543D01*
G01X224409D02*
Y672953D01*
G01X221378Y669606D02*
Y670787D01*
G01Y666457D02*
Y667638D01*
G01Y663307D02*
Y664488D01*
G01Y660157D02*
Y661339D01*
G01Y657008D02*
Y658189D01*
G01Y653858D02*
Y655039D01*
G01Y650709D02*
Y651890D01*
G01X227303Y669632D02*
Y669643D01*
G01Y666483D02*
Y666494D01*
G01Y663333D02*
Y663344D01*
G01Y660183D02*
Y660194D01*
G01Y657034D02*
Y657045D01*
G01Y653884D02*
Y653895D01*
G01Y650735D02*
Y650746D01*
G01X240695Y699035D02*
X240699Y699134D01*
G01X240690Y698963D02*
X240695Y699035D01*
G01X240692Y698937D02*
X240690Y698963D01*
G01X240695Y704035D02*
X240699Y704134D01*
G01X240690Y703963D02*
X240695Y704035D01*
G01X240692Y703937D02*
X240690Y703963D01*
G01X240695Y709035D02*
X240699Y709134D01*
G01X240690Y708963D02*
X240695Y709035D01*
G01X240692Y708937D02*
X240690Y708963D01*
G01X240695Y714035D02*
X240699Y714134D01*
G01X240690Y713963D02*
X240695Y714035D01*
G01X240692Y713937D02*
X240690Y713963D01*
G01X240695Y719035D02*
X240699Y719134D01*
G01X240690Y718963D02*
X240695Y719035D01*
G01X240692Y718937D02*
X240690Y718963D01*
G01X240695Y724035D02*
X240699Y724134D01*
G01X240690Y723963D02*
X240695Y724035D01*
G01X240692Y723937D02*
X240690Y723963D01*
G01X240695Y729035D02*
X240699Y729134D01*
G01X240690Y728963D02*
X240695Y729035D01*
G01X240692Y728937D02*
X240690Y728963D01*
G01X240695Y734035D02*
X240699Y734134D01*
G01X240690Y733963D02*
X240695Y734035D01*
G01X240692Y733937D02*
X240690Y733963D01*
G01X240695Y739035D02*
X240699Y739134D01*
G01X240690Y738963D02*
X240695Y739035D01*
G01X240692Y738937D02*
X240690Y738963D01*
G01X240695Y744035D02*
X240699Y744134D01*
G01X240690Y743963D02*
X240695Y744035D01*
G01X240692Y743937D02*
X240690Y743963D01*
G01X239745Y742557D02*
X239746Y742559D01*
G01X239744Y742552D02*
X239745Y742557D01*
G01X239744Y742543D02*
Y742552D01*
G01X239745Y737557D02*
X239746Y737559D01*
G01X239744Y737552D02*
X239745Y737557D01*
G01X239744Y737543D02*
Y737552D01*
G01X239745Y732557D02*
X239746Y732559D01*
G01X239744Y732552D02*
X239745Y732557D01*
G01X239744Y732543D02*
Y732552D01*
G01X239745Y727557D02*
X239746Y727559D01*
G01X239744Y727552D02*
X239745Y727557D01*
G01X239744Y727543D02*
Y727552D01*
G01X239745Y722557D02*
X239746Y722559D01*
G01X239744Y722552D02*
X239745Y722557D01*
G01X239744Y722543D02*
Y722552D01*
G01X239745Y717557D02*
X239746Y717559D01*
G01X239744Y717552D02*
X239745Y717557D01*
G01X239744Y717543D02*
Y717552D01*
G01X239745Y712557D02*
X239746Y712559D01*
G01X239744Y712552D02*
X239745Y712557D01*
G01X239744Y712543D02*
Y712552D01*
G01X239745Y707557D02*
X239746Y707559D01*
G01X239744Y707552D02*
X239745Y707557D01*
G01X239744Y707543D02*
Y707552D01*
G01X239745Y702557D02*
X239746Y702559D01*
G01X239744Y702552D02*
X239745Y702557D01*
G01X239744Y702543D02*
Y702552D01*
G01X239745Y697557D02*
X239746Y697559D01*
G01X239744Y697552D02*
X239745Y697557D01*
G01X239744Y697543D02*
Y697552D01*
G01X240711Y698932D02*
X240692Y698937D01*
G01X240726Y698918D02*
X240711Y698932D01*
G01X240731Y698898D02*
X240726Y698918D01*
G01X240711Y703932D02*
X240692Y703937D01*
G01X240726Y703918D02*
X240711Y703932D01*
G01X240731Y703898D02*
X240726Y703918D01*
G01X240711Y708932D02*
X240692Y708937D01*
G01X240726Y708918D02*
X240711Y708932D01*
G01X240731Y708898D02*
X240726Y708918D01*
G01X240711Y713932D02*
X240692Y713937D01*
G01X240726Y713918D02*
X240711Y713932D01*
G01X240731Y713898D02*
X240726Y713918D01*
G01X240711Y718932D02*
X240692Y718937D01*
G01X240726Y718918D02*
X240711Y718932D01*
G01X240731Y718898D02*
X240726Y718918D01*
G01X240711Y723932D02*
X240692Y723937D01*
G01X240726Y723918D02*
X240711Y723932D01*
G01X240731Y723898D02*
X240726Y723918D01*
G01X240711Y728932D02*
X240692Y728937D01*
G01X240726Y728918D02*
X240711Y728932D01*
G01X240731Y728898D02*
X240726Y728918D01*
G01X240711Y733932D02*
X240692Y733937D01*
G01X240726Y733918D02*
X240711Y733932D01*
G01X240731Y733898D02*
X240726Y733918D01*
G01X240711Y738932D02*
X240692Y738937D01*
G01X240726Y738918D02*
X240711Y738932D01*
G01X240731Y738898D02*
X240726Y738918D01*
G01X240711Y743932D02*
X240692Y743937D01*
G01X240726Y743918D02*
X240711Y743932D01*
G01X240731Y743898D02*
X240726Y743918D01*
G01X240729Y698904D02*
X240728Y698911D01*
G01X240730Y698900D02*
X240729Y698904D01*
G01X240731Y698898D02*
X240730Y698900D01*
G01X240729Y703904D02*
X240728Y703911D01*
G01X240730Y703900D02*
X240729Y703904D01*
G01X240731Y703898D02*
X240730Y703900D01*
G01X240729Y708904D02*
X240728Y708911D01*
G01X240730Y708900D02*
X240729Y708904D01*
G01X240731Y708898D02*
X240730Y708900D01*
G01X240729Y713904D02*
X240728Y713911D01*
G01X240730Y713900D02*
X240729Y713904D01*
G01X240731Y713898D02*
X240730Y713900D01*
G01X239744Y698944D02*
Y698954D01*
G01X239745Y698939D02*
X239744Y698944D01*
G01X239746Y698937D02*
X239745Y698939D01*
G01X239744Y703944D02*
Y703954D01*
G01X239745Y703939D02*
X239744Y703944D01*
G01X239746Y703937D02*
X239745Y703939D01*
G01X239744Y708944D02*
Y708954D01*
G01X239745Y708939D02*
X239744Y708944D01*
G01X239746Y708937D02*
X239745Y708939D01*
G01X239744Y713944D02*
Y713954D01*
G01X239745Y713939D02*
X239744Y713944D01*
G01X239746Y713937D02*
X239745Y713939D01*
G01X239744Y718944D02*
Y718954D01*
G01X239745Y718939D02*
X239744Y718944D01*
G01X239746Y718937D02*
X239745Y718939D01*
G01X239744Y723944D02*
Y723954D01*
G01X239745Y723939D02*
X239744Y723944D01*
G01X239746Y723937D02*
X239745Y723939D01*
G01X239744Y728944D02*
Y728954D01*
G01X239745Y728939D02*
X239744Y728944D01*
G01X239746Y728937D02*
X239745Y728939D01*
G01X239744Y733944D02*
Y733954D01*
G01X239745Y733939D02*
X239744Y733944D01*
G01X239746Y733937D02*
X239745Y733939D01*
G01X239744Y738944D02*
Y738954D01*
G01X239745Y738939D02*
X239744Y738944D01*
G01X239746Y738937D02*
X239745Y738939D01*
G01X239744Y743944D02*
Y743954D01*
G01X239745Y743939D02*
X239744Y743944D01*
G01X239746Y743937D02*
X239745Y743939D01*
G01X240720Y699081D02*
X240728Y699055D01*
G01X240711Y699107D02*
X240720Y699081D01*
G01X240699Y699134D02*
X240711Y699107D01*
G01X240720Y704081D02*
X240728Y704055D01*
G01X240711Y704107D02*
X240720Y704081D01*
G01X240699Y704134D02*
X240711Y704107D01*
G01X240720Y709081D02*
X240728Y709055D01*
G01X240711Y709107D02*
X240720Y709081D01*
G01X240699Y709134D02*
X240711Y709107D01*
G01X240720Y714081D02*
X240728Y714055D01*
G01X240711Y714107D02*
X240720Y714081D01*
G01X240699Y714134D02*
X240711Y714107D01*
G01X240720Y719081D02*
X240728Y719055D01*
G01X240711Y719107D02*
X240720Y719081D01*
G01X240699Y719134D02*
X240711Y719107D01*
G01X240720Y724081D02*
X240728Y724055D01*
G01X240711Y724107D02*
X240720Y724081D01*
G01X240699Y724134D02*
X240711Y724107D01*
G01X240720Y729081D02*
X240728Y729055D01*
G01X240711Y729107D02*
X240720Y729081D01*
G01X240699Y729134D02*
X240711Y729107D01*
G01X240720Y734081D02*
X240728Y734055D01*
G01X240711Y734107D02*
X240720Y734081D01*
G01X240699Y734134D02*
X240711Y734107D01*
G01X240720Y739081D02*
X240728Y739055D01*
G01X240711Y739107D02*
X240720Y739081D01*
G01X240699Y739134D02*
X240711Y739107D01*
G01X240720Y744081D02*
X240728Y744055D01*
G01X240711Y744107D02*
X240720Y744081D01*
G01X240699Y744134D02*
X240711Y744107D01*
G01X240729Y742552D02*
X240728Y742543D01*
G01X240730Y742557D02*
X240729Y742552D01*
G01X240731Y742559D02*
X240730Y742557D01*
G01X240729Y737552D02*
X240728Y737543D01*
G01X240730Y737557D02*
X240729Y737552D01*
G01X240731Y737559D02*
X240730Y737557D01*
G01X240729Y732552D02*
X240728Y732543D01*
G01X240730Y732557D02*
X240729Y732552D01*
G01X240731Y732559D02*
X240730Y732557D01*
G01X240729Y727552D02*
X240728Y727543D01*
G01X240730Y727557D02*
X240729Y727552D01*
G01X240731Y727559D02*
X240730Y727557D01*
G01X240729Y722552D02*
X240728Y722543D01*
G01X240730Y722557D02*
X240729Y722552D01*
G01X240731Y722559D02*
X240730Y722557D01*
G01X240729Y718904D02*
X240728Y718911D01*
G01X240730Y718900D02*
X240729Y718904D01*
G01X240731Y718898D02*
X240730Y718900D01*
G01X240729Y723904D02*
X240728Y723911D01*
G01X240730Y723900D02*
X240729Y723904D01*
G01X240731Y723898D02*
X240730Y723900D01*
G01X240729Y728904D02*
X240728Y728911D01*
G01X240730Y728900D02*
X240729Y728904D01*
G01X240731Y728898D02*
X240730Y728900D01*
G01X240729Y733904D02*
X240728Y733911D01*
G01X240730Y733900D02*
X240729Y733904D01*
G01X240731Y733898D02*
X240730Y733900D01*
G01X240729Y738904D02*
X240728Y738911D01*
G01X240730Y738900D02*
X240729Y738904D01*
G01X240731Y738898D02*
X240730Y738900D01*
G01X240729Y743904D02*
X240728Y743911D01*
G01X240730Y743900D02*
X240729Y743904D01*
G01X240731Y743898D02*
X240730Y743900D01*
G01X240729Y717552D02*
X240728Y717543D01*
G01X240730Y717557D02*
X240729Y717552D01*
G01X240731Y717559D02*
X240730Y717557D01*
G01X240729Y712552D02*
X240728Y712543D01*
G01X240730Y712557D02*
X240729Y712552D01*
G01X240731Y712559D02*
X240730Y712557D01*
G01X240729Y707552D02*
X240728Y707543D01*
G01X240730Y707557D02*
X240729Y707552D01*
G01X240731Y707559D02*
X240730Y707557D01*
G01X240729Y702552D02*
X240728Y702543D01*
G01X240730Y702557D02*
X240729Y702552D01*
G01X240731Y702559D02*
X240730Y702557D01*
G01X240729Y697552D02*
X240728Y697543D01*
G01X240730Y697557D02*
X240729Y697552D01*
G01X240731Y697559D02*
X240730Y697557D01*
G01X240716Y698929D02*
X240727Y698913D01*
G01X240691Y698937D02*
X240716Y698929D01*
G01Y703929D02*
X240727Y703913D01*
G01X240691Y703937D02*
X240716Y703929D01*
G01Y708929D02*
X240727Y708913D01*
G01X240691Y708937D02*
X240716Y708929D01*
G01Y713929D02*
X240727Y713913D01*
G01X240691Y713937D02*
X240716Y713929D01*
G01Y718929D02*
X240727Y718913D01*
G01X240691Y718937D02*
X240716Y718929D01*
G01Y723929D02*
X240727Y723913D01*
G01X240691Y723937D02*
X240716Y723929D01*
G01Y728929D02*
X240727Y728913D01*
G01X240691Y728937D02*
X240716Y728929D01*
G01Y733929D02*
X240727Y733913D01*
G01X240691Y733937D02*
X240716Y733929D01*
G01Y738929D02*
X240727Y738913D01*
G01X240691Y738937D02*
X240716Y738929D01*
G01Y743929D02*
X240727Y743913D01*
G01X240691Y743937D02*
X240716Y743929D01*
G01X240728Y744429D02*
X239744D01*
G01X239746Y743937D02*
X245079D01*
G01Y743898D02*
X240731D01*
G01X245079Y742559D02*
X239746D01*
G01X239744Y742067D02*
X240728D01*
G01Y739429D02*
X239744D01*
G01X239746Y738937D02*
X245079D01*
G01Y738898D02*
X240731D01*
G01X245079Y737559D02*
X239746D01*
G01X239744Y737067D02*
X240728D01*
G01Y734429D02*
X239744D01*
G01X239746Y733937D02*
X245079D01*
G01Y733898D02*
X240731D01*
G01X245079Y732559D02*
X239746D01*
G01X239744Y732067D02*
X240728D01*
G01Y729429D02*
X239744D01*
G01X239746Y728937D02*
X245079D01*
G01Y728898D02*
X240731D01*
G01X245079Y727559D02*
X239746D01*
G01X239744Y727067D02*
X240728D01*
G01Y724429D02*
X239744D01*
G01X239746Y723937D02*
X245079D01*
G01Y723898D02*
X240731D01*
G01X245079Y722559D02*
X239746D01*
G01X239744Y722067D02*
X240728D01*
G01Y719429D02*
X239744D01*
G01X239746Y718937D02*
X245079D01*
G01Y718898D02*
X240731D01*
G01X245079Y717559D02*
X239746D01*
G01X239744Y717067D02*
X240728D01*
G01Y714429D02*
X239744D01*
G01X239746Y713937D02*
X245079D01*
G01Y713898D02*
X240731D01*
G01X245079Y712559D02*
X239746D01*
G01X239744Y712067D02*
X240728D01*
G01Y709429D02*
X239744D01*
G01X239746Y708937D02*
X245079D01*
G01Y708898D02*
X240731D01*
G01X245079Y707559D02*
X239746D01*
G01X239744Y707067D02*
X240728D01*
G01X239744Y744133D02*
X240699Y744134D01*
G01X240728Y742363D02*
X239744Y742362D01*
G01Y739133D02*
X240699Y739134D01*
G01X240728Y737363D02*
X239744Y737362D01*
G01Y734133D02*
X240699Y734134D01*
G01X240728Y732363D02*
X239744Y732362D01*
G01Y729133D02*
X240699Y729134D01*
G01X240728Y727363D02*
X239744Y727362D01*
G01Y724133D02*
X240699Y724134D01*
G01X240728Y722363D02*
X239744Y722362D01*
G01Y719133D02*
X240699Y719134D01*
G01X240728Y717363D02*
X239744Y717362D01*
G01Y714133D02*
X240699Y714134D01*
G01X240728Y712363D02*
X239744Y712362D01*
G01Y709133D02*
X240699Y709134D01*
G01X240728Y707363D02*
X239744Y707362D01*
G01X240728Y704429D02*
X239744D01*
G01X239746Y703937D02*
X245079D01*
G01Y703898D02*
X240731D01*
G01X245079Y702559D02*
X239746D01*
G01X239744Y702067D02*
X240728D01*
G01Y699429D02*
X239744D01*
G01X239746Y698937D02*
X245079D01*
G01Y698898D02*
X240731D01*
G01X245079Y697559D02*
X239746D01*
G01X239744Y697067D02*
X240728D01*
G01X239744Y704133D02*
X240699Y704134D01*
G01X240728Y702363D02*
X239744Y702362D01*
G01Y699133D02*
X240699Y699134D01*
G01X240728Y697363D02*
X239744Y697362D01*
G01X240728Y698911D02*
X240729Y698920D01*
G01X240728Y703911D02*
X240729Y703920D01*
G01X240728Y708911D02*
X240729Y708920D01*
G01X240728Y713911D02*
X240729Y713920D01*
G01X240728Y718911D02*
X240729Y718920D01*
G01X240728Y723911D02*
X240729Y723920D01*
G01X240728Y728911D02*
X240729Y728920D01*
G01X240728Y733911D02*
X240729Y733920D01*
G01X240728Y738911D02*
X240729Y738920D01*
G01X240728Y743911D02*
X240729Y743920D01*
G01X245079Y742559D02*
Y743937D01*
G01Y737559D02*
Y738937D01*
G01Y732559D02*
Y733937D01*
G01Y727559D02*
Y728937D01*
G01Y722559D02*
Y723937D01*
G01Y717559D02*
Y718937D01*
G01Y712559D02*
Y713937D01*
G01Y707559D02*
Y708937D01*
G01Y702559D02*
Y703937D01*
G01Y697559D02*
Y698937D01*
G01X241909D02*
Y697559D01*
G01Y703937D02*
Y702559D01*
G01Y708937D02*
Y707559D01*
G01Y713937D02*
Y712559D01*
G01Y718937D02*
Y717559D01*
G01Y723937D02*
Y722559D01*
G01Y728937D02*
Y727559D01*
G01Y733937D02*
Y732559D01*
G01Y738937D02*
Y737559D01*
G01Y743937D02*
Y742559D01*
G01X240728Y742067D02*
Y744429D01*
G01Y737067D02*
Y739429D01*
G01Y732067D02*
Y734429D01*
G01Y727067D02*
Y729429D01*
G01Y722067D02*
Y724429D01*
G01Y717067D02*
Y719429D01*
G01Y712067D02*
Y714429D01*
G01Y707067D02*
Y709429D01*
G01Y702067D02*
Y704429D01*
G01Y697067D02*
Y699429D01*
G01X239744D02*
Y697067D01*
G01Y704429D02*
Y702067D01*
G01Y709429D02*
Y707067D01*
G01Y714429D02*
Y712067D01*
G01Y719429D02*
Y717067D01*
G01Y724429D02*
Y722067D01*
G01Y729429D02*
Y727067D01*
G01Y734429D02*
Y732067D01*
G01Y739429D02*
Y737067D01*
G01Y744429D02*
Y742067D01*
G01X239173Y769429D02*
G03X238583Y770020I-591J0D01*
G01X231890D02*
G03X231299Y769429I0J-591D01*
G01X234055Y768248D02*
G03Y766280I0J-984D01*
G01X236417D02*
G03Y768248I0J984D01*
G01X246063Y768839D02*
G03X244094Y770807I-1968J0D01*
G01X226378D02*
G03X224409Y768839I0J-1969D01*
G01X232677Y760335D02*
G03X231496Y759154I0J-1181D01*
G01X238976D02*
G03X237795Y760335I-1181J0D01*
G01X237126Y755059D02*
G03I-1890J0D01*
G01X237598D02*
G03I-2362J0D01*
G01X244094Y770807D02*
X226378D01*
G01X238583Y770020D02*
X231890D01*
G01X236417Y768248D02*
X234055D01*
G01Y766280D02*
X236417D01*
G01X239173Y764902D02*
X231299D01*
G01Y763327D02*
X239173D01*
G01X246063Y760374D02*
X224409D01*
G01X232677Y760335D02*
X237795D01*
G01X234055Y755650D02*
X236417D01*
G01X234055Y753957D02*
X236417D01*
G01X227756Y751988D02*
X242126D01*
G01X227756Y750610D02*
X231496D01*
G01X242126D02*
X238976D01*
G01X227756Y749744D02*
X242717D01*
G01X229528Y748248D02*
X237402D01*
G01X230709Y747067D02*
X236220D01*
G01X246063Y753091D02*
X242717Y749744D01*
G01X236220Y747067D02*
X237402Y748248D01*
G01X229528D02*
X230709Y747067D01*
G01X224409Y753091D02*
X227756Y749744D01*
G01X232752Y751988D02*
X234055Y753957D01*
G01Y755650D02*
X231745Y759879D01*
G01X236417Y753957D02*
X237721Y751988D01*
G01X238728Y759879D02*
X236417Y755650D01*
G01X246063Y753091D02*
Y768839D01*
G01X239173Y763327D02*
Y769429D01*
G01X238976Y759154D02*
Y750610D01*
G01X236417Y755650D02*
Y753957D01*
G01X234055D02*
Y755650D01*
G01X231496Y750610D02*
Y759154D01*
G01X231299Y763327D02*
Y769429D01*
G01X224409Y768839D02*
Y753091D01*
G01X239745Y1080313D02*
X239746Y1080315D01*
G01X239744Y1080308D02*
X239745Y1080313D01*
G01X239744Y1080299D02*
Y1080308D01*
G01X239745Y1075313D02*
X239746Y1075315D01*
G01X239744Y1075308D02*
X239745Y1075313D01*
G01X239744Y1075299D02*
Y1075308D01*
G01X239745Y1070313D02*
X239746Y1070315D01*
G01X239744Y1070308D02*
X239745Y1070313D01*
G01X239744Y1070299D02*
Y1070308D01*
G01X240729Y1080308D02*
X240728Y1080299D01*
G01X240730Y1080313D02*
X240729Y1080308D01*
G01X240731Y1080315D02*
X240730Y1080313D01*
G01X240729Y1075308D02*
X240728Y1075299D01*
G01X240730Y1075313D02*
X240729Y1075308D01*
G01X240731Y1075315D02*
X240730Y1075313D01*
G01X240729Y1070308D02*
X240728Y1070299D01*
G01X240730Y1070313D02*
X240729Y1070308D01*
G01X240731Y1070315D02*
X240730Y1070313D01*
G01X240695Y1071791D02*
X240699Y1071890D01*
G01X240690Y1071719D02*
X240695Y1071791D01*
G01X240692Y1071693D02*
X240690Y1071719D01*
G01X240695Y1076791D02*
X240699Y1076890D01*
G01X240690Y1076719D02*
X240695Y1076791D01*
G01X240692Y1076693D02*
X240690Y1076719D01*
G01X240695Y1081791D02*
X240699Y1081890D01*
G01X240690Y1081719D02*
X240695Y1081791D01*
G01X240692Y1081693D02*
X240690Y1081719D01*
G01X240711Y1071688D02*
X240692Y1071693D01*
G01X240726Y1071674D02*
X240711Y1071688D01*
G01X240731Y1071654D02*
X240726Y1071674D01*
G01X240711Y1076688D02*
X240692Y1076693D01*
G01X240726Y1076674D02*
X240711Y1076688D01*
G01X240731Y1076654D02*
X240726Y1076674D01*
G01X240711Y1081688D02*
X240692Y1081693D01*
G01X240726Y1081674D02*
X240711Y1081688D01*
G01X240731Y1081654D02*
X240726Y1081674D01*
G01X239744Y1071700D02*
Y1071709D01*
G01X239745Y1071695D02*
X239744Y1071700D01*
G01X239746Y1071693D02*
X239745Y1071695D01*
G01X239744Y1076700D02*
Y1076709D01*
G01X239745Y1076695D02*
X239744Y1076700D01*
G01X239746Y1076693D02*
X239745Y1076695D01*
G01X239744Y1081700D02*
Y1081709D01*
G01X239745Y1081695D02*
X239744Y1081700D01*
G01X239746Y1081693D02*
X239745Y1081695D01*
G01X240720Y1071837D02*
X240728Y1071811D01*
G01X240711Y1071863D02*
X240720Y1071837D01*
G01X240699Y1071890D02*
X240711Y1071863D01*
G01X240720Y1076837D02*
X240728Y1076811D01*
G01X240711Y1076863D02*
X240720Y1076837D01*
G01X240699Y1076890D02*
X240711Y1076863D01*
G01X240720Y1081837D02*
X240728Y1081811D01*
G01X240711Y1081863D02*
X240720Y1081837D01*
G01X240699Y1081890D02*
X240711Y1081863D01*
G01X240729Y1071660D02*
X240728Y1071667D01*
G01X240730Y1071656D02*
X240729Y1071660D01*
G01X240731Y1071654D02*
X240730Y1071656D01*
G01X240729Y1076660D02*
X240728Y1076667D01*
G01X240730Y1076656D02*
X240729Y1076660D01*
G01X240731Y1076654D02*
X240730Y1076656D01*
G01X240729Y1081660D02*
X240728Y1081667D01*
G01X240730Y1081656D02*
X240729Y1081660D01*
G01X240731Y1081654D02*
X240730Y1081656D01*
G01X240716Y1071685D02*
X240727Y1071669D01*
G01X240691Y1071693D02*
X240716Y1071685D01*
G01Y1076685D02*
X240727Y1076669D01*
G01X240691Y1076693D02*
X240716Y1076685D01*
G01Y1081685D02*
X240727Y1081669D01*
G01X240691Y1081693D02*
X240716Y1081685D01*
G01X231299Y1044823D02*
G03X231890Y1044232I591J0D01*
G01X238583D02*
G03X239173Y1044823I-1J591D01*
G01X236417Y1046004D02*
G03Y1047972I0J984D01*
G01X234055D02*
G03Y1046004I0J-984D01*
G01X236339Y1059193D02*
G03I-1103J0D01*
G01X237795Y1053917D02*
G03X238976Y1055098I0J1181D01*
G01X231496D02*
G03X232677Y1053917I1181J0D01*
G01X236811Y1059193D02*
G03I-1575J0D01*
G01X224409Y1045413D02*
G03X226378Y1043445I1969J1D01*
G01X244094D02*
G03X246063Y1045413I0J1969D01*
G01X240728Y1082185D02*
X239744D01*
G01X239746Y1081693D02*
X245079D01*
G01Y1081654D02*
X240731D01*
G01X245079Y1080315D02*
X239746D01*
G01X239744Y1079823D02*
X240728D01*
G01Y1077185D02*
X239744D01*
G01X239746Y1076693D02*
X245079D01*
G01Y1076654D02*
X240731D01*
G01X245079Y1075315D02*
X239746D01*
G01X239744Y1074823D02*
X240728D01*
G01Y1072185D02*
X239744D01*
G01X239746Y1071693D02*
X245079D01*
G01Y1071654D02*
X240731D01*
G01X245079Y1070315D02*
X239746D01*
G01X239744Y1069823D02*
X240728D01*
G01X236220Y1067185D02*
X230709D01*
G01X237402Y1066004D02*
X229528D01*
G01X242717Y1064508D02*
X227756D01*
G01X239744Y1081889D02*
X240699Y1081890D01*
G01X240728Y1080119D02*
X239744Y1080118D01*
G01Y1076889D02*
X240699Y1076890D01*
G01X240728Y1075119D02*
X239744Y1075118D01*
G01Y1071889D02*
X240699Y1071890D01*
G01X240728Y1070119D02*
X239744Y1070118D01*
G01X238976Y1063642D02*
X242126D01*
G01X231496D02*
X227756D01*
G01Y1062264D02*
X242126D01*
G01X236417Y1060295D02*
X234055D01*
G01X236417Y1058602D02*
X234055D01*
G01X237795Y1053917D02*
X232677D01*
G01X246063Y1053878D02*
X224409D01*
G01X239173Y1050925D02*
X231299D01*
G01Y1049350D02*
X239173D01*
G01X236417Y1047972D02*
X234055D01*
G01Y1046004D02*
X236417D01*
G01X238583Y1044232D02*
X231890D01*
G01X244094Y1043445D02*
X226378D01*
G01X242717Y1064508D02*
X246063Y1061161D01*
G01X236220Y1067185D02*
X237402Y1066004D01*
G01X236417Y1058602D02*
X238728Y1054373D01*
G01X234055Y1060295D02*
X232752Y1062264D01*
G01X230709Y1067185D02*
X229528Y1066004D01*
G01X227756Y1064508D02*
X224409Y1061161D01*
G01X237721Y1062264D02*
X236417Y1060295D01*
G01X231745Y1054373D02*
X234055Y1058602D01*
G01X240728Y1071667D02*
X240729Y1071676D01*
G01X240728Y1076667D02*
X240729Y1076676D01*
G01X240728Y1081667D02*
X240729Y1081676D01*
G01X246063Y1045413D02*
Y1061161D01*
G01X245079Y1080315D02*
Y1081693D01*
G01Y1075315D02*
Y1076693D01*
G01Y1070315D02*
Y1071693D01*
G01X242717Y1202500D02*
Y1064508D01*
G01X242126Y1204744D02*
Y1062264D01*
G01X241909Y1071693D02*
Y1070315D01*
G01Y1076693D02*
Y1075315D01*
G01Y1081693D02*
Y1080315D01*
G01X240728Y1079823D02*
Y1082185D01*
G01Y1074823D02*
Y1077185D01*
G01Y1069823D02*
Y1072185D01*
G01Y1076667D02*
Y1076811D01*
G01Y1071667D02*
Y1071811D01*
G01Y1081667D02*
Y1081811D01*
G01X239744Y1072185D02*
Y1069823D01*
G01Y1077185D02*
Y1074823D01*
G01Y1082185D02*
Y1079823D01*
G01X239173Y1050925D02*
Y1044823D01*
G01X238976Y1063642D02*
Y1055098D01*
G01X237402Y1102461D02*
Y1066004D01*
G01X236417Y1060295D02*
Y1058602D01*
G01X236220Y1103642D02*
Y1067185D01*
G01X234055Y1058602D02*
Y1060295D01*
G01X231496Y1055098D02*
Y1063642D01*
G01X231299Y1050925D02*
Y1044823D01*
G01X230709Y1067185D02*
Y1199823D01*
G01X229528Y1066004D02*
Y1201004D01*
G01X227756Y1101299D02*
Y1062264D01*
G01X224409Y1061161D02*
Y1045413D01*
G01X226332Y1123535D02*
X226356Y1123543D01*
G01X226320Y1123520D02*
X226332Y1123535D01*
G01X226319Y1123514D02*
X226320Y1123520D01*
G01X226332Y1120385D02*
X226356Y1120394D01*
G01X226320Y1120371D02*
X226332Y1120385D01*
G01X226319Y1120364D02*
X226320Y1120371D01*
G01X226332Y1117236D02*
X226356Y1117244D01*
G01X226320Y1117221D02*
X226332Y1117236D01*
G01X226319Y1117215D02*
X226320Y1117221D01*
G01X226332Y1114086D02*
X226356Y1114094D01*
G01X226320Y1114072D02*
X226332Y1114086D01*
G01X226319Y1114065D02*
X226320Y1114072D01*
G01X226332Y1110937D02*
X226356Y1110945D01*
G01X226320Y1110922D02*
X226332Y1110937D01*
G01X226319Y1110915D02*
X226320Y1110922D01*
G01X226332Y1107787D02*
X226356Y1107795D01*
G01X226320Y1107772D02*
X226332Y1107787D01*
G01X226319Y1107766D02*
X226320Y1107772D01*
G01X226332Y1104637D02*
X226356Y1104646D01*
G01X226320Y1104623D02*
X226332Y1104637D01*
G01X226319Y1104616D02*
X226320Y1104623D01*
G01X227303Y1123510D02*
Y1123517D01*
G01Y1123506D02*
Y1123510D01*
G01X227302Y1123504D02*
X227303Y1123506D01*
G01Y1120361D02*
Y1120368D01*
G01Y1120356D02*
Y1120361D01*
G01X227302Y1120354D02*
X227303Y1120356D01*
G01Y1117211D02*
Y1117218D01*
G01Y1117207D02*
Y1117211D01*
G01X227302Y1117205D02*
X227303Y1117207D01*
G01Y1114061D02*
Y1114069D01*
G01Y1114057D02*
Y1114061D01*
G01X227302Y1114055D02*
X227303Y1114057D01*
G01Y1110912D02*
Y1110919D01*
G01Y1110907D02*
Y1110912D01*
G01X227302Y1110906D02*
X227303Y1110907D01*
G01Y1107762D02*
Y1107769D01*
G01Y1107758D02*
Y1107762D01*
G01X227302Y1107756D02*
X227303Y1107758D01*
G01Y1104613D02*
Y1104620D01*
G01Y1104608D02*
Y1104613D01*
G01X227302Y1104606D02*
X227303Y1104608D01*
G01X226319Y1112947D02*
Y1112939D01*
G01X226318Y1112952D02*
X226319Y1112947D01*
G01X226317Y1112949D02*
X226318Y1112952D01*
G01X226319Y1106648D02*
Y1106640D01*
G01X226318Y1106652D02*
X226319Y1106648D01*
G01X226317Y1106650D02*
X226318Y1106652D01*
G01X227264Y1123548D02*
Y1123555D01*
G01X227263Y1123545D02*
X227264Y1123548D01*
G01X227262Y1123543D02*
X227263Y1123545D01*
G01X227264Y1120399D02*
Y1120405D01*
G01X227263Y1120395D02*
X227264Y1120399D01*
G01X227262Y1120394D02*
X227263Y1120395D01*
G01X227264Y1117249D02*
Y1117256D01*
G01X227263Y1117246D02*
X227264Y1117249D01*
G01X227262Y1117244D02*
X227263Y1117246D01*
G01X227264Y1114100D02*
Y1114106D01*
G01X227263Y1114096D02*
X227264Y1114100D01*
G01X227262Y1114094D02*
X227263Y1114096D01*
G01X227264Y1110950D02*
Y1110956D01*
G01X227263Y1110946D02*
X227264Y1110950D01*
G01X227262Y1110945D02*
X227263Y1110946D01*
G01X227264Y1107800D02*
Y1107807D01*
G01X227263Y1107797D02*
X227264Y1107800D01*
G01X227262Y1107795D02*
X227263Y1107797D01*
G01X227264Y1104651D02*
Y1104657D01*
G01X227263Y1104647D02*
X227264Y1104651D01*
G01X227262Y1104646D02*
X227263Y1104647D01*
G01X226319Y1116096D02*
Y1116089D01*
G01X226318Y1116101D02*
X226319Y1116096D01*
G01X226318Y1116092D02*
Y1116101D01*
G01X226359Y1123728D02*
X226358Y1123740D01*
G01X226356Y1123715D02*
X226359Y1123728D01*
G01X226356Y1123701D02*
Y1123715D01*
G01X226359Y1120578D02*
X226358Y1120591D01*
G01X226356Y1120565D02*
X226359Y1120578D01*
G01X226356Y1120552D02*
Y1120565D01*
G01X226359Y1117429D02*
X226358Y1117441D01*
G01X226356Y1117416D02*
X226359Y1117429D01*
G01X226356Y1117402D02*
Y1117416D01*
G01X226359Y1114279D02*
X226358Y1114291D01*
G01X226356Y1114266D02*
X226359Y1114279D01*
G01X226356Y1114252D02*
Y1114266D01*
G01X226359Y1111130D02*
X226358Y1111142D01*
G01X226356Y1111117D02*
X226359Y1111130D01*
G01X226356Y1111103D02*
Y1111117D01*
G01X226359Y1107980D02*
X226358Y1107992D01*
G01X226356Y1107967D02*
X226359Y1107980D01*
G01X226356Y1107953D02*
Y1107967D01*
G01X226359Y1104830D02*
X226358Y1104843D01*
G01X226356Y1104817D02*
X226359Y1104830D01*
G01X226356Y1104804D02*
Y1104817D01*
G01X239745Y1130313D02*
X239746Y1130315D01*
G01X239744Y1130308D02*
X239745Y1130313D01*
G01X239744Y1130299D02*
Y1130308D01*
G01X239745Y1125313D02*
X239746Y1125315D01*
G01X239744Y1125308D02*
X239745Y1125313D01*
G01X239744Y1125299D02*
Y1125308D01*
G01X239745Y1100313D02*
X239746Y1100315D01*
G01X239744Y1100308D02*
X239745Y1100313D01*
G01X239744Y1100299D02*
Y1100308D01*
G01X239745Y1095313D02*
X239746Y1095315D01*
G01X239744Y1095308D02*
X239745Y1095313D01*
G01X239744Y1095299D02*
Y1095308D01*
G01X239745Y1090313D02*
X239746Y1090315D01*
G01X239744Y1090308D02*
X239745Y1090313D01*
G01X239744Y1090299D02*
Y1090308D01*
G01X239745Y1085313D02*
X239746Y1085315D01*
G01X239744Y1085308D02*
X239745Y1085313D01*
G01X239744Y1085299D02*
Y1085308D01*
G01X226319Y1122396D02*
Y1122388D01*
G01X226318Y1122400D02*
X226319Y1122396D01*
G01X226318Y1122393D02*
Y1122400D01*
G01X226356Y1122191D02*
X226355Y1122204D01*
G01X226359Y1122178D02*
X226356Y1122191D01*
G01X226358Y1122165D02*
X226359Y1122178D01*
G01X226356Y1119041D02*
X226355Y1119055D01*
G01X226359Y1119028D02*
X226356Y1119041D01*
G01X226358Y1119016D02*
X226359Y1119028D01*
G01X226356Y1115892D02*
X226355Y1115905D01*
G01X226359Y1115879D02*
X226356Y1115892D01*
G01X226358Y1115866D02*
X226359Y1115879D01*
G01X226356Y1112742D02*
X226355Y1112756D01*
G01X226359Y1112729D02*
X226356Y1112742D01*
G01X226358Y1112717D02*
X226359Y1112729D01*
G01X226356Y1109593D02*
X226355Y1109606D01*
G01X226359Y1109580D02*
X226356Y1109593D01*
G01X226358Y1109567D02*
X226359Y1109580D01*
G01X226356Y1106443D02*
X226355Y1106456D01*
G01X226359Y1106430D02*
X226356Y1106443D01*
G01X226358Y1106417D02*
X226359Y1106430D01*
G01X226356Y1103293D02*
X226355Y1103307D01*
G01X226359Y1103280D02*
X226356Y1103293D01*
G01X226358Y1103268D02*
X226359Y1103280D01*
G01X227266Y1123715D02*
X227267Y1123701D01*
G01X227263Y1123728D02*
X227266Y1123715D01*
G01X227264Y1123740D02*
X227263Y1123728D01*
G01X227266Y1120565D02*
X227267Y1120552D01*
G01X227263Y1120578D02*
X227266Y1120565D01*
G01X227264Y1120591D02*
X227263Y1120578D01*
G01X227266Y1117415D02*
X227267Y1117402D01*
G01X227263Y1117428D02*
X227266Y1117415D01*
G01X227264Y1117441D02*
X227263Y1117428D01*
G01X227266Y1114266D02*
X227267Y1114252D01*
G01X227263Y1114279D02*
X227266Y1114266D01*
G01X227264Y1114291D02*
X227263Y1114279D01*
G01X227266Y1111116D02*
X227267Y1111103D01*
G01X227263Y1111129D02*
X227266Y1111116D01*
G01X227264Y1111142D02*
X227263Y1111129D01*
G01X227266Y1107967D02*
X227267Y1107953D01*
G01X227263Y1107980D02*
X227266Y1107967D01*
G01X227264Y1107992D02*
X227263Y1107980D01*
G01X227266Y1104817D02*
X227267Y1104804D01*
G01X227263Y1104830D02*
X227266Y1104817D01*
G01X227264Y1104843D02*
X227263Y1104830D01*
G01X226319Y1109797D02*
Y1109790D01*
G01X226318Y1109802D02*
X226319Y1109797D01*
G01X226317Y1109795D02*
X226318Y1109802D01*
G01X226319Y1119246D02*
Y1119239D01*
G01X226318Y1119251D02*
X226319Y1119246D01*
G01X226317Y1119244D02*
X226318Y1119251D01*
G01X227263Y1122178D02*
X227264Y1122165D01*
G01X227266Y1122191D02*
X227263Y1122178D01*
G01X227267Y1122204D02*
X227266Y1122191D01*
G01X227263Y1119028D02*
X227264Y1119016D01*
G01X227266Y1119041D02*
X227263Y1119028D01*
G01X227267Y1119055D02*
X227266Y1119041D01*
G01X227263Y1115879D02*
X227264Y1115866D01*
G01X227266Y1115892D02*
X227263Y1115879D01*
G01X227267Y1115905D02*
X227266Y1115892D01*
G01X227263Y1112729D02*
X227264Y1112717D01*
G01X227266Y1112742D02*
X227263Y1112729D01*
G01X227267Y1112756D02*
X227266Y1112742D01*
G01X227263Y1109580D02*
X227264Y1109567D01*
G01X227266Y1109593D02*
X227263Y1109580D01*
G01X227267Y1109606D02*
X227266Y1109593D01*
G01X227263Y1106430D02*
X227264Y1106417D01*
G01X227266Y1106443D02*
X227263Y1106430D01*
G01X227267Y1106456D02*
X227266Y1106443D01*
G01X227263Y1103280D02*
X227264Y1103268D01*
G01X227266Y1103293D02*
X227263Y1103280D01*
G01X227267Y1103307D02*
X227266Y1103293D01*
G01X226319Y1103498D02*
Y1103491D01*
G01X226318Y1103503D02*
X226319Y1103498D01*
G01X226317Y1103496D02*
X226318Y1103503D01*
G01X240729Y1130308D02*
X240728Y1130299D01*
G01X240730Y1130313D02*
X240729Y1130308D01*
G01X240731Y1130315D02*
X240730Y1130313D01*
G01X240729Y1125308D02*
X240728Y1125299D01*
G01X240730Y1125313D02*
X240729Y1125308D01*
G01X240731Y1125315D02*
X240730Y1125313D01*
G01X240729Y1100308D02*
X240728Y1100299D01*
G01X240730Y1100313D02*
X240729Y1100308D01*
G01X240731Y1100315D02*
X240730Y1100313D01*
G01X240729Y1095308D02*
X240728Y1095299D01*
G01X240730Y1095313D02*
X240729Y1095308D01*
G01X240731Y1095315D02*
X240730Y1095313D01*
G01X240729Y1090308D02*
X240728Y1090299D01*
G01X240730Y1090313D02*
X240729Y1090308D01*
G01X240731Y1090315D02*
X240730Y1090313D01*
G01X240729Y1085308D02*
X240728Y1085299D01*
G01X240730Y1085313D02*
X240729Y1085308D01*
G01X240731Y1085315D02*
X240730Y1085313D01*
G01X226319Y1123510D02*
Y1123518D01*
G01X226318Y1123506D02*
X226319Y1123510D01*
G01X226317Y1123504D02*
X226318Y1123506D01*
G01X226319Y1120361D02*
Y1120368D01*
G01X226318Y1120356D02*
X226319Y1120361D01*
G01X226317Y1120354D02*
X226318Y1120356D01*
G01X226319Y1117211D02*
Y1117219D01*
G01X226318Y1117206D02*
X226319Y1117211D01*
G01X226317Y1117205D02*
X226318Y1117206D01*
G01X226319Y1114061D02*
Y1114069D01*
G01X226318Y1114057D02*
X226319Y1114061D01*
G01X226317Y1114055D02*
X226318Y1114057D01*
G01X226319Y1110912D02*
Y1110919D01*
G01X226318Y1110907D02*
X226319Y1110912D01*
G01X226317Y1110906D02*
X226318Y1110907D01*
G01X226319Y1107762D02*
Y1107770D01*
G01X226318Y1107757D02*
X226319Y1107762D01*
G01X226317Y1107756D02*
X226318Y1107757D01*
G01X226319Y1104613D02*
Y1104620D01*
G01X226318Y1104608D02*
X226319Y1104613D01*
G01X226317Y1104606D02*
X226318Y1104608D01*
G01X227301Y1122376D02*
X227303Y1122388D01*
G01X227294Y1122365D02*
X227301Y1122376D01*
G01X227284Y1122356D02*
X227294Y1122365D01*
G01X227301Y1116076D02*
X227303Y1116089D01*
G01X227294Y1116065D02*
X227301Y1116076D01*
G01X227284Y1116057D02*
X227294Y1116065D01*
G01X227301Y1112927D02*
X227303Y1112939D01*
G01X227294Y1112916D02*
X227301Y1112927D01*
G01X227284Y1112907D02*
X227294Y1112916D01*
G01X227301Y1109777D02*
X227303Y1109790D01*
G01X227294Y1109766D02*
X227301Y1109777D01*
G01X227284Y1109758D02*
X227294Y1109766D01*
G01X227301Y1106628D02*
X227303Y1106640D01*
G01X227294Y1106617D02*
X227301Y1106628D01*
G01X227284Y1106608D02*
X227294Y1106617D01*
G01X227301Y1103478D02*
X227303Y1103491D01*
G01X227294Y1103467D02*
X227301Y1103478D01*
G01X227284Y1103459D02*
X227294Y1103467D01*
G01X226357Y1123548D02*
Y1123555D01*
G01Y1123544D02*
Y1123548D01*
G01X226356Y1123543D02*
X226357Y1123544D01*
G01X240695Y1086791D02*
X240699Y1086890D01*
G01X240690Y1086719D02*
X240695Y1086791D01*
G01X240692Y1086693D02*
X240690Y1086719D01*
G01X240695Y1091791D02*
X240699Y1091890D01*
G01X240690Y1091719D02*
X240695Y1091791D01*
G01X240692Y1091693D02*
X240690Y1091719D01*
G01X240695Y1096791D02*
X240699Y1096890D01*
G01X240690Y1096719D02*
X240695Y1096791D01*
G01X240692Y1096693D02*
X240690Y1096719D01*
G01X240695Y1101791D02*
X240699Y1101890D01*
G01X240690Y1101719D02*
X240695Y1101791D01*
G01X240692Y1101693D02*
X240690Y1101719D01*
G01X240695Y1126791D02*
X240699Y1126890D01*
G01X240690Y1126719D02*
X240695Y1126791D01*
G01X240692Y1126693D02*
X240690Y1126719D01*
G01X226357Y1120399D02*
Y1120405D01*
G01Y1120395D02*
Y1120399D01*
G01X226356Y1120394D02*
X226357Y1120395D01*
G01Y1117249D02*
Y1117256D01*
G01Y1117245D02*
Y1117249D01*
G01X226356Y1117244D02*
X226357Y1117245D01*
G01Y1114100D02*
Y1114106D01*
G01Y1114096D02*
Y1114100D01*
G01X226356Y1114094D02*
X226357Y1114096D01*
G01Y1110950D02*
Y1110956D01*
G01Y1110946D02*
Y1110950D01*
G01X226356Y1110945D02*
X226357Y1110946D01*
G01Y1107800D02*
Y1107807D01*
G01Y1107796D02*
Y1107800D01*
G01X226356Y1107795D02*
X226357Y1107796D01*
G01Y1104651D02*
Y1104657D01*
G01Y1104647D02*
Y1104651D01*
G01X226356Y1104646D02*
X226357Y1104647D01*
G01X226320Y1123524D02*
X226319Y1123518D01*
G01X226321Y1123530D02*
X226320Y1123524D01*
G01X226324Y1123536D02*
X226321Y1123530D01*
G01X226328Y1123541D02*
X226324Y1123536D01*
G01X226333Y1123546D02*
X226328Y1123541D01*
G01X226338Y1123550D02*
X226333Y1123546D01*
G01X226320Y1120374D02*
X226319Y1120368D01*
G01X226321Y1120381D02*
X226320Y1120374D01*
G01X226324Y1120386D02*
X226321Y1120381D01*
G01X226328Y1120392D02*
X226324Y1120386D01*
G01X226333Y1120396D02*
X226328Y1120392D01*
G01X226338Y1120400D02*
X226333Y1120396D01*
G01X226320Y1117225D02*
X226319Y1117219D01*
G01X226321Y1117231D02*
X226320Y1117225D01*
G01X226324Y1117237D02*
X226321Y1117231D01*
G01X226328Y1117242D02*
X226324Y1117237D01*
G01X226333Y1117246D02*
X226328Y1117242D01*
G01X226338Y1117250D02*
X226333Y1117246D01*
G01X226320Y1114075D02*
X226319Y1114069D01*
G01X226321Y1114081D02*
X226320Y1114075D01*
G01X226324Y1114087D02*
X226321Y1114081D01*
G01X226328Y1114093D02*
X226324Y1114087D01*
G01X226333Y1114097D02*
X226328Y1114093D01*
G01X226338Y1114101D02*
X226333Y1114097D01*
G01X226320Y1110926D02*
X226319Y1110919D01*
G01X226321Y1110932D02*
X226320Y1110926D01*
G01X226324Y1110937D02*
X226321Y1110932D01*
G01X226328Y1110943D02*
X226324Y1110937D01*
G01X226333Y1110947D02*
X226328Y1110943D01*
G01X226338Y1110951D02*
X226333Y1110947D01*
G01X226320Y1107776D02*
X226319Y1107770D01*
G01X226321Y1107782D02*
X226320Y1107776D01*
G01X226324Y1107788D02*
X226321Y1107782D01*
G01X226328Y1107793D02*
X226324Y1107788D01*
G01X226333Y1107798D02*
X226328Y1107793D01*
G01X226338Y1107802D02*
X226333Y1107798D01*
G01X226320Y1104626D02*
X226319Y1104620D01*
G01X226321Y1104633D02*
X226320Y1104626D01*
G01X226324Y1104638D02*
X226321Y1104633D01*
G01X226328Y1104644D02*
X226324Y1104638D01*
G01X226333Y1104648D02*
X226328Y1104644D01*
G01X226338Y1104652D02*
X226333Y1104648D01*
G01X227274Y1122364D02*
X227262Y1122362D01*
G01X227285Y1122369D02*
X227274Y1122364D01*
G01Y1119215D02*
X227262Y1119213D01*
G01X227285Y1119220D02*
X227274Y1119215D01*
G01Y1116065D02*
X227262Y1116063D01*
G01X227285Y1116070D02*
X227274Y1116065D01*
G01Y1112915D02*
X227262Y1112913D01*
G01X227285Y1112920D02*
X227274Y1112915D01*
G01Y1109766D02*
X227262Y1109764D01*
G01X227285Y1109771D02*
X227274Y1109766D01*
G01Y1106616D02*
X227262Y1106614D01*
G01X227285Y1106621D02*
X227274Y1106616D01*
G01X240711Y1086688D02*
X240692Y1086693D01*
G01X240726Y1086674D02*
X240711Y1086688D01*
G01X240731Y1086654D02*
X240726Y1086674D01*
G01X240711Y1091688D02*
X240692Y1091693D01*
G01X240726Y1091674D02*
X240711Y1091688D01*
G01X240731Y1091654D02*
X240726Y1091674D01*
G01X240711Y1096688D02*
X240692Y1096693D01*
G01X240726Y1096674D02*
X240711Y1096688D01*
G01X240731Y1096654D02*
X240726Y1096674D01*
G01X240711Y1101688D02*
X240692Y1101693D01*
G01X240726Y1101674D02*
X240711Y1101688D01*
G01X240731Y1101654D02*
X240726Y1101674D01*
G01X227296Y1110927D02*
X227288Y1110935D01*
G01X227300Y1110917D02*
X227296Y1110927D01*
G01X227302Y1110906D02*
X227300Y1110917D01*
G01X227296Y1104628D02*
X227288Y1104636D01*
G01X227300Y1104617D02*
X227296Y1104628D01*
G01X227302Y1104606D02*
X227300Y1104617D01*
G01X227296Y1107777D02*
X227288Y1107786D01*
G01X227300Y1107767D02*
X227296Y1107777D01*
G01X227302Y1107756D02*
X227300Y1107767D01*
G01X227296Y1114076D02*
X227288Y1114085D01*
G01X227300Y1114066D02*
X227296Y1114076D01*
G01X227302Y1114055D02*
X227300Y1114066D01*
G01X227296Y1117226D02*
X227288Y1117235D01*
G01X227300Y1117216D02*
X227296Y1117226D01*
G01X227302Y1117205D02*
X227300Y1117216D01*
G01X227296Y1120376D02*
X227288Y1120384D01*
G01X227300Y1120365D02*
X227296Y1120376D01*
G01X227302Y1120354D02*
X227300Y1120365D01*
G01X227296Y1123525D02*
X227288Y1123534D01*
G01X227300Y1123515D02*
X227296Y1123525D01*
G01X227302Y1123504D02*
X227300Y1123515D01*
G01X227274Y1103467D02*
X227262Y1103465D01*
G01X227285Y1103472D02*
X227274Y1103467D01*
G01X227264Y1103459D02*
X227265Y1103454D01*
G01X227263Y1103463D02*
X227264Y1103459D01*
G01X227262Y1103465D02*
X227263Y1103463D01*
G01X227264Y1106609D02*
X227265Y1106603D01*
G01X227263Y1106613D02*
X227264Y1106609D01*
G01X227262Y1106614D02*
X227263Y1106613D01*
G01X227264Y1109759D02*
X227265Y1109753D01*
G01X227263Y1109763D02*
X227264Y1109759D01*
G01X227262Y1109764D02*
X227263Y1109763D01*
G01X227264Y1112908D02*
X227265Y1112902D01*
G01X227263Y1112912D02*
X227264Y1112908D01*
G01X227262Y1112913D02*
X227263Y1112912D01*
G01X227264Y1116058D02*
X227265Y1116052D01*
G01X227263Y1116062D02*
X227264Y1116058D01*
G01X227262Y1116063D02*
X227263Y1116062D01*
G01X227264Y1122357D02*
X227265Y1122351D01*
G01X227263Y1122361D02*
X227264Y1122357D01*
G01X227262Y1122362D02*
X227263Y1122361D01*
G01X239744Y1086700D02*
Y1086709D01*
G01X239745Y1086695D02*
X239744Y1086700D01*
G01X239746Y1086693D02*
X239745Y1086695D01*
G01X239744Y1091700D02*
Y1091709D01*
G01X239745Y1091695D02*
X239744Y1091700D01*
G01X239746Y1091693D02*
X239745Y1091695D01*
G01X239744Y1096700D02*
Y1096709D01*
G01X239745Y1096695D02*
X239744Y1096700D01*
G01X239746Y1096693D02*
X239745Y1096695D01*
G01X239744Y1101700D02*
Y1101709D01*
G01X239745Y1101695D02*
X239744Y1101700D01*
G01X239746Y1101693D02*
X239745Y1101695D01*
G01X239744Y1126700D02*
Y1126709D01*
G01X239745Y1126695D02*
X239744Y1126700D01*
G01X239746Y1126693D02*
X239745Y1126695D01*
G01X240720Y1086837D02*
X240728Y1086811D01*
G01X240711Y1086863D02*
X240720Y1086837D01*
G01X240699Y1086890D02*
X240711Y1086863D01*
G01X240720Y1091837D02*
X240728Y1091811D01*
G01X240711Y1091863D02*
X240720Y1091837D01*
G01X240699Y1091890D02*
X240711Y1091863D01*
G01X240720Y1096837D02*
X240728Y1096811D01*
G01X240711Y1096863D02*
X240720Y1096837D01*
G01X240699Y1096890D02*
X240711Y1096863D01*
G01X240720Y1101837D02*
X240728Y1101811D01*
G01X240711Y1101863D02*
X240720Y1101837D01*
G01X240699Y1101890D02*
X240711Y1101863D01*
G01X240720Y1126837D02*
X240728Y1126811D01*
G01X240711Y1126863D02*
X240720Y1126837D01*
G01X240699Y1126890D02*
X240711Y1126863D01*
G01X226337Y1112919D02*
X226356Y1112913D01*
G01X226323Y1112931D02*
X226337Y1112919D01*
G01X226317Y1112949D02*
X226323Y1112931D01*
G01X240711Y1126688D02*
X240692Y1126693D01*
G01X240726Y1126674D02*
X240711Y1126688D01*
G01X240731Y1126654D02*
X240726Y1126674D01*
G01X226342Y1106617D02*
X226356Y1106614D01*
G01X226330Y1106624D02*
X226342Y1106617D01*
G01X226318Y1106643D02*
X226330Y1106624D01*
G01X226342Y1116066D02*
X226356Y1116063D01*
G01X226330Y1116073D02*
X226342Y1116066D01*
G01X226318Y1116091D02*
X226330Y1116073D01*
G01X226341Y1109767D02*
X226356Y1109764D01*
G01X226329Y1109774D02*
X226341Y1109767D01*
G01X226317Y1109794D02*
X226329Y1109774D01*
G01X226341Y1119215D02*
X226356Y1119213D01*
G01X226329Y1119223D02*
X226341Y1119215D01*
G01X226317Y1119243D02*
X226329Y1119223D01*
G01X227303Y1103498D02*
Y1103491D01*
G01X227302Y1103503D02*
X227303Y1103498D01*
G01X227302Y1103504D02*
Y1103503D01*
G01X227303Y1106648D02*
Y1106640D01*
G01X227302Y1106652D02*
X227303Y1106648D01*
G01X227302Y1106654D02*
Y1106652D01*
G01X227303Y1109797D02*
Y1109790D01*
G01X227302Y1109802D02*
X227303Y1109797D01*
G01X227302Y1109803D02*
Y1109802D01*
G01X227303Y1112947D02*
Y1112939D01*
G01X227302Y1112952D02*
X227303Y1112947D01*
G01X227302Y1112953D02*
Y1112952D01*
G01X227303Y1116096D02*
Y1116089D01*
G01X227302Y1116101D02*
X227303Y1116096D01*
G01X227302Y1116102D02*
Y1116101D01*
G01X227303Y1119246D02*
Y1119239D01*
G01X227302Y1119251D02*
X227303Y1119246D01*
G01X227302Y1119252D02*
Y1119251D01*
G01X227303Y1122396D02*
Y1122388D01*
G01X227302Y1122400D02*
X227303Y1122396D01*
G01X227302Y1122402D02*
Y1122400D01*
G01X226341Y1122365D02*
X226356Y1122362D01*
G01X226329Y1122373D02*
X226341Y1122365D01*
G01X226317Y1122393D02*
X226329Y1122373D01*
G01X226341Y1103468D02*
X226356Y1103465D01*
G01X226328Y1103476D02*
X226341Y1103468D01*
G01X226317Y1103496D02*
X226328Y1103476D01*
G01X227302Y1104627D02*
X227303Y1104620D01*
G01X227301Y1104633D02*
X227302Y1104627D01*
G01X227298Y1104639D02*
X227301Y1104633D01*
G01X227302Y1107776D02*
X227303Y1107770D01*
G01X227301Y1107783D02*
X227302Y1107776D01*
G01X227298Y1107789D02*
X227301Y1107783D01*
G01X227302Y1110926D02*
X227303Y1110919D01*
G01X227301Y1110932D02*
X227302Y1110926D01*
G01X227298Y1110938D02*
X227301Y1110932D01*
G01X227302Y1114076D02*
X227303Y1114069D01*
G01X227301Y1114082D02*
X227302Y1114076D01*
G01X227298Y1114088D02*
X227301Y1114082D01*
G01X227302Y1117225D02*
X227303Y1117219D01*
G01X227301Y1117231D02*
X227302Y1117225D01*
G01X227298Y1117237D02*
X227301Y1117231D01*
G01X227302Y1120375D02*
X227303Y1120368D01*
G01X227301Y1120381D02*
X227302Y1120375D01*
G01X227298Y1120387D02*
X227301Y1120381D01*
G01X227302Y1123524D02*
X227303Y1123518D01*
G01X227301Y1123531D02*
X227302Y1123524D01*
G01X227298Y1123537D02*
X227301Y1123531D01*
G01X240729Y1086660D02*
X240728Y1086667D01*
G01X240730Y1086656D02*
X240729Y1086660D01*
G01X240731Y1086654D02*
X240730Y1086656D01*
G01X240729Y1091660D02*
X240728Y1091667D01*
G01X240730Y1091656D02*
X240729Y1091660D01*
G01X240731Y1091654D02*
X240730Y1091656D01*
G01X240729Y1096660D02*
X240728Y1096667D01*
G01X240730Y1096656D02*
X240729Y1096660D01*
G01X240731Y1096654D02*
X240730Y1096656D01*
G01X240729Y1101660D02*
X240728Y1101667D01*
G01X240730Y1101656D02*
X240729Y1101660D01*
G01X240731Y1101654D02*
X240730Y1101656D01*
G01X240729Y1126660D02*
X240728Y1126667D01*
G01X240730Y1126656D02*
X240729Y1126660D01*
G01X240731Y1126654D02*
X240730Y1126656D01*
G01X226358Y1103460D02*
Y1103454D01*
G01X226357Y1103463D02*
X226358Y1103460D01*
G01X226356Y1103465D02*
X226357Y1103463D01*
G01X226358Y1106609D02*
Y1106603D01*
G01X226357Y1106613D02*
X226358Y1106609D01*
G01X226356Y1106614D02*
X226357Y1106613D01*
G01X226358Y1109759D02*
Y1109753D01*
G01X226357Y1109763D02*
X226358Y1109759D01*
G01X226356Y1109764D02*
X226357Y1109763D01*
G01X226358Y1112909D02*
Y1112902D01*
G01X226357Y1112912D02*
X226358Y1112909D01*
G01X226356Y1112913D02*
X226357Y1112912D01*
G01X226358Y1116058D02*
Y1116052D01*
G01X226357Y1116062D02*
X226358Y1116058D01*
G01X226356Y1116063D02*
X226357Y1116062D01*
G01X226358Y1119208D02*
Y1119202D01*
G01X226357Y1119211D02*
X226358Y1119208D01*
G01X226356Y1119213D02*
X226357Y1119211D01*
G01X226358Y1122357D02*
Y1122351D01*
G01X226357Y1122361D02*
X226358Y1122357D01*
G01X226356Y1122362D02*
X226357Y1122361D01*
G01X227272Y1110944D02*
X227262Y1110945D01*
G01X227280Y1110941D02*
X227272Y1110944D01*
G01X227288Y1110935D02*
X227280Y1110941D01*
G01X227272Y1104644D02*
X227262Y1104646D01*
G01X227281Y1104641D02*
X227272Y1104644D01*
G01X227288Y1104636D02*
X227281Y1104641D01*
G01X227272Y1107794D02*
X227262Y1107795D01*
G01X227281Y1107791D02*
X227272Y1107794D01*
G01X227288Y1107786D02*
X227281Y1107791D01*
G01X227272Y1114093D02*
X227262Y1114094D01*
G01X227281Y1114090D02*
X227272Y1114093D01*
G01X227288Y1114085D02*
X227281Y1114090D01*
G01X227272Y1117243D02*
X227262Y1117244D01*
G01X227281Y1117240D02*
X227272Y1117243D01*
G01X227288Y1117235D02*
X227281Y1117240D01*
G01X227272Y1120393D02*
X227262Y1120394D01*
G01X227281Y1120389D02*
X227272Y1120393D01*
G01X227288Y1120384D02*
X227281Y1120389D01*
G01X227272Y1123542D02*
X227262Y1123543D01*
G01X227281Y1123539D02*
X227272Y1123542D01*
G01X227288Y1123534D02*
X227281Y1123539D01*
G01X226319Y1106644D02*
Y1106640D01*
G01X226320Y1106638D02*
X226319Y1106644D01*
G01X226332Y1106622D02*
X226320Y1106638D01*
G01X226357Y1106614D02*
X226332Y1106622D01*
G01X226319Y1109794D02*
Y1109790D01*
G01X226320Y1109787D02*
X226319Y1109794D01*
G01X226332Y1109772D02*
X226320Y1109787D01*
G01X226356Y1109764D02*
X226332Y1109772D01*
G01X226319Y1116093D02*
Y1116089D01*
G01X226320Y1116087D02*
X226319Y1116093D01*
G01X226332Y1116071D02*
X226320Y1116087D01*
G01X226356Y1116063D02*
X226332Y1116071D01*
G01X226319Y1119243D02*
Y1119239D01*
G01X226320Y1119236D02*
X226319Y1119243D01*
G01X226332Y1119221D02*
X226320Y1119236D01*
G01X226356Y1119213D02*
X226332Y1119221D01*
G01X226319Y1103494D02*
Y1103491D01*
G01X226320Y1103488D02*
X226319Y1103494D01*
G01X226332Y1103473D02*
X226320Y1103488D01*
G01X226356Y1103465D02*
X226332Y1103473D01*
G01X226319Y1122392D02*
Y1122388D01*
G01X226320Y1122386D02*
X226319Y1122392D01*
G01X226332Y1122370D02*
X226320Y1122386D01*
G01X226356Y1122362D02*
X226332Y1122370D01*
G01X240716Y1086685D02*
X240727Y1086669D01*
G01X240691Y1086693D02*
X240716Y1086685D01*
G01Y1091685D02*
X240727Y1091669D01*
G01X240691Y1091693D02*
X240716Y1091685D01*
G01Y1096685D02*
X240727Y1096669D01*
G01X240691Y1096693D02*
X240716Y1096685D01*
G01Y1101685D02*
X240727Y1101669D01*
G01X240691Y1101693D02*
X240716Y1101685D01*
G01Y1126685D02*
X240727Y1126669D01*
G01X240691Y1126693D02*
X240716Y1126685D01*
G01X226319Y1112943D02*
Y1112939D01*
G01X226320Y1112938D02*
X226319Y1112943D01*
G01X226330Y1112923D02*
X226320Y1112938D01*
G01X226354Y1112914D02*
X226330Y1112923D01*
G01X227294Y1104644D02*
X227298Y1104639D01*
G01X227289Y1104648D02*
X227294Y1104644D01*
G01X227283Y1104652D02*
X227289Y1104648D01*
G01X227277Y1104655D02*
X227283Y1104652D01*
G01X227270Y1104657D02*
X227277Y1104655D01*
G01X227264Y1104657D02*
X227270D01*
G01X227294Y1107794D02*
X227298Y1107789D01*
G01X227289Y1107798D02*
X227294Y1107794D01*
G01X227283Y1107802D02*
X227289Y1107798D01*
G01X227277Y1107804D02*
X227283Y1107802D01*
G01X227270Y1107806D02*
X227277Y1107804D01*
G01X227264Y1107807D02*
X227270Y1107806D01*
G01X227294Y1110943D02*
X227298Y1110938D01*
G01X227289Y1110948D02*
X227294Y1110943D01*
G01X227283Y1110952D02*
X227289Y1110948D01*
G01X227277Y1110954D02*
X227283Y1110952D01*
G01X227270Y1110956D02*
X227277Y1110954D01*
G01X227264Y1110956D02*
X227270D01*
G01X227294Y1114093D02*
X227298Y1114088D01*
G01X227289Y1114097D02*
X227294Y1114093D01*
G01X227283Y1114101D02*
X227289Y1114097D01*
G01X227277Y1114104D02*
X227283Y1114101D01*
G01X227270Y1114106D02*
X227277Y1114104D01*
G01X227264Y1114106D02*
X227270D01*
G01X227294Y1117243D02*
X227298Y1117237D01*
G01X227289Y1117247D02*
X227294Y1117243D01*
G01X227283Y1117251D02*
X227289Y1117247D01*
G01X227277Y1117253D02*
X227283Y1117251D01*
G01X227270Y1117255D02*
X227277Y1117253D01*
G01X227264Y1117256D02*
X227270Y1117255D01*
G01X227294Y1120392D02*
X227298Y1120387D01*
G01X227289Y1120396D02*
X227294Y1120392D01*
G01X227283Y1120400D02*
X227289Y1120396D01*
G01X227277Y1120403D02*
X227283Y1120400D01*
G01X227270Y1120405D02*
X227277Y1120403D01*
G01X227264Y1120405D02*
X227270D01*
G01X227294Y1123542D02*
X227298Y1123537D01*
G01X227289Y1123546D02*
X227294Y1123542D01*
G01X227283Y1123550D02*
X227289Y1123546D01*
G01X227277Y1123552D02*
X227283Y1123550D01*
G01X227270Y1123554D02*
X227277Y1123552D01*
G01X227264Y1123555D02*
X227270Y1123554D01*
G01X226320Y1103483D02*
X226319Y1103491D01*
G01X226322Y1103476D02*
X226320Y1103483D01*
G01X226326Y1103470D02*
X226322Y1103476D01*
G01X226330Y1103464D02*
X226326Y1103470D01*
G01X226337Y1103459D02*
X226330Y1103464D01*
G01X226343Y1103456D02*
X226337Y1103459D01*
G01X226351Y1103454D02*
X226343Y1103456D01*
G01X226358Y1103454D02*
X226351D01*
G01X226320Y1106633D02*
X226319Y1106640D01*
G01X226322Y1106626D02*
X226320Y1106633D01*
G01X226326Y1106620D02*
X226322Y1106626D01*
G01X226330Y1106614D02*
X226326Y1106620D01*
G01X226337Y1106609D02*
X226330Y1106614D01*
G01X226343Y1106606D02*
X226337Y1106609D01*
G01X226351Y1106604D02*
X226343Y1106606D01*
G01X226358Y1106603D02*
X226351Y1106604D01*
G01X226320Y1109782D02*
X226319Y1109790D01*
G01X226322Y1109776D02*
X226320Y1109782D01*
G01X226326Y1109769D02*
X226322Y1109776D01*
G01X226330Y1109763D02*
X226326Y1109769D01*
G01X226337Y1109759D02*
X226330Y1109763D01*
G01X226343Y1109756D02*
X226337Y1109759D01*
G01X226351Y1109754D02*
X226343Y1109756D01*
G01X226358Y1109753D02*
X226351Y1109754D01*
G01X226320Y1112932D02*
X226319Y1112939D01*
G01X226322Y1112925D02*
X226320Y1112932D01*
G01X226326Y1112919D02*
X226322Y1112925D01*
G01X226330Y1112913D02*
X226326Y1112919D01*
G01X226337Y1112908D02*
X226330Y1112913D01*
G01X226343Y1112905D02*
X226337Y1112908D01*
G01X226351Y1112903D02*
X226343Y1112905D01*
G01X226358Y1112902D02*
X226351Y1112903D01*
G01X226320Y1116081D02*
X226319Y1116089D01*
G01X226322Y1116075D02*
X226320Y1116081D01*
G01X226326Y1116069D02*
X226322Y1116075D01*
G01X226330Y1116063D02*
X226326Y1116069D01*
G01X226337Y1116058D02*
X226330Y1116063D01*
G01X226343Y1116055D02*
X226337Y1116058D01*
G01X226351Y1116053D02*
X226343Y1116055D01*
G01X226358Y1116052D02*
X226351Y1116053D01*
G01X226320Y1119231D02*
X226319Y1119239D01*
G01X226322Y1119224D02*
X226320Y1119231D01*
G01X226326Y1119218D02*
X226322Y1119224D01*
G01X226330Y1119212D02*
X226326Y1119218D01*
G01X226337Y1119207D02*
X226330Y1119212D01*
G01X226343Y1119204D02*
X226337Y1119207D01*
G01X226351Y1119202D02*
X226343Y1119204D01*
G01X226358Y1119202D02*
X226351D01*
G01X226320Y1122381D02*
X226319Y1122388D01*
G01X226322Y1122374D02*
X226320Y1122381D01*
G01X226326Y1122368D02*
X226322Y1122374D01*
G01X226330Y1122362D02*
X226326Y1122368D01*
G01X226337Y1122357D02*
X226330Y1122362D01*
G01X226343Y1122354D02*
X226337Y1122357D01*
G01X226351Y1122352D02*
X226343Y1122354D01*
G01X226358Y1122351D02*
X226351Y1122352D01*
G01X227273Y1104644D02*
X227282Y1104640D01*
G01X227262Y1104646D02*
X227273Y1104644D01*
G01Y1107794D02*
X227282Y1107790D01*
G01X227262Y1107795D02*
X227273Y1107794D01*
G01Y1110944D02*
X227282Y1110939D01*
G01X227262Y1110945D02*
X227273Y1110944D01*
G01Y1114093D02*
X227282Y1114089D01*
G01X227262Y1114094D02*
X227273Y1114093D01*
G01Y1117243D02*
X227282Y1117239D01*
G01X227262Y1117244D02*
X227273Y1117243D01*
G01Y1120393D02*
X227282Y1120388D01*
G01X227262Y1120394D02*
X227273Y1120393D01*
G01Y1123542D02*
X227282Y1123538D01*
G01X227262Y1123543D02*
X227273Y1123542D01*
G01X227281Y1103457D02*
X227284Y1103459D01*
G01X227278Y1103456D02*
X227281Y1103457D01*
G01X227274Y1103455D02*
X227278Y1103456D01*
G01X227271Y1103454D02*
X227274Y1103455D01*
G01X227267Y1103454D02*
X227271D01*
G01X227264D02*
X227267D01*
G01X226341Y1104654D02*
X226338Y1104652D01*
G01X226344Y1104655D02*
X226341Y1104654D01*
G01X226348Y1104656D02*
X226344Y1104655D01*
G01X226351Y1104656D02*
X226348D01*
G01X226355Y1104657D02*
X226351Y1104656D01*
G01X226358Y1104657D02*
X226355D01*
G01X227281Y1106607D02*
X227284Y1106608D01*
G01X227278Y1106606D02*
X227281Y1106607D01*
G01X227274Y1106604D02*
X227278Y1106606D01*
G01X227271Y1106604D02*
X227274D01*
G01X227267Y1106603D02*
X227271Y1106604D01*
G01X227264Y1106603D02*
X227267D01*
G01X226341Y1107803D02*
X226338Y1107802D01*
G01X226344Y1107804D02*
X226341Y1107803D01*
G01X226348Y1107806D02*
X226344Y1107804D01*
G01X226351Y1107806D02*
X226348D01*
G01X226355Y1107807D02*
X226351Y1107806D01*
G01X226358Y1107807D02*
X226355D01*
G01X227281Y1109756D02*
X227284Y1109758D01*
G01X227278Y1109755D02*
X227281Y1109756D01*
G01X227274Y1109754D02*
X227278Y1109755D01*
G01X227271Y1109753D02*
X227274Y1109754D01*
G01X227267Y1109753D02*
X227271D01*
G01X227264D02*
X227267D01*
G01X226341Y1110953D02*
X226338Y1110951D01*
G01X226344Y1110954D02*
X226341Y1110953D01*
G01X226348Y1110955D02*
X226344Y1110954D01*
G01X226351Y1110956D02*
X226348Y1110955D01*
G01X226355Y1110956D02*
X226351D01*
G01X226358D02*
X226355D01*
G01X227281Y1112906D02*
X227284Y1112907D01*
G01X227278Y1112905D02*
X227281Y1112906D01*
G01X227274Y1112904D02*
X227278Y1112905D01*
G01X227271Y1112903D02*
X227274Y1112904D01*
G01X227267Y1112902D02*
X227271Y1112903D01*
G01X227264Y1112902D02*
X227267D01*
G01X226341Y1114102D02*
X226338Y1114101D01*
G01X226344Y1114104D02*
X226341Y1114102D01*
G01X226348Y1114105D02*
X226344Y1114104D01*
G01X226351Y1114105D02*
X226348D01*
G01X226355Y1114106D02*
X226351Y1114105D01*
G01X226358Y1114106D02*
X226355D01*
G01X227281Y1116056D02*
X227284Y1116057D01*
G01X227278Y1116054D02*
X227281Y1116056D01*
G01X227274Y1116053D02*
X227278Y1116054D01*
G01X227271Y1116052D02*
X227274Y1116053D01*
G01X227267Y1116052D02*
X227271D01*
G01X227264D02*
X227267D01*
G01X226341Y1117252D02*
X226338Y1117250D01*
G01X226344Y1117253D02*
X226341Y1117252D01*
G01X226348Y1117254D02*
X226344Y1117253D01*
G01X226351Y1117255D02*
X226348Y1117254D01*
G01X226355Y1117256D02*
X226351Y1117255D01*
G01X226358Y1117256D02*
X226355D01*
G01X226341Y1120402D02*
X226338Y1120400D01*
G01X226344Y1120403D02*
X226341Y1120402D01*
G01X226348Y1120404D02*
X226344Y1120403D01*
G01X226351Y1120404D02*
X226348D01*
G01X226355Y1120405D02*
X226351Y1120404D01*
G01X226358Y1120405D02*
X226355D01*
G01X227281Y1122355D02*
X227284Y1122356D01*
G01X227278Y1122354D02*
X227281Y1122355D01*
G01X227274Y1122352D02*
X227278Y1122354D01*
G01X227271Y1122352D02*
X227274D01*
G01X227267Y1122351D02*
X227271Y1122352D01*
G01X227264Y1122351D02*
X227267D01*
G01X226341Y1123551D02*
X226338Y1123550D01*
G01X226344Y1123552D02*
X226341Y1123551D01*
G01X226348Y1123554D02*
X226344Y1123552D01*
G01X226351Y1123554D02*
X226348D01*
G01X226355Y1123555D02*
X226351Y1123554D01*
G01X226358Y1123555D02*
X226355D01*
G01X225572Y1106654D02*
X225138D01*
G01X225945D02*
X225572D01*
G01Y1112953D02*
X225138D01*
G01X225945D02*
X225572D01*
G01Y1116102D02*
X225138D01*
G01X225945D02*
X225572D01*
G01X227302Y1119231D02*
X227303Y1119239D01*
G01X227300Y1119224D02*
X227302Y1119231D01*
G01X227296Y1119218D02*
X227300Y1119224D01*
G01X227292Y1119212D02*
X227296Y1119218D01*
G01X227285Y1119207D02*
X227292Y1119212D01*
G01X227279Y1119204D02*
X227285Y1119207D01*
G01X227271Y1119202D02*
X227279Y1119204D01*
G01X227264Y1119202D02*
X227271D01*
G01X226322Y1104626D02*
X226317Y1104606D01*
G01X226336Y1104641D02*
X226322Y1104626D01*
G01X226356Y1104646D02*
X226336Y1104641D01*
G01X226322Y1107776D02*
X226317Y1107756D01*
G01X226336Y1107790D02*
X226322Y1107776D01*
G01X226356Y1107795D02*
X226336Y1107790D01*
G01X226322Y1110925D02*
X226317Y1110906D01*
G01X226336Y1110940D02*
X226322Y1110925D01*
G01X226356Y1110945D02*
X226336Y1110940D01*
G01X226322Y1114075D02*
X226317Y1114055D01*
G01X226336Y1114089D02*
X226322Y1114075D01*
G01X226356Y1114094D02*
X226336Y1114089D01*
G01X226322Y1117224D02*
X226317Y1117205D01*
G01X226336Y1117239D02*
X226322Y1117224D01*
G01X226356Y1117244D02*
X226336Y1117239D01*
G01X226322Y1120374D02*
X226317Y1120354D01*
G01X226336Y1120389D02*
X226322Y1120374D01*
G01X226356Y1120394D02*
X226336Y1120389D01*
G01X226322Y1123524D02*
X226317Y1123504D01*
G01X226336Y1123538D02*
X226322Y1123524D01*
G01X226356Y1123543D02*
X226336Y1123538D01*
G01X227296Y1103484D02*
X227302Y1103504D01*
G01X227282Y1103470D02*
X227296Y1103484D01*
G01X227262Y1103465D02*
X227282Y1103470D01*
G01X227296Y1106634D02*
X227302Y1106654D01*
G01X227282Y1106620D02*
X227296Y1106634D01*
G01X227262Y1106614D02*
X227282Y1106620D01*
G01X227296Y1109783D02*
X227302Y1109803D01*
G01X227282Y1109769D02*
X227296Y1109783D01*
G01X227262Y1109764D02*
X227282Y1109769D01*
G01X227296Y1112933D02*
X227302Y1112953D01*
G01X227282Y1112919D02*
X227296Y1112933D01*
G01X227262Y1112913D02*
X227282Y1112919D01*
G01X227296Y1116083D02*
X227302Y1116102D01*
G01X227282Y1116069D02*
X227296Y1116083D01*
G01X227262Y1116063D02*
X227282Y1116069D01*
G01X227296Y1119232D02*
X227302Y1119252D01*
G01X227282Y1119218D02*
X227296Y1119232D01*
G01X227262Y1119213D02*
X227282Y1119218D01*
G01X227296Y1122382D02*
X227302Y1122402D01*
G01X227282Y1122368D02*
X227296Y1122382D01*
G01X227262Y1122362D02*
X227282Y1122368D01*
G01X226206Y1122402D02*
X226317Y1122393D01*
G01Y1112949D02*
X226206Y1112953D01*
G01X226317Y1106650D02*
X226206Y1106654D01*
G01X226317Y1116099D02*
X226206Y1116102D01*
G01X245079Y1130315D02*
X239746D01*
G01X239744Y1129823D02*
X240728D01*
G01Y1127185D02*
X239744D01*
G01X239746Y1126693D02*
X245079D01*
G01Y1126654D02*
X240731D01*
G01X227756Y1125709D02*
X224409D01*
G01X245079Y1125315D02*
X239746D01*
G01X239744Y1124823D02*
X240728D01*
G01X237402Y1124547D02*
X241339D01*
G01X227264Y1123740D02*
X226358D01*
G01X227303Y1123701D02*
X226319D01*
G01X227262Y1123543D02*
X221378D01*
G01Y1123504D02*
X227302D01*
G01X236220Y1123366D02*
X240157D01*
G01X227302Y1122402D02*
X221378D01*
G01X227262Y1122362D02*
X221378D01*
G01X226319Y1122205D02*
X227303D01*
G01X226358Y1122165D02*
X227264D01*
G01Y1120591D02*
X226358D01*
G01X227303Y1120551D02*
X226319D01*
G01X227262Y1120394D02*
X221378D01*
G01Y1120354D02*
X227302D01*
G01Y1119252D02*
X221378D01*
G01X227262Y1119213D02*
X221378D01*
G01X226319Y1119055D02*
X227303D01*
G01X226358Y1119016D02*
X227264D01*
G01Y1117441D02*
X226358D01*
G01X227303Y1117402D02*
X226319D01*
G01X227262Y1117244D02*
X221378D01*
G01Y1117205D02*
X227302D01*
G01Y1116102D02*
X221378D01*
G01X227262Y1116063D02*
X221378D01*
G01X226319Y1115906D02*
X227303D01*
G01X226358Y1115866D02*
X227264D01*
G01Y1114291D02*
X226358D01*
G01X227303Y1114252D02*
X226319D01*
G01X227262Y1114094D02*
X221378D01*
G01Y1114055D02*
X227302D01*
G01Y1112953D02*
X221378D01*
G01X227262Y1112913D02*
X221378D01*
G01X226319Y1112756D02*
X227303D01*
G01X226358Y1112717D02*
X227264D01*
G01Y1111142D02*
X226358D01*
G01X227303Y1111102D02*
X226319D01*
G01X227262Y1110945D02*
X221378D01*
G01Y1110906D02*
X227302D01*
G01Y1109803D02*
X221378D01*
G01X227262Y1109764D02*
X221378D01*
G01X226319Y1109606D02*
X227303D01*
G01X226358Y1109567D02*
X227264D01*
G01Y1107992D02*
X226358D01*
G01X227303Y1107953D02*
X226319D01*
G01X227262Y1107795D02*
X221378D01*
G01Y1107756D02*
X227302D01*
G01Y1106654D02*
X221378D01*
G01X227262Y1106614D02*
X221378D01*
G01X226319Y1106457D02*
X227303D01*
G01X226358Y1106417D02*
X227264D01*
G01Y1104843D02*
X226358D01*
G01X227303Y1104803D02*
X226319D01*
G01X227262Y1104646D02*
X221378D01*
G01Y1104606D02*
X227302D01*
G01X240157Y1103642D02*
X236220D01*
G01X227302Y1103504D02*
X221378D01*
G01X227262Y1103465D02*
X221378D01*
G01X226319Y1103307D02*
X227303D01*
G01X226358Y1103268D02*
X227264D01*
G01X241339Y1102461D02*
X237402D01*
G01X240728Y1102185D02*
X239744D01*
G01X239746Y1101693D02*
X245079D01*
G01Y1101654D02*
X240731D01*
G01X227756Y1101299D02*
X224409D01*
G01X245079Y1100315D02*
X239746D01*
G01X239744Y1099823D02*
X240728D01*
G01Y1097185D02*
X239744D01*
G01X239746Y1096693D02*
X245079D01*
G01Y1096654D02*
X240731D01*
G01X245079Y1095315D02*
X239746D01*
G01X239744Y1094823D02*
X240728D01*
G01Y1092185D02*
X239744D01*
G01X239746Y1091693D02*
X245079D01*
G01Y1091654D02*
X240731D01*
G01X245079Y1090315D02*
X239746D01*
G01X239744Y1089823D02*
X240728D01*
G01Y1087185D02*
X239744D01*
G01X239746Y1086693D02*
X245079D01*
G01Y1086654D02*
X240731D01*
G01X245079Y1085315D02*
X239746D01*
G01X239744Y1084823D02*
X240728D01*
G01Y1130119D02*
X239744Y1130118D01*
G01Y1126889D02*
X240699Y1126890D01*
G01X240728Y1125119D02*
X239744Y1125118D01*
G01Y1101889D02*
X240699Y1101890D01*
G01X240728Y1100119D02*
X239744Y1100118D01*
G01Y1096889D02*
X240699Y1096890D01*
G01X240728Y1095119D02*
X239744Y1095118D01*
G01Y1091889D02*
X240699Y1091890D01*
G01X240728Y1090119D02*
X239744Y1090118D01*
G01Y1086889D02*
X240699Y1086890D01*
G01X240728Y1085119D02*
X239744Y1085118D01*
G01X240157Y1103642D02*
X241339Y1102461D01*
G01X236220Y1103642D02*
X237402Y1102461D01*
G01X227262Y1119213D02*
X227266Y1119202D01*
G01X240157Y1123366D02*
X241339Y1124547D01*
G01X236220Y1123366D02*
X237402Y1124547D01*
G01X227303Y1104609D02*
Y1104620D01*
G01Y1107758D02*
Y1107769D01*
G01Y1110908D02*
Y1110919D01*
G01Y1114057D02*
Y1114069D01*
G01Y1117207D02*
Y1117218D01*
G01Y1120357D02*
Y1120368D01*
G01Y1123506D02*
Y1123517D01*
G01X240728Y1086667D02*
X240729Y1086676D01*
G01X240728Y1091667D02*
X240729Y1091676D01*
G01X240728Y1096667D02*
X240729Y1096676D01*
G01X240728Y1101667D02*
X240729Y1101676D01*
G01X240728Y1126667D02*
X240729Y1126676D01*
G01X245079Y1130315D02*
Y1131693D01*
G01Y1125315D02*
Y1126693D01*
G01Y1100315D02*
Y1101693D01*
G01Y1095315D02*
Y1096693D01*
G01Y1090315D02*
Y1091693D01*
G01Y1085315D02*
Y1086693D01*
G01X241909D02*
Y1085315D01*
G01Y1091693D02*
Y1090315D01*
G01Y1096693D02*
Y1095315D01*
G01Y1101693D02*
Y1100315D01*
G01Y1126693D02*
Y1125315D01*
G01Y1131693D02*
Y1130315D01*
G01X241339Y1124547D02*
Y1102461D01*
G01X240728Y1129823D02*
Y1132185D01*
G01Y1124823D02*
Y1127185D01*
G01Y1099823D02*
Y1102185D01*
G01Y1094823D02*
Y1097185D01*
G01Y1089823D02*
Y1092185D01*
G01Y1084823D02*
Y1087185D01*
G01Y1086667D02*
Y1086811D01*
G01Y1096667D02*
Y1096811D01*
G01Y1091667D02*
Y1091811D01*
G01Y1101667D02*
Y1101811D01*
G01Y1126667D02*
Y1126811D01*
G01X240157Y1123366D02*
Y1103642D01*
G01X239744Y1087185D02*
Y1084823D01*
G01Y1092185D02*
Y1089823D01*
G01Y1097185D02*
Y1094823D01*
G01Y1102185D02*
Y1099823D01*
G01Y1127185D02*
Y1124823D01*
G01Y1132185D02*
Y1129823D01*
G01X237402Y1201004D02*
Y1124547D01*
G01X236220Y1199823D02*
Y1123366D01*
G01X227756Y1204744D02*
Y1125709D01*
G01X227303Y1122205D02*
Y1123701D01*
G01Y1119055D02*
Y1120551D01*
G01Y1115906D02*
Y1117402D01*
G01Y1112756D02*
Y1114252D01*
G01Y1109606D02*
Y1111102D01*
G01Y1106457D02*
Y1107953D01*
G01Y1103307D02*
Y1104803D01*
G01X227264Y1106603D02*
Y1106456D01*
G01Y1103454D02*
Y1103307D01*
G01Y1104804D02*
Y1104657D01*
G01Y1109753D02*
Y1109606D01*
G01Y1111103D02*
Y1110956D01*
G01Y1107953D02*
Y1107807D01*
G01Y1116052D02*
Y1115905D01*
G01Y1112902D02*
Y1112756D01*
G01Y1114252D02*
Y1114106D01*
G01Y1119202D02*
Y1119055D01*
G01Y1120552D02*
Y1120405D01*
G01Y1117402D02*
Y1117256D01*
G01Y1122351D02*
Y1122204D01*
G01Y1123701D02*
Y1123555D01*
G01X226358Y1122204D02*
Y1122351D01*
G01Y1123555D02*
Y1123702D01*
G01Y1119054D02*
Y1119202D01*
G01Y1120405D02*
Y1120552D01*
G01Y1117256D02*
Y1117402D01*
G01Y1115905D02*
Y1116052D01*
G01Y1112755D02*
Y1112902D01*
G01Y1114106D02*
Y1114253D01*
G01Y1109606D02*
Y1109753D01*
G01Y1110956D02*
Y1111103D01*
G01Y1107807D02*
Y1107954D01*
G01Y1106456D02*
Y1106603D01*
G01Y1103306D02*
Y1103454D01*
G01Y1104657D02*
Y1104804D01*
G01X226319Y1104803D02*
Y1103307D01*
G01Y1111102D02*
Y1109606D01*
G01Y1107953D02*
Y1106457D01*
G01Y1114252D02*
Y1112756D01*
G01Y1120551D02*
Y1119055D01*
G01Y1117402D02*
Y1115906D01*
G01Y1123701D02*
Y1122205D01*
G01X225138Y1107795D02*
Y1106614D01*
G01Y1104646D02*
Y1103465D01*
G01Y1110945D02*
Y1109764D01*
G01Y1117244D02*
Y1116063D01*
G01Y1114094D02*
Y1112913D01*
G01Y1120394D02*
Y1119213D01*
G01Y1123543D02*
Y1122362D01*
G01X224803Y1125709D02*
Y1101299D01*
G01X224409D02*
Y1125709D01*
G01X221378Y1122362D02*
Y1123543D01*
G01Y1119213D02*
Y1120394D01*
G01Y1116063D02*
Y1117244D01*
G01Y1112913D02*
Y1114094D01*
G01Y1109764D02*
Y1110945D01*
G01Y1106614D02*
Y1107795D01*
G01Y1103465D02*
Y1104646D01*
G01X227303Y1122388D02*
Y1122399D01*
G01Y1119239D02*
Y1119250D01*
G01Y1116089D02*
Y1116100D01*
G01Y1112939D02*
Y1112950D01*
G01Y1109790D02*
Y1109801D01*
G01Y1106640D02*
Y1106651D01*
G01Y1103491D02*
Y1103502D01*
G01X240729Y1175308D02*
X240728Y1175299D01*
G01X240730Y1175313D02*
X240729Y1175308D01*
G01X240731Y1175315D02*
X240730Y1175313D01*
G01X240729Y1170308D02*
X240728Y1170299D01*
G01X240730Y1170313D02*
X240729Y1170308D01*
G01X240731Y1170315D02*
X240730Y1170313D01*
G01X240729Y1165308D02*
X240728Y1165299D01*
G01X240730Y1165313D02*
X240729Y1165308D01*
G01X240731Y1165315D02*
X240730Y1165313D01*
G01X240729Y1160308D02*
X240728Y1160299D01*
G01X240730Y1160313D02*
X240729Y1160308D01*
G01X240731Y1160315D02*
X240730Y1160313D01*
G01X240729Y1155308D02*
X240728Y1155299D01*
G01X240730Y1155313D02*
X240729Y1155308D01*
G01X240731Y1155315D02*
X240730Y1155313D01*
G01X240729Y1150308D02*
X240728Y1150299D01*
G01X240730Y1150313D02*
X240729Y1150308D01*
G01X240731Y1150315D02*
X240730Y1150313D01*
G01X239745Y1175313D02*
X239746Y1175315D01*
G01X239744Y1175308D02*
X239745Y1175313D01*
G01X239744Y1175299D02*
Y1175308D01*
G01X239745Y1170313D02*
X239746Y1170315D01*
G01X239744Y1170308D02*
X239745Y1170313D01*
G01X239744Y1170299D02*
Y1170308D01*
G01X239745Y1165313D02*
X239746Y1165315D01*
G01X239744Y1165308D02*
X239745Y1165313D01*
G01X239744Y1165299D02*
Y1165308D01*
G01X239745Y1160313D02*
X239746Y1160315D01*
G01X239744Y1160308D02*
X239745Y1160313D01*
G01X239744Y1160299D02*
Y1160308D01*
G01X239745Y1155313D02*
X239746Y1155315D01*
G01X239744Y1155308D02*
X239745Y1155313D01*
G01X239744Y1155299D02*
Y1155308D01*
G01X239745Y1150313D02*
X239746Y1150315D01*
G01X239744Y1150308D02*
X239745Y1150313D01*
G01X239744Y1150299D02*
Y1150308D01*
G01X239745Y1145313D02*
X239746Y1145315D01*
G01X239744Y1145308D02*
X239745Y1145313D01*
G01X239744Y1145299D02*
Y1145308D01*
G01X239745Y1140313D02*
X239746Y1140315D01*
G01X239744Y1140308D02*
X239745Y1140313D01*
G01X239744Y1140299D02*
Y1140308D01*
G01X239745Y1135313D02*
X239746Y1135315D01*
G01X239744Y1135308D02*
X239745Y1135313D01*
G01X239744Y1135299D02*
Y1135308D01*
G01X240729Y1145308D02*
X240728Y1145299D01*
G01X240730Y1145313D02*
X240729Y1145308D01*
G01X240731Y1145315D02*
X240730Y1145313D01*
G01X240729Y1140308D02*
X240728Y1140299D01*
G01X240730Y1140313D02*
X240729Y1140308D01*
G01X240731Y1140315D02*
X240730Y1140313D01*
G01X240729Y1135308D02*
X240728Y1135299D01*
G01X240730Y1135313D02*
X240729Y1135308D01*
G01X240731Y1135315D02*
X240730Y1135313D01*
G01X240695Y1131791D02*
X240699Y1131890D01*
G01X240690Y1131719D02*
X240695Y1131791D01*
G01X240692Y1131693D02*
X240690Y1131719D01*
G01X240695Y1136791D02*
X240699Y1136890D01*
G01X240690Y1136719D02*
X240695Y1136791D01*
G01X240692Y1136693D02*
X240690Y1136719D01*
G01X240695Y1141791D02*
X240699Y1141890D01*
G01X240690Y1141719D02*
X240695Y1141791D01*
G01X240692Y1141693D02*
X240690Y1141719D01*
G01X240695Y1146791D02*
X240699Y1146890D01*
G01X240690Y1146719D02*
X240695Y1146791D01*
G01X240692Y1146693D02*
X240690Y1146719D01*
G01X240695Y1151791D02*
X240699Y1151890D01*
G01X240690Y1151719D02*
X240695Y1151791D01*
G01X240692Y1151693D02*
X240690Y1151719D01*
G01X240695Y1156791D02*
X240699Y1156890D01*
G01X240690Y1156719D02*
X240695Y1156791D01*
G01X240692Y1156693D02*
X240690Y1156719D01*
G01X240695Y1161791D02*
X240699Y1161890D01*
G01X240690Y1161719D02*
X240695Y1161791D01*
G01X240692Y1161693D02*
X240690Y1161719D01*
G01X240695Y1166791D02*
X240699Y1166890D01*
G01X240690Y1166719D02*
X240695Y1166791D01*
G01X240692Y1166693D02*
X240690Y1166719D01*
G01X240695Y1171791D02*
X240699Y1171890D01*
G01X240690Y1171719D02*
X240695Y1171791D01*
G01X240692Y1171693D02*
X240690Y1171719D01*
G01X240695Y1176791D02*
X240699Y1176890D01*
G01X240690Y1176719D02*
X240695Y1176791D01*
G01X240692Y1176693D02*
X240690Y1176719D01*
G01X240720Y1131837D02*
X240728Y1131811D01*
G01X240711Y1131863D02*
X240720Y1131837D01*
G01X240699Y1131890D02*
X240711Y1131863D01*
G01X240720Y1136837D02*
X240728Y1136811D01*
G01X240711Y1136863D02*
X240720Y1136837D01*
G01X240699Y1136890D02*
X240711Y1136863D01*
G01Y1131688D02*
X240692Y1131693D01*
G01X240726Y1131674D02*
X240711Y1131688D01*
G01X240731Y1131654D02*
X240726Y1131674D01*
G01X240711Y1136688D02*
X240692Y1136693D01*
G01X240726Y1136674D02*
X240711Y1136688D01*
G01X240731Y1136654D02*
X240726Y1136674D01*
G01X240711Y1141688D02*
X240692Y1141693D01*
G01X240726Y1141674D02*
X240711Y1141688D01*
G01X240731Y1141654D02*
X240726Y1141674D01*
G01X240711Y1146688D02*
X240692Y1146693D01*
G01X240726Y1146674D02*
X240711Y1146688D01*
G01X240731Y1146654D02*
X240726Y1146674D01*
G01X240711Y1151688D02*
X240692Y1151693D01*
G01X240726Y1151674D02*
X240711Y1151688D01*
G01X240731Y1151654D02*
X240726Y1151674D01*
G01X240711Y1156688D02*
X240692Y1156693D01*
G01X240726Y1156674D02*
X240711Y1156688D01*
G01X240731Y1156654D02*
X240726Y1156674D01*
G01X240711Y1161688D02*
X240692Y1161693D01*
G01X240726Y1161674D02*
X240711Y1161688D01*
G01X240731Y1161654D02*
X240726Y1161674D01*
G01X240711Y1166688D02*
X240692Y1166693D01*
G01X240726Y1166674D02*
X240711Y1166688D01*
G01X240731Y1166654D02*
X240726Y1166674D01*
G01X240711Y1171688D02*
X240692Y1171693D01*
G01X240726Y1171674D02*
X240711Y1171688D01*
G01X240731Y1171654D02*
X240726Y1171674D01*
G01X240711Y1176688D02*
X240692Y1176693D01*
G01X240726Y1176674D02*
X240711Y1176688D01*
G01X240731Y1176654D02*
X240726Y1176674D01*
G01X239744Y1131700D02*
Y1131709D01*
G01X239745Y1131695D02*
X239744Y1131700D01*
G01X239746Y1131693D02*
X239745Y1131695D01*
G01X239744Y1136700D02*
Y1136709D01*
G01X239745Y1136695D02*
X239744Y1136700D01*
G01X239746Y1136693D02*
X239745Y1136695D01*
G01X239744Y1141700D02*
Y1141709D01*
G01X239745Y1141695D02*
X239744Y1141700D01*
G01X239746Y1141693D02*
X239745Y1141695D01*
G01X239744Y1146700D02*
Y1146709D01*
G01X239745Y1146695D02*
X239744Y1146700D01*
G01X239746Y1146693D02*
X239745Y1146695D01*
G01X239744Y1151700D02*
Y1151709D01*
G01X239745Y1151695D02*
X239744Y1151700D01*
G01X239746Y1151693D02*
X239745Y1151695D01*
G01X239744Y1156700D02*
Y1156709D01*
G01X239745Y1156695D02*
X239744Y1156700D01*
G01X239746Y1156693D02*
X239745Y1156695D01*
G01X239744Y1161700D02*
Y1161709D01*
G01X239745Y1161695D02*
X239744Y1161700D01*
G01X239746Y1161693D02*
X239745Y1161695D01*
G01X239744Y1166700D02*
Y1166709D01*
G01X239745Y1166695D02*
X239744Y1166700D01*
G01X239746Y1166693D02*
X239745Y1166695D01*
G01X239744Y1171700D02*
Y1171709D01*
G01X239745Y1171695D02*
X239744Y1171700D01*
G01X239746Y1171693D02*
X239745Y1171695D01*
G01X239744Y1176700D02*
Y1176709D01*
G01X239745Y1176695D02*
X239744Y1176700D01*
G01X239746Y1176693D02*
X239745Y1176695D01*
G01X240720Y1141837D02*
X240728Y1141811D01*
G01X240711Y1141863D02*
X240720Y1141837D01*
G01X240699Y1141890D02*
X240711Y1141863D01*
G01X240720Y1146837D02*
X240728Y1146811D01*
G01X240711Y1146863D02*
X240720Y1146837D01*
G01X240699Y1146890D02*
X240711Y1146863D01*
G01X240720Y1151837D02*
X240728Y1151811D01*
G01X240711Y1151863D02*
X240720Y1151837D01*
G01X240699Y1151890D02*
X240711Y1151863D01*
G01X240720Y1156837D02*
X240728Y1156811D01*
G01X240711Y1156863D02*
X240720Y1156837D01*
G01X240699Y1156890D02*
X240711Y1156863D01*
G01X240720Y1161837D02*
X240728Y1161811D01*
G01X240711Y1161863D02*
X240720Y1161837D01*
G01X240699Y1161890D02*
X240711Y1161863D01*
G01X240720Y1166837D02*
X240728Y1166811D01*
G01X240711Y1166863D02*
X240720Y1166837D01*
G01X240699Y1166890D02*
X240711Y1166863D01*
G01X240720Y1171837D02*
X240728Y1171811D01*
G01X240711Y1171863D02*
X240720Y1171837D01*
G01X240699Y1171890D02*
X240711Y1171863D01*
G01X240720Y1176837D02*
X240728Y1176811D01*
G01X240711Y1176863D02*
X240720Y1176837D01*
G01X240699Y1176890D02*
X240711Y1176863D01*
G01X240729Y1131660D02*
X240728Y1131667D01*
G01X240730Y1131656D02*
X240729Y1131660D01*
G01X240731Y1131654D02*
X240730Y1131656D01*
G01X240729Y1136660D02*
X240728Y1136667D01*
G01X240730Y1136656D02*
X240729Y1136660D01*
G01X240731Y1136654D02*
X240730Y1136656D01*
G01X240729Y1141660D02*
X240728Y1141667D01*
G01X240730Y1141656D02*
X240729Y1141660D01*
G01X240731Y1141654D02*
X240730Y1141656D01*
G01X240729Y1146660D02*
X240728Y1146667D01*
G01X240730Y1146656D02*
X240729Y1146660D01*
G01X240731Y1146654D02*
X240730Y1146656D01*
G01X240729Y1151660D02*
X240728Y1151667D01*
G01X240730Y1151656D02*
X240729Y1151660D01*
G01X240731Y1151654D02*
X240730Y1151656D01*
G01X240729Y1156660D02*
X240728Y1156667D01*
G01X240730Y1156656D02*
X240729Y1156660D01*
G01X240731Y1156654D02*
X240730Y1156656D01*
G01X240729Y1161660D02*
X240728Y1161667D01*
G01X240730Y1161656D02*
X240729Y1161660D01*
G01X240731Y1161654D02*
X240730Y1161656D01*
G01X240729Y1166660D02*
X240728Y1166667D01*
G01X240730Y1166656D02*
X240729Y1166660D01*
G01X240731Y1166654D02*
X240730Y1166656D01*
G01X240729Y1171660D02*
X240728Y1171667D01*
G01X240730Y1171656D02*
X240729Y1171660D01*
G01X240731Y1171654D02*
X240730Y1171656D01*
G01X240729Y1176660D02*
X240728Y1176667D01*
G01X240730Y1176656D02*
X240729Y1176660D01*
G01X240731Y1176654D02*
X240730Y1176656D01*
G01X240716Y1131685D02*
X240727Y1131669D01*
G01X240691Y1131693D02*
X240716Y1131685D01*
G01Y1136685D02*
X240727Y1136669D01*
G01X240691Y1136693D02*
X240716Y1136685D01*
G01Y1141685D02*
X240727Y1141669D01*
G01X240691Y1141693D02*
X240716Y1141685D01*
G01Y1146685D02*
X240727Y1146669D01*
G01X240691Y1146693D02*
X240716Y1146685D01*
G01Y1151685D02*
X240727Y1151669D01*
G01X240691Y1151693D02*
X240716Y1151685D01*
G01Y1156685D02*
X240727Y1156669D01*
G01X240691Y1156693D02*
X240716Y1156685D01*
G01Y1161685D02*
X240727Y1161669D01*
G01X240691Y1161693D02*
X240716Y1161685D01*
G01Y1166685D02*
X240727Y1166669D01*
G01X240691Y1166693D02*
X240716Y1166685D01*
G01Y1171685D02*
X240727Y1171669D01*
G01X240691Y1171693D02*
X240716Y1171685D01*
G01Y1176685D02*
X240727Y1176669D01*
G01X240691Y1176693D02*
X240716Y1176685D01*
G01X240728Y1177185D02*
X239744D01*
G01X239746Y1176693D02*
X245079D01*
G01Y1176654D02*
X240731D01*
G01X245079Y1175315D02*
X239746D01*
G01X239744Y1174823D02*
X240728D01*
G01Y1172185D02*
X239744D01*
G01X239746Y1171693D02*
X245079D01*
G01Y1171654D02*
X240731D01*
G01X245079Y1170315D02*
X239746D01*
G01X239744Y1169823D02*
X240728D01*
G01Y1167185D02*
X239744D01*
G01X239746Y1166693D02*
X245079D01*
G01Y1166654D02*
X240731D01*
G01X245079Y1165315D02*
X239746D01*
G01X239744Y1164823D02*
X240728D01*
G01Y1162185D02*
X239744D01*
G01X239746Y1161693D02*
X245079D01*
G01Y1161654D02*
X240731D01*
G01X245079Y1160315D02*
X239746D01*
G01X239744Y1159823D02*
X240728D01*
G01Y1157185D02*
X239744D01*
G01X239746Y1156693D02*
X245079D01*
G01Y1156654D02*
X240731D01*
G01X245079Y1155315D02*
X239746D01*
G01X239744Y1154823D02*
X240728D01*
G01X239744Y1176889D02*
X240699Y1176890D01*
G01X240728Y1175119D02*
X239744Y1175118D01*
G01Y1171889D02*
X240699Y1171890D01*
G01X240728Y1170119D02*
X239744Y1170118D01*
G01Y1166889D02*
X240699Y1166890D01*
G01X240728Y1165119D02*
X239744Y1165118D01*
G01Y1161889D02*
X240699Y1161890D01*
G01X240728Y1160119D02*
X239744Y1160118D01*
G01Y1156889D02*
X240699Y1156890D01*
G01X240728Y1155119D02*
X239744Y1155118D01*
G01X240728Y1152185D02*
X239744D01*
G01X239746Y1151693D02*
X245079D01*
G01Y1151654D02*
X240731D01*
G01X245079Y1150315D02*
X239746D01*
G01X239744Y1149823D02*
X240728D01*
G01Y1147185D02*
X239744D01*
G01X239746Y1146693D02*
X245079D01*
G01Y1146654D02*
X240731D01*
G01X245079Y1145315D02*
X239746D01*
G01X239744Y1144823D02*
X240728D01*
G01Y1142185D02*
X239744D01*
G01X239746Y1141693D02*
X245079D01*
G01Y1141654D02*
X240731D01*
G01X245079Y1140315D02*
X239746D01*
G01X239744Y1139823D02*
X240728D01*
G01Y1137185D02*
X239744D01*
G01X239746Y1136693D02*
X245079D01*
G01Y1136654D02*
X240731D01*
G01X245079Y1135315D02*
X239746D01*
G01X239744Y1134823D02*
X240728D01*
G01Y1132185D02*
X239744D01*
G01X239746Y1131693D02*
X245079D01*
G01Y1131654D02*
X240731D01*
G01X239744Y1151889D02*
X240699Y1151890D01*
G01X240728Y1150119D02*
X239744Y1150118D01*
G01Y1146889D02*
X240699Y1146890D01*
G01X240728Y1145119D02*
X239744Y1145118D01*
G01Y1141889D02*
X240699Y1141890D01*
G01X240728Y1140119D02*
X239744Y1140118D01*
G01Y1136889D02*
X240699Y1136890D01*
G01X240728Y1135119D02*
X239744Y1135118D01*
G01Y1131889D02*
X240699Y1131890D01*
G01X240728Y1131667D02*
X240729Y1131676D01*
G01X240728Y1136667D02*
X240729Y1136676D01*
G01X240728Y1141667D02*
X240729Y1141676D01*
G01X240728Y1146667D02*
X240729Y1146676D01*
G01X240728Y1151667D02*
X240729Y1151676D01*
G01X240728Y1156667D02*
X240729Y1156676D01*
G01X240728Y1161667D02*
X240729Y1161676D01*
G01X240728Y1166667D02*
X240729Y1166676D01*
G01X240728Y1171667D02*
X240729Y1171676D01*
G01X240728Y1176667D02*
X240729Y1176676D01*
G01X245079Y1175315D02*
Y1176693D01*
G01Y1170315D02*
Y1171693D01*
G01Y1165315D02*
Y1166693D01*
G01Y1160315D02*
Y1161693D01*
G01Y1155315D02*
Y1156693D01*
G01Y1150315D02*
Y1151693D01*
G01Y1145315D02*
Y1146693D01*
G01Y1140315D02*
Y1141693D01*
G01Y1135315D02*
Y1136693D01*
G01X241909D02*
Y1135315D01*
G01Y1141693D02*
Y1140315D01*
G01Y1146693D02*
Y1145315D01*
G01Y1151693D02*
Y1150315D01*
G01Y1156693D02*
Y1155315D01*
G01Y1161693D02*
Y1160315D01*
G01Y1166693D02*
Y1165315D01*
G01Y1171693D02*
Y1170315D01*
G01Y1176693D02*
Y1175315D01*
G01X240728Y1174823D02*
Y1177185D01*
G01Y1169823D02*
Y1172185D01*
G01Y1164823D02*
Y1167185D01*
G01Y1159823D02*
Y1162185D01*
G01Y1154823D02*
Y1157185D01*
G01Y1149823D02*
Y1152185D01*
G01Y1144823D02*
Y1147185D01*
G01Y1139823D02*
Y1142185D01*
G01Y1134823D02*
Y1137185D01*
G01Y1136667D02*
Y1136811D01*
G01Y1131667D02*
Y1131811D01*
G01Y1146667D02*
Y1146811D01*
G01Y1141667D02*
Y1141811D01*
G01Y1156667D02*
Y1156811D01*
G01Y1151667D02*
Y1151811D01*
G01Y1166667D02*
Y1166811D01*
G01Y1161667D02*
Y1161811D01*
G01Y1176667D02*
Y1176811D01*
G01Y1171667D02*
Y1171811D01*
G01X239744Y1137185D02*
Y1134823D01*
G01Y1142185D02*
Y1139823D01*
G01Y1147185D02*
Y1144823D01*
G01Y1152185D02*
Y1149823D01*
G01Y1157185D02*
Y1154823D01*
G01Y1162185D02*
Y1159823D01*
G01Y1167185D02*
Y1164823D01*
G01Y1172185D02*
Y1169823D01*
G01Y1177185D02*
Y1174823D01*
G01X240729Y1195308D02*
X240728Y1195299D01*
G01X240730Y1195313D02*
X240729Y1195308D01*
G01X240731Y1195315D02*
X240730Y1195313D01*
G01X240729Y1190308D02*
X240728Y1190299D01*
G01X240730Y1190313D02*
X240729Y1190308D01*
G01X240731Y1190315D02*
X240730Y1190313D01*
G01X240729Y1185308D02*
X240728Y1185299D01*
G01X240730Y1185313D02*
X240729Y1185308D01*
G01X240731Y1185315D02*
X240730Y1185313D01*
G01X240729Y1180308D02*
X240728Y1180299D01*
G01X240730Y1180313D02*
X240729Y1180308D01*
G01X240731Y1180315D02*
X240730Y1180313D01*
G01X239745Y1195313D02*
X239746Y1195315D01*
G01X239744Y1195308D02*
X239745Y1195313D01*
G01X239744Y1195299D02*
Y1195308D01*
G01X239745Y1190313D02*
X239746Y1190315D01*
G01X239744Y1190308D02*
X239745Y1190313D01*
G01X239744Y1190299D02*
Y1190308D01*
G01X239745Y1185313D02*
X239746Y1185315D01*
G01X239744Y1185308D02*
X239745Y1185313D01*
G01X239744Y1185299D02*
Y1185308D01*
G01X239745Y1180313D02*
X239746Y1180315D01*
G01X239744Y1180308D02*
X239745Y1180313D01*
G01X239744Y1180299D02*
Y1180308D01*
G01X240695Y1181791D02*
X240699Y1181890D01*
G01X240690Y1181719D02*
X240695Y1181791D01*
G01X240692Y1181693D02*
X240690Y1181719D01*
G01X240695Y1186791D02*
X240699Y1186890D01*
G01X240690Y1186719D02*
X240695Y1186791D01*
G01X240692Y1186693D02*
X240690Y1186719D01*
G01X240695Y1191791D02*
X240699Y1191890D01*
G01X240690Y1191719D02*
X240695Y1191791D01*
G01X240692Y1191693D02*
X240690Y1191719D01*
G01X240695Y1196791D02*
X240699Y1196890D01*
G01X240690Y1196719D02*
X240695Y1196791D01*
G01X240692Y1196693D02*
X240690Y1196719D01*
G01X240711Y1181688D02*
X240692Y1181693D01*
G01X240726Y1181674D02*
X240711Y1181688D01*
G01X240731Y1181654D02*
X240726Y1181674D01*
G01X240711Y1186688D02*
X240692Y1186693D01*
G01X240726Y1186674D02*
X240711Y1186688D01*
G01X240731Y1186654D02*
X240726Y1186674D01*
G01X240711Y1191688D02*
X240692Y1191693D01*
G01X240726Y1191674D02*
X240711Y1191688D01*
G01X240731Y1191654D02*
X240726Y1191674D01*
G01X240711Y1196688D02*
X240692Y1196693D01*
G01X240726Y1196674D02*
X240711Y1196688D01*
G01X240731Y1196654D02*
X240726Y1196674D01*
G01X239744Y1181700D02*
Y1181709D01*
G01X239745Y1181695D02*
X239744Y1181700D01*
G01X239746Y1181693D02*
X239745Y1181695D01*
G01X239744Y1186700D02*
Y1186709D01*
G01X239745Y1186695D02*
X239744Y1186700D01*
G01X239746Y1186693D02*
X239745Y1186695D01*
G01X239744Y1191700D02*
Y1191709D01*
G01X239745Y1191695D02*
X239744Y1191700D01*
G01X239746Y1191693D02*
X239745Y1191695D01*
G01X239744Y1196700D02*
Y1196709D01*
G01X239745Y1196695D02*
X239744Y1196700D01*
G01X239746Y1196693D02*
X239745Y1196695D01*
G01X240720Y1181837D02*
X240728Y1181811D01*
G01X240711Y1181863D02*
X240720Y1181837D01*
G01X240699Y1181890D02*
X240711Y1181863D01*
G01X240720Y1186837D02*
X240728Y1186811D01*
G01X240711Y1186863D02*
X240720Y1186837D01*
G01X240699Y1186890D02*
X240711Y1186863D01*
G01X240720Y1191837D02*
X240728Y1191811D01*
G01X240711Y1191863D02*
X240720Y1191837D01*
G01X240699Y1191890D02*
X240711Y1191863D01*
G01X240720Y1196837D02*
X240728Y1196811D01*
G01X240711Y1196863D02*
X240720Y1196837D01*
G01X240699Y1196890D02*
X240711Y1196863D01*
G01X240729Y1181660D02*
X240728Y1181667D01*
G01X240730Y1181656D02*
X240729Y1181660D01*
G01X240731Y1181654D02*
X240730Y1181656D01*
G01X240729Y1186660D02*
X240728Y1186667D01*
G01X240730Y1186656D02*
X240729Y1186660D01*
G01X240731Y1186654D02*
X240730Y1186656D01*
G01X240729Y1191660D02*
X240728Y1191667D01*
G01X240730Y1191656D02*
X240729Y1191660D01*
G01X240731Y1191654D02*
X240730Y1191656D01*
G01X240729Y1196660D02*
X240728Y1196667D01*
G01X240730Y1196656D02*
X240729Y1196660D01*
G01X240731Y1196654D02*
X240730Y1196656D01*
G01X240716Y1181685D02*
X240727Y1181669D01*
G01X240691Y1181693D02*
X240716Y1181685D01*
G01Y1186685D02*
X240727Y1186669D01*
G01X240691Y1186693D02*
X240716Y1186685D01*
G01Y1191685D02*
X240727Y1191669D01*
G01X240691Y1191693D02*
X240716Y1191685D01*
G01Y1196685D02*
X240727Y1196669D01*
G01X240691Y1196693D02*
X240716Y1196685D01*
G01X246063Y1221594D02*
G03X244094Y1223563I-1968J1D01*
G01X239173Y1222185D02*
G03X238583Y1222776I-591J0D01*
G01X231890D02*
G03X231299Y1222185I0J-591D01*
G01X234055Y1221004D02*
G03Y1219035I0J-985D01*
G01X236417D02*
G03Y1221004I0J985D01*
G01X226378Y1223563D02*
G03X224409Y1221594I0J-1969D01*
G01X232677Y1213091D02*
G03X231496Y1211909I0J-1181D01*
G01X238976D02*
G03X237795Y1213091I-1181J1D01*
G01X237126Y1207815D02*
G03I-1890J0D01*
G01X237598D02*
G03I-2362J0D01*
G01X244094Y1223563D02*
X226378D01*
G01X238583Y1222776D02*
X231890D01*
G01X236417Y1221004D02*
X234055D01*
G01Y1219035D02*
X236417D01*
G01X239173Y1217657D02*
X231299D01*
G01Y1216083D02*
X239173D01*
G01X246063Y1213130D02*
X224409D01*
G01X232677Y1213091D02*
X237795D01*
G01X234055Y1208406D02*
X236417D01*
G01X234055Y1206713D02*
X236417D01*
G01X227756Y1204744D02*
X242126D01*
G01X227756Y1203366D02*
X231496D01*
G01X242126D02*
X238976D01*
G01X227756Y1202500D02*
X242717D01*
G01X229528Y1201004D02*
X237402D01*
G01X230709Y1199823D02*
X236220D01*
G01X240728Y1197185D02*
X239744D01*
G01X239746Y1196693D02*
X245079D01*
G01Y1196654D02*
X240731D01*
G01X245079Y1195315D02*
X239746D01*
G01X239744Y1194823D02*
X240728D01*
G01Y1192185D02*
X239744D01*
G01X239746Y1191693D02*
X245079D01*
G01Y1191654D02*
X240731D01*
G01X245079Y1190315D02*
X239746D01*
G01X239744Y1189823D02*
X240728D01*
G01Y1187185D02*
X239744D01*
G01X239746Y1186693D02*
X245079D01*
G01Y1186654D02*
X240731D01*
G01X245079Y1185315D02*
X239746D01*
G01X239744Y1184823D02*
X240728D01*
G01Y1182185D02*
X239744D01*
G01X239746Y1181693D02*
X245079D01*
G01Y1181654D02*
X240731D01*
G01X245079Y1180315D02*
X239746D01*
G01X239744Y1179823D02*
X240728D01*
G01X239744Y1196889D02*
X240699Y1196890D01*
G01X240728Y1195119D02*
X239744Y1195118D01*
G01Y1191889D02*
X240699Y1191890D01*
G01X240728Y1190119D02*
X239744Y1190118D01*
G01Y1186889D02*
X240699Y1186890D01*
G01X240728Y1185119D02*
X239744Y1185118D01*
G01Y1181889D02*
X240699Y1181890D01*
G01X240728Y1180119D02*
X239744Y1180118D01*
G01X229528Y1201004D02*
X230709Y1199823D01*
G01X224409Y1205846D02*
X227756Y1202500D01*
G01X236417Y1206713D02*
X237721Y1204744D01*
G01X234055Y1208406D02*
X231745Y1212635D01*
G01X240728Y1181667D02*
X240729Y1181676D01*
G01X240728Y1186667D02*
X240729Y1186676D01*
G01X240728Y1191667D02*
X240729Y1191676D01*
G01X240728Y1196667D02*
X240729Y1196676D01*
G01X246063Y1205846D02*
Y1221594D01*
G01X245079Y1195315D02*
Y1196693D01*
G01Y1190315D02*
Y1191693D01*
G01Y1185315D02*
Y1186693D01*
G01Y1180315D02*
Y1181693D01*
G01X241909D02*
Y1180315D01*
G01Y1186693D02*
Y1185315D01*
G01Y1191693D02*
Y1190315D01*
G01Y1196693D02*
Y1195315D01*
G01X240728Y1194823D02*
Y1197185D01*
G01Y1189823D02*
Y1192185D01*
G01Y1184823D02*
Y1187185D01*
G01Y1179823D02*
Y1182185D01*
G01Y1186667D02*
Y1186811D01*
G01Y1181667D02*
Y1181811D01*
G01Y1196667D02*
Y1196811D01*
G01Y1191667D02*
Y1191811D01*
G01X239744Y1182185D02*
Y1179823D01*
G01Y1187185D02*
Y1184823D01*
G01Y1192185D02*
Y1189823D01*
G01Y1197185D02*
Y1194823D01*
G01X239173Y1216083D02*
Y1222185D01*
G01X238976Y1211909D02*
Y1203366D01*
G01X236417Y1208406D02*
Y1206713D01*
G01X234055D02*
Y1208406D01*
G01X231496Y1203366D02*
Y1211909D01*
G01X231299Y1216083D02*
Y1222185D01*
G01X224409Y1221594D02*
Y1205846D01*
G01X246063D02*
X242717Y1202500D01*
G01X236220Y1199823D02*
X237402Y1201004D01*
G01X232752Y1204744D02*
X234055Y1206713D01*
G01X238728Y1212635D02*
X236417Y1208406D01*
G01X320567Y-335933D02*
Y-354870D01*
G01X362598Y0D02*
G03Y-7874I0J-3937D01*
G01X323228D02*
G03Y0I0J3937D01*
G01X362598D02*
G03Y-7874I0J-3937D01*
G01X323228D02*
G03Y0I0J3937D01*
G01X355512Y139311D02*
G03X356102Y138720I591J0D01*
G01X360630Y140492D02*
G03Y142461I0J984D01*
G01X358268D02*
G03Y140492I0J-984D01*
G01X360551Y153681D02*
G03I-1102J0D01*
G01X362008Y148406D02*
G03X363189Y149587I0J1181D01*
G01X355709D02*
G03X356890Y148406I1181J0D01*
G01X361024Y153681D02*
G03I-1575J0D01*
G01X348622Y139902D02*
G03X350591Y137933I1969J0D01*
G01X354921Y161673D02*
X353740Y160492D01*
G01X351969Y158996D02*
X348622Y155650D01*
G01X361933Y156752D02*
X360630Y154783D01*
G01X355957Y148861D02*
X358268Y153091D01*
G01X361614Y196949D02*
Y160492D01*
G01X360630Y154783D02*
Y153091D01*
G01X360433Y198130D02*
Y161673D01*
G01X358268Y153091D02*
Y154783D01*
G01X355709Y149587D02*
Y158130D01*
G01X355512Y145413D02*
Y139311D01*
G01X354921Y161673D02*
Y294311D01*
G01X353740Y160492D02*
Y295492D01*
G01X351969Y195787D02*
Y156752D01*
G01X360433Y161673D02*
X354921D01*
G01X361614Y160492D02*
X353740D01*
G01X366929Y158996D02*
X351969D01*
G01X355709Y158130D02*
X351969D01*
G01Y156752D02*
X366339D01*
G01X360630Y154783D02*
X358268D01*
G01X360630Y153091D02*
X358268D01*
G01X362008Y148406D02*
X356890D01*
G01X370276Y148366D02*
X348622D01*
G01X363386Y145413D02*
X355512D01*
G01Y143839D02*
X363386D01*
G01X360630Y142461D02*
X358268D01*
G01Y140492D02*
X360630D01*
G01X362795Y138720D02*
X356102D01*
G01X368307Y137933D02*
X350591D01*
G01X348622Y155650D02*
Y139902D01*
G01X360630Y153091D02*
X362940Y148861D01*
G01X358268Y154783D02*
X356964Y156752D01*
G01X360433Y161673D02*
X361614Y160492D01*
G01X351484Y205432D02*
X351475Y205433D01*
G01X351493Y205429D02*
X351484Y205432D01*
G01X351501Y205424D02*
X351493Y205429D01*
G01X351484Y199133D02*
X351475Y199134D01*
G01X351493Y199130D02*
X351484Y199133D01*
G01X351501Y199124D02*
X351493Y199130D01*
G01X351484Y202282D02*
X351475Y202283D01*
G01X351493Y202279D02*
X351484Y202282D01*
G01X351501Y202274D02*
X351493Y202279D01*
G01X351484Y208581D02*
X351475Y208583D01*
G01X351493Y208578D02*
X351484Y208581D01*
G01X351501Y208573D02*
X351493Y208578D01*
G01X351484Y211731D02*
X351475Y211732D01*
G01X351493Y211728D02*
X351484Y211731D01*
G01X351501Y211723D02*
X351493Y211728D01*
G01X350570Y197948D02*
X350571Y197942D01*
G01X350570Y197952D02*
Y197948D01*
G01X350569Y197953D02*
X350570Y197952D01*
G01Y201098D02*
X350571Y201091D01*
G01X350570Y201101D02*
Y201098D01*
G01X350569Y201102D02*
X350570Y201101D01*
G01Y204247D02*
X350571Y204241D01*
G01X350570Y204251D02*
Y204247D01*
G01X350569Y204252D02*
X350570Y204251D01*
G01Y207397D02*
X350571Y207391D01*
G01X350570Y207400D02*
Y207397D01*
G01X350569Y207402D02*
X350570Y207400D01*
G01Y210546D02*
X350571Y210540D01*
G01X350570Y210550D02*
Y210546D01*
G01X350569Y210551D02*
X350570Y210550D01*
G01X350554Y201105D02*
X350569Y201102D01*
G01X350543Y201112D02*
X350554Y201105D01*
G01X350531Y201131D02*
X350543Y201112D01*
G01X350554Y210554D02*
X350569Y210551D01*
G01X350543Y210561D02*
X350554Y210554D01*
G01X350531Y210580D02*
X350543Y210561D01*
G01X350554Y204255D02*
X350569Y204252D01*
G01X350542Y204263D02*
X350554Y204255D01*
G01X350530Y204283D02*
X350542Y204263D01*
G01X351516Y197986D02*
Y197979D01*
G01X351515Y197991D02*
X351516Y197986D01*
G01X351514Y197992D02*
X351515Y197991D01*
G01X351516Y201136D02*
Y201128D01*
G01X351515Y201141D02*
X351516Y201136D01*
G01X351514Y201142D02*
X351515Y201141D01*
G01X351516Y204285D02*
Y204278D01*
G01X351515Y204290D02*
X351516Y204285D01*
G01X351514Y204291D02*
X351515Y204290D01*
G01X351516Y207435D02*
Y207428D01*
G01X351515Y207440D02*
X351516Y207435D01*
G01X351514Y207441D02*
X351515Y207440D01*
G01X351516Y210585D02*
Y210577D01*
G01X351515Y210589D02*
X351516Y210585D01*
G01X351514Y210591D02*
X351515Y210589D01*
G01X350554Y197956D02*
X350569Y197953D01*
G01X350541Y197964D02*
X350554Y197956D01*
G01X350530Y197985D02*
X350541Y197964D01*
G01X351515Y199115D02*
X351516Y199108D01*
G01X351513Y199121D02*
X351515Y199115D01*
G01X351510Y199127D02*
X351513Y199121D01*
G01X351515Y202265D02*
X351516Y202258D01*
G01X351513Y202271D02*
X351515Y202265D01*
G01X351510Y202277D02*
X351513Y202271D01*
G01X351515Y205414D02*
X351516Y205407D01*
G01X351513Y205420D02*
X351515Y205414D01*
G01X351510Y205426D02*
X351513Y205420D01*
G01X351515Y208564D02*
X351516Y208557D01*
G01X351513Y208570D02*
X351515Y208564D01*
G01X351510Y208576D02*
X351513Y208570D01*
G01X351515Y211713D02*
X351516Y211707D01*
G01X351513Y211720D02*
X351515Y211713D01*
G01X351510Y211726D02*
X351513Y211720D01*
G01X351477Y197948D02*
Y197942D01*
G01X351476Y197952D02*
X351477Y197948D01*
G01X351475Y197953D02*
X351476Y197952D01*
G01X351477Y201097D02*
Y201091D01*
G01X351476Y201101D02*
X351477Y201097D01*
G01X351475Y201102D02*
X351476Y201101D01*
G01X351477Y204247D02*
Y204241D01*
G01X351476Y204251D02*
X351477Y204247D01*
G01X351475Y204252D02*
X351476Y204251D01*
G01X351477Y207396D02*
Y207391D01*
G01X351476Y207400D02*
X351477Y207396D01*
G01X351475Y207402D02*
X351476Y207400D01*
G01X351477Y210546D02*
Y210540D01*
G01X351476Y210550D02*
X351477Y210546D01*
G01X351475Y210551D02*
X351476Y210550D01*
G01X350531Y201132D02*
Y201128D01*
G01X350533Y201126D02*
X350531Y201132D01*
G01X350545Y201111D02*
X350533Y201126D01*
G01X350570Y201102D02*
X350545Y201111D01*
G01X350531Y204282D02*
Y204278D01*
G01X350533Y204276D02*
X350531Y204282D01*
G01X350544Y204260D02*
X350533Y204276D01*
G01X350569Y204252D02*
X350544Y204260D01*
G01X350531Y210581D02*
Y210577D01*
G01X350533Y210575D02*
X350531Y210581D01*
G01X350544Y210559D02*
X350533Y210575D01*
G01X350569Y210551D02*
X350544Y210559D01*
G01X350531Y197983D02*
Y197979D01*
G01X350533Y197976D02*
X350531Y197983D01*
G01X350544Y197961D02*
X350533Y197976D01*
G01X350569Y197953D02*
X350544Y197961D01*
G01X350531Y207431D02*
Y207428D01*
G01X350533Y207426D02*
X350531Y207431D01*
G01X350543Y207411D02*
X350533Y207426D01*
G01X350566Y207402D02*
X350543Y207411D01*
G01X350549Y207407D02*
X350569Y207402D01*
G01X350536Y207419D02*
X350549Y207407D01*
G01X350529Y207437D02*
X350536Y207419D01*
G01X350531Y210585D02*
Y210577D01*
G01X350530Y210589D02*
X350531Y210585D01*
G01Y210580D02*
X350530Y210589D01*
G01X351506Y199132D02*
X351510Y199127D01*
G01X351502Y199137D02*
X351506Y199132D01*
G01X351496Y199141D02*
X351502Y199137D01*
G01X351490Y199143D02*
X351496Y199141D01*
G01X351483Y199145D02*
X351490Y199143D01*
G01X351476Y199145D02*
X351483D01*
G01X351506Y202282D02*
X351510Y202277D01*
G01X351502Y202286D02*
X351506Y202282D01*
G01X351496Y202290D02*
X351502Y202286D01*
G01X351490Y202293D02*
X351496Y202290D01*
G01X351483Y202294D02*
X351490Y202293D01*
G01X351476Y202295D02*
X351483Y202294D01*
G01X351506Y205431D02*
X351510Y205426D01*
G01X351502Y205436D02*
X351506Y205431D01*
G01X351496Y205440D02*
X351502Y205436D01*
G01X351490Y205442D02*
X351496Y205440D01*
G01X351483Y205444D02*
X351490Y205442D01*
G01X351476Y205444D02*
X351483D01*
G01X351506Y208581D02*
X351510Y208576D01*
G01X351502Y208585D02*
X351506Y208581D01*
G01X351496Y208589D02*
X351502Y208585D01*
G01X351490Y208592D02*
X351496Y208589D01*
G01X351483Y208594D02*
X351490Y208592D01*
G01X351476Y208594D02*
X351483D01*
G01X351506Y211731D02*
X351510Y211726D01*
G01X351502Y211735D02*
X351506Y211731D01*
G01X351496Y211739D02*
X351502Y211735D01*
G01X351490Y211741D02*
X351496Y211739D01*
G01X351483Y211743D02*
X351490Y211741D01*
G01X351476Y211744D02*
X351483Y211743D01*
G01X350532Y197971D02*
X350531Y197979D01*
G01X350535Y197965D02*
X350532Y197971D01*
G01X350538Y197958D02*
X350535Y197965D01*
G01X350543Y197952D02*
X350538Y197958D01*
G01X350549Y197948D02*
X350543Y197952D01*
G01X350556Y197944D02*
X350549Y197948D01*
G01X350563Y197943D02*
X350556Y197944D01*
G01X350571Y197942D02*
X350563Y197943D01*
G01X350532Y201121D02*
X350531Y201128D01*
G01X350535Y201114D02*
X350532Y201121D01*
G01X350538Y201108D02*
X350535Y201114D01*
G01X350543Y201102D02*
X350538Y201108D01*
G01X350549Y201097D02*
X350543Y201102D01*
G01X350556Y201094D02*
X350549Y201097D01*
G01X350563Y201092D02*
X350556Y201094D01*
G01X350571Y201091D02*
X350563Y201092D01*
G01X350532Y204270D02*
X350531Y204278D01*
G01X350535Y204264D02*
X350532Y204270D01*
G01X350538Y204257D02*
X350535Y204264D01*
G01X350543Y204252D02*
X350538Y204257D01*
G01X350549Y204247D02*
X350543Y204252D01*
G01X350556Y204244D02*
X350549Y204247D01*
G01X350563Y204242D02*
X350556Y204244D01*
G01X350571Y204241D02*
X350563Y204242D01*
G01X350532Y207420D02*
X350531Y207428D01*
G01X350535Y207413D02*
X350532Y207420D01*
G01X350538Y207407D02*
X350535Y207413D01*
G01X350543Y207401D02*
X350538Y207407D01*
G01X350549Y207396D02*
X350543Y207401D01*
G01X350556Y207393D02*
X350549Y207396D01*
G01X350563Y207391D02*
X350556Y207393D01*
G01X350571Y207391D02*
X350563D01*
G01X350532Y210570D02*
X350531Y210577D01*
G01X350535Y210563D02*
X350532Y210570D01*
G01X350538Y210557D02*
X350535Y210563D01*
G01X350543Y210551D02*
X350538Y210557D01*
G01X350549Y210546D02*
X350543Y210551D01*
G01X350556Y210543D02*
X350549Y210546D01*
G01X350563Y210541D02*
X350556Y210543D01*
G01X350571Y210540D02*
X350563Y210541D01*
G01X351485Y199133D02*
X351495Y199128D01*
G01X351475Y199134D02*
X351485Y199133D01*
G01Y202282D02*
X351495Y202278D01*
G01X351475Y202283D02*
X351485Y202282D01*
G01Y205432D02*
X351495Y205428D01*
G01X351475Y205433D02*
X351485Y205432D01*
G01Y208581D02*
X351495Y208577D01*
G01X351475Y208583D02*
X351485Y208581D01*
G01Y211731D02*
X351495Y211727D01*
G01X351475Y211732D02*
X351485Y211731D01*
G01X351508Y205415D02*
X351501Y205424D01*
G01X351513Y205405D02*
X351508Y205415D01*
G01X351515Y205394D02*
X351513Y205405D01*
G01X351508Y199116D02*
X351501Y199124D01*
G01X351513Y199106D02*
X351508Y199116D01*
G01X351515Y199094D02*
X351513Y199106D01*
G01X351508Y202265D02*
X351501Y202274D01*
G01X351513Y202255D02*
X351508Y202265D01*
G01X351515Y202244D02*
X351513Y202255D01*
G01X351508Y208565D02*
X351501Y208573D01*
G01X351513Y208554D02*
X351508Y208565D01*
G01X351515Y208543D02*
X351513Y208554D01*
G01X351508Y211714D02*
X351501Y211723D01*
G01X351513Y211704D02*
X351508Y211714D01*
G01X351515Y211693D02*
X351513Y211704D01*
G01X350572Y211917D02*
X350571Y211929D01*
G01X350569Y211904D02*
X350572Y211917D01*
G01X350569Y211890D02*
Y211904D01*
G01X350572Y208767D02*
X350571Y208780D01*
G01X350569Y208754D02*
X350572Y208767D01*
G01X350569Y208741D02*
Y208754D01*
G01X350572Y205618D02*
X350571Y205630D01*
G01X350569Y205605D02*
X350572Y205618D01*
G01X350569Y205591D02*
Y205605D01*
G01X350572Y202468D02*
X350571Y202480D01*
G01X350569Y202455D02*
X350572Y202468D01*
G01X350569Y202441D02*
Y202455D01*
G01X350572Y199319D02*
X350571Y199331D01*
G01X350569Y199306D02*
X350572Y199319D01*
G01X350569Y199292D02*
Y199306D01*
G01Y210380D02*
X350567Y210393D01*
G01X350572Y210367D02*
X350569Y210380D01*
G01X350571Y210354D02*
X350572Y210367D01*
G01X350569Y207230D02*
X350567Y207244D01*
G01X350572Y207217D02*
X350569Y207230D01*
G01X350571Y207205D02*
X350572Y207217D01*
G01X350569Y204081D02*
X350567Y204094D01*
G01X350572Y204068D02*
X350569Y204081D01*
G01X350571Y204055D02*
X350572Y204068D01*
G01X350569Y200931D02*
X350567Y200944D01*
G01X350572Y200918D02*
X350569Y200931D01*
G01X350571Y200906D02*
X350572Y200918D01*
G01X350569Y197781D02*
X350567Y197795D01*
G01X350572Y197769D02*
X350569Y197781D01*
G01X350571Y197756D02*
X350572Y197769D01*
G01X351479Y211904D02*
X351480Y211890D01*
G01X351476Y211917D02*
X351479Y211904D01*
G01X351476Y211929D02*
Y211917D01*
G01X351479Y208754D02*
X351480Y208741D01*
G01X351476Y208767D02*
X351479Y208754D01*
G01X351476Y208780D02*
Y208767D01*
G01X351479Y205604D02*
X351480Y205591D01*
G01X351476Y205617D02*
X351479Y205604D01*
G01X351476Y205630D02*
Y205617D01*
G01X351479Y202455D02*
X351480Y202441D01*
G01X351476Y202468D02*
X351479Y202455D01*
G01X351476Y202480D02*
Y202468D01*
G01X351479Y199305D02*
X351480Y199292D01*
G01X351476Y199318D02*
X351479Y199305D01*
G01X351476Y199331D02*
Y199318D01*
G01X350531Y204285D02*
Y204278D01*
G01X350530Y204290D02*
X350531Y204285D01*
G01X350530Y204283D02*
Y204290D01*
G01X351476Y210367D02*
Y210354D01*
G01X351478Y210380D02*
X351476Y210367D01*
G01X351480Y210393D02*
X351478Y210380D01*
G01X351476Y207217D02*
Y207205D01*
G01X351478Y207230D02*
X351476Y207217D01*
G01X351480Y207244D02*
X351478Y207230D01*
G01X351476Y204068D02*
Y204055D01*
G01X351478Y204081D02*
X351476Y204068D01*
G01X351480Y204094D02*
X351478Y204081D01*
G01X351476Y200918D02*
Y200906D01*
G01X351478Y200931D02*
X351476Y200918D01*
G01X351480Y200944D02*
X351478Y200931D01*
G01X351476Y197769D02*
Y197756D01*
G01X351478Y197781D02*
X351476Y197769D01*
G01X351480Y197795D02*
X351478Y197781D01*
G01X350531Y197987D02*
Y197979D01*
G01X350530Y197991D02*
X350531Y197987D01*
G01X350530Y197985D02*
Y197991D01*
G01X351493Y197945D02*
X351496Y197947D01*
G01X351490Y197944D02*
X351493Y197945D01*
G01X351487Y197943D02*
X351490Y197944D01*
G01X351483Y197942D02*
X351487Y197943D01*
G01X351480Y197942D02*
X351483D01*
G01X351476D02*
X351480D01*
G01X350554Y199142D02*
X350551Y199140D01*
G01X350557Y199143D02*
X350554Y199142D01*
G01X350560Y199144D02*
X350557Y199143D01*
G01X350564Y199144D02*
X350560D01*
G01X350567Y199145D02*
X350564Y199144D01*
G01X350571Y199145D02*
X350567D01*
G01X351493Y201095D02*
X351496Y201096D01*
G01X351490Y201094D02*
X351493Y201095D01*
G01X351487Y201093D02*
X351490Y201094D01*
G01X351483Y201092D02*
X351487Y201093D01*
G01X351480Y201091D02*
X351483Y201092D01*
G01X351476Y201091D02*
X351480D01*
G01X350554Y202291D02*
X350551Y202290D01*
G01X350557Y202293D02*
X350554Y202291D01*
G01X350560Y202294D02*
X350557Y202293D01*
G01X350564Y202294D02*
X350560D01*
G01X350567Y202295D02*
X350564Y202294D01*
G01X350571Y202295D02*
X350567D01*
G01X351493Y204244D02*
X351496Y204246D01*
G01X351490Y204243D02*
X351493Y204244D01*
G01X351487Y204242D02*
X351490Y204243D01*
G01X351483Y204241D02*
X351487Y204242D01*
G01X351480Y204241D02*
X351483D01*
G01X351476D02*
X351480D01*
G01X350554Y205441D02*
X350551Y205439D01*
G01X350557Y205442D02*
X350554Y205441D01*
G01X350560Y205443D02*
X350557Y205442D01*
G01X350564Y205444D02*
X350560Y205443D01*
G01X350567Y205444D02*
X350564D01*
G01X350571D02*
X350567D01*
G01X351493Y207394D02*
X351496Y207396D01*
G01X351490Y207393D02*
X351493Y207394D01*
G01X351487Y207392D02*
X351490Y207393D01*
G01X351483Y207391D02*
X351487Y207392D01*
G01X351480Y207391D02*
X351483D01*
G01X351476D02*
X351480D01*
G01X350554Y208591D02*
X350551Y208589D01*
G01X350557Y208592D02*
X350554Y208591D01*
G01X350560Y208593D02*
X350557Y208592D01*
G01X350564Y208593D02*
X350560D01*
G01X350567Y208594D02*
X350564Y208593D01*
G01X350571Y208594D02*
X350567D01*
G01X351493Y210544D02*
X351496Y210545D01*
G01X351490Y210543D02*
X351493Y210544D01*
G01X351487Y210541D02*
X351490Y210543D01*
G01X351483Y210541D02*
X351487D01*
G01X351480Y210540D02*
X351483Y210541D01*
G01X351476Y210540D02*
X351480D01*
G01X350554Y211740D02*
X350551Y211739D01*
G01X350557Y211741D02*
X350554Y211740D01*
G01X350560Y211743D02*
X350557Y211741D01*
G01X350564Y211743D02*
X350560D01*
G01X350567Y211744D02*
X350564Y211743D01*
G01X350571Y211744D02*
X350567D01*
G01X349784Y201142D02*
X349350D01*
G01X350158D02*
X349784D01*
G01Y207441D02*
X349350D01*
G01X350158D02*
X349784D01*
G01Y210591D02*
X349350D01*
G01X350157D02*
X349784D01*
G01X350544Y211724D02*
X350569Y211732D01*
G01X350533Y211709D02*
X350544Y211724D01*
G01X350531Y211703D02*
X350533Y211709D01*
G01X350544Y208574D02*
X350569Y208583D01*
G01X350533Y208560D02*
X350544Y208574D01*
G01X350531Y208553D02*
X350533Y208560D01*
G01X350544Y205425D02*
X350569Y205433D01*
G01X350533Y205410D02*
X350544Y205425D01*
G01X350531Y205404D02*
X350533Y205410D01*
G01X350544Y202275D02*
X350569Y202283D01*
G01X350533Y202261D02*
X350544Y202275D01*
G01X350531Y202254D02*
X350533Y202261D01*
G01X350544Y199126D02*
X350569Y199134D01*
G01X350533Y199111D02*
X350544Y199126D01*
G01X350531Y199104D02*
X350533Y199111D01*
G01X350534Y199114D02*
X350529Y199094D01*
G01X350549Y199129D02*
X350534Y199114D01*
G01X350569Y199134D02*
X350549Y199129D01*
G01X350534Y202264D02*
X350529Y202244D01*
G01X350549Y202278D02*
X350534Y202264D01*
G01X350569Y202283D02*
X350549Y202278D01*
G01X350534Y205413D02*
X350529Y205394D01*
G01X350549Y205428D02*
X350534Y205413D01*
G01X350569Y205433D02*
X350549Y205428D01*
G01X350534Y208563D02*
X350529Y208543D01*
G01X350549Y208578D02*
X350534Y208563D01*
G01X350569Y208583D02*
X350549Y208578D01*
G01X350534Y211713D02*
X350529Y211693D01*
G01X350549Y211727D02*
X350534Y211713D01*
G01X350569Y211732D02*
X350549Y211727D01*
G01X351509Y197972D02*
X351514Y197992D01*
G01X351494Y197958D02*
X351509Y197972D01*
G01X351475Y197953D02*
X351494Y197958D01*
G01X351509Y201122D02*
X351514Y201142D01*
G01X351494Y201108D02*
X351509Y201122D01*
G01X351475Y201102D02*
X351494Y201108D01*
G01X351509Y204272D02*
X351514Y204291D01*
G01X351494Y204257D02*
X351509Y204272D01*
G01X351475Y204252D02*
X351494Y204257D01*
G01X351509Y207421D02*
X351514Y207441D01*
G01X351494Y207407D02*
X351509Y207421D01*
G01X351475Y207402D02*
X351494Y207407D01*
G01X351509Y210571D02*
X351514Y210591D01*
G01X351494Y210557D02*
X351509Y210571D01*
G01X351475Y210551D02*
X351494Y210557D01*
G01X351516Y211699D02*
Y211706D01*
G01X351515Y211695D02*
X351516Y211699D01*
G01X351515Y211693D02*
Y211695D01*
G01X351516Y208550D02*
Y208557D01*
G01X351515Y208545D02*
X351516Y208550D01*
G01X351515Y208543D02*
Y208545D01*
G01X351516Y205400D02*
Y205407D01*
G01X351515Y205396D02*
X351516Y205400D01*
G01X351515Y205394D02*
Y205396D01*
G01X351516Y202250D02*
Y202257D01*
G01X351515Y202246D02*
X351516Y202250D01*
G01X351515Y202244D02*
Y202246D01*
G01X351516Y199101D02*
Y199108D01*
G01X351515Y199096D02*
X351516Y199101D01*
G01X351515Y199094D02*
Y199096D01*
G01X350531Y207435D02*
Y207428D01*
G01X350530Y207440D02*
X350531Y207435D01*
G01X350529Y207437D02*
X350530Y207440D01*
G01X350531Y201136D02*
Y201128D01*
G01X350530Y201141D02*
X350531Y201136D01*
G01X350529Y201138D02*
X350530Y201141D01*
G01X351476Y211737D02*
Y211744D01*
G01Y211734D02*
Y211737D01*
G01X351475Y211732D02*
X351476Y211734D01*
G01Y208588D02*
Y208594D01*
G01Y208584D02*
Y208588D01*
G01X351475Y208583D02*
X351476Y208584D01*
G01Y205438D02*
Y205444D01*
G01Y205435D02*
Y205438D01*
G01X351475Y205433D02*
X351476Y205435D01*
G01Y202289D02*
Y202295D01*
G01Y202285D02*
Y202289D01*
G01X351475Y202283D02*
X351476Y202285D01*
G01Y199139D02*
Y199145D01*
G01Y199135D02*
Y199139D01*
G01X351475Y199134D02*
X351476Y199135D01*
G01X350531Y211699D02*
Y211707D01*
G01X350530Y211694D02*
X350531Y211699D01*
G01X350529Y211693D02*
X350530Y211694D01*
G01X350531Y208550D02*
Y208557D01*
G01X350530Y208545D02*
X350531Y208550D01*
G01X350529Y208543D02*
X350530Y208545D01*
G01X350531Y205400D02*
Y205407D01*
G01X350530Y205395D02*
X350531Y205400D01*
G01X350529Y205394D02*
X350530Y205395D01*
G01X350531Y202250D02*
Y202258D01*
G01X350530Y202246D02*
X350531Y202250D01*
G01X350529Y202244D02*
X350530Y202246D01*
G01X350531Y199101D02*
Y199108D01*
G01X350530Y199096D02*
X350531Y199101D01*
G01X350529Y199094D02*
X350530Y199096D01*
G01X351513Y210565D02*
X351516Y210577D01*
G01X351507Y210554D02*
X351513Y210565D01*
G01X351496Y210545D02*
X351507Y210554D01*
G01X351513Y207415D02*
X351516Y207428D01*
G01X351507Y207404D02*
X351513Y207415D01*
G01X351496Y207396D02*
X351507Y207404D01*
G01X351513Y204265D02*
X351516Y204278D01*
G01X351507Y204254D02*
X351513Y204265D01*
G01X351496Y204246D02*
X351507Y204254D01*
G01X351513Y201116D02*
X351516Y201128D01*
G01X351507Y201105D02*
X351513Y201116D01*
G01X351496Y201096D02*
X351507Y201105D01*
G01X351513Y197966D02*
X351516Y197979D01*
G01X351507Y197955D02*
X351513Y197966D01*
G01X351496Y197947D02*
X351507Y197955D01*
G01X350570Y211737D02*
Y211744D01*
G01Y211733D02*
Y211737D01*
G01X350568Y211732D02*
X350570Y211733D01*
G01Y208588D02*
Y208594D01*
G01Y208584D02*
Y208588D01*
G01X350568Y208583D02*
X350570Y208584D01*
G01Y205438D02*
Y205444D01*
G01Y205434D02*
Y205438D01*
G01X350568Y205433D02*
X350570Y205434D01*
G01Y202289D02*
Y202295D01*
G01Y202285D02*
Y202289D01*
G01X350568Y202283D02*
X350570Y202285D01*
G01Y199139D02*
Y199145D01*
G01Y199135D02*
Y199139D01*
G01X350568Y199134D02*
X350570Y199135D01*
G01X350532Y211713D02*
X350531Y211707D01*
G01X350534Y211719D02*
X350532Y211713D01*
G01X350537Y211725D02*
X350534Y211719D01*
G01X350541Y211730D02*
X350537Y211725D01*
G01X350545Y211735D02*
X350541Y211730D01*
G01X350551Y211739D02*
X350545Y211735D01*
G01X350532Y208563D02*
X350531Y208557D01*
G01X350534Y208570D02*
X350532Y208563D01*
G01X350537Y208575D02*
X350534Y208570D01*
G01X350541Y208581D02*
X350537Y208575D01*
G01X350545Y208585D02*
X350541Y208581D01*
G01X350551Y208589D02*
X350545Y208585D01*
G01X350532Y205414D02*
X350531Y205407D01*
G01X350534Y205420D02*
X350532Y205414D01*
G01X350537Y205426D02*
X350534Y205420D01*
G01X350541Y205431D02*
X350537Y205426D01*
G01X350545Y205435D02*
X350541Y205431D01*
G01X350551Y205439D02*
X350545Y205435D01*
G01X350532Y202264D02*
X350531Y202258D01*
G01X350534Y202270D02*
X350532Y202264D01*
G01X350537Y202276D02*
X350534Y202270D01*
G01X350541Y202281D02*
X350537Y202276D01*
G01X350545Y202286D02*
X350541Y202281D01*
G01X350551Y202290D02*
X350545Y202286D01*
G01X350532Y199115D02*
X350531Y199108D01*
G01X350534Y199121D02*
X350532Y199115D01*
G01X350537Y199126D02*
X350534Y199121D01*
G01X350541Y199132D02*
X350537Y199126D01*
G01X350545Y199136D02*
X350541Y199132D01*
G01X350551Y199140D02*
X350545Y199136D01*
G01X351487Y210553D02*
X351475Y210551D01*
G01X351497Y210558D02*
X351487Y210553D01*
G01Y207404D02*
X351475Y207402D01*
G01X351497Y207409D02*
X351487Y207404D01*
G01Y204254D02*
X351475Y204252D01*
G01X351497Y204259D02*
X351487Y204254D01*
G01Y201104D02*
X351475Y201102D01*
G01X351497Y201109D02*
X351487Y201104D01*
G01Y197955D02*
X351475Y197953D01*
G01X351497Y197960D02*
X351487Y197955D01*
G01X350529Y207437D02*
X350418Y207441D01*
G01X350529Y201138D02*
X350418Y201142D01*
G01X350529Y210587D02*
X350418Y210591D01*
G01X351476Y211929D02*
X350571D01*
G01X351516Y211890D02*
X350531D01*
G01X351475Y211732D02*
X345591D01*
G01Y211693D02*
X351515D01*
G01X351514Y210591D02*
X345591D01*
G01X351475Y210551D02*
X345591D01*
G01X350531Y210394D02*
X351516D01*
G01X350571Y210354D02*
X351476D01*
G01Y208780D02*
X350571D01*
G01X351516Y208740D02*
X350531D01*
G01X351475Y208583D02*
X345591D01*
G01Y208543D02*
X351515D01*
G01X351514Y207441D02*
X345591D01*
G01X351475Y207402D02*
X345591D01*
G01X350531Y207244D02*
X351516D01*
G01X350571Y207205D02*
X351476D01*
G01Y205630D02*
X350571D01*
G01X351516Y205591D02*
X350531D01*
G01X351475Y205433D02*
X345591D01*
G01Y205394D02*
X351515D01*
G01X351514Y204291D02*
X345591D01*
G01X351475Y204252D02*
X345591D01*
G01X350531Y204094D02*
X351516D01*
G01X350571Y204055D02*
X351476D01*
G01Y202480D02*
X350571D01*
G01X351516Y202441D02*
X350531D01*
G01X351475Y202283D02*
X345591D01*
G01Y202244D02*
X351515D01*
G01X351514Y201142D02*
X345591D01*
G01X351475Y201102D02*
X345591D01*
G01X350531Y200945D02*
X351516D01*
G01X350571Y200906D02*
X351476D01*
G01Y199331D02*
X350571D01*
G01X351516Y199291D02*
X350531D01*
G01X351475Y199134D02*
X345591D01*
G01Y199094D02*
X351515D01*
G01X364370Y198130D02*
X360433D01*
G01X351514Y197992D02*
X345591D01*
G01X351475Y197953D02*
X345591D01*
G01X350531Y197795D02*
X351516D01*
G01X350571Y197756D02*
X351476D01*
G01X365551Y196949D02*
X361614D01*
G01X351969Y195787D02*
X348622D01*
G01X351515Y199097D02*
X351516Y199108D01*
G01X351515Y202246D02*
X351516Y202257D01*
G01X351515Y205396D02*
X351516Y205407D01*
G01X351515Y208546D02*
X351516Y208557D01*
G01X351515Y211695D02*
X351516Y211706D01*
G01Y210394D02*
Y211890D01*
G01Y207244D02*
Y208740D01*
G01Y204094D02*
Y205591D01*
G01Y200945D02*
Y202441D01*
G01Y197795D02*
Y199291D01*
G01X351476Y197942D02*
Y197795D01*
G01Y201091D02*
Y200944D01*
G01Y202441D02*
Y202295D01*
G01Y199292D02*
Y199145D01*
G01Y207391D02*
Y207244D01*
G01Y204241D02*
Y204094D01*
G01Y205591D02*
Y205444D01*
G01Y210540D02*
Y210393D01*
G01Y211890D02*
Y211744D01*
G01Y208741D02*
Y208594D01*
G01X350571Y210393D02*
Y210540D01*
G01Y211744D02*
Y211891D01*
G01Y208594D02*
Y208741D01*
G01Y207243D02*
Y207391D01*
G01Y204094D02*
Y204241D01*
G01Y205444D02*
Y205591D01*
G01Y200944D02*
Y201091D01*
G01Y202295D02*
Y202442D01*
G01Y199145D02*
Y199292D01*
G01Y197794D02*
Y197942D01*
G01X350531Y202441D02*
Y200945D01*
G01Y199291D02*
Y197795D01*
G01Y205591D02*
Y204094D01*
G01Y211890D02*
Y210394D01*
G01Y208740D02*
Y207244D01*
G01X349350Y199134D02*
Y197953D01*
G01Y202283D02*
Y201102D01*
G01Y208583D02*
Y207402D01*
G01Y205433D02*
Y204252D01*
G01Y211732D02*
Y210551D01*
G01X349016Y220197D02*
Y195787D01*
G01X348622D02*
Y220197D01*
G01X345591Y210551D02*
Y211732D01*
G01Y207402D02*
Y208583D01*
G01Y204252D02*
Y205433D01*
G01Y201102D02*
Y202283D01*
G01Y197953D02*
Y199134D01*
G01X351516Y210577D02*
X351515Y210588D01*
G01X351516Y207428D02*
X351515Y207439D01*
G01X351516Y204278D02*
X351515Y204289D01*
G01X351516Y201128D02*
X351515Y201139D01*
G01X351516Y197979D02*
X351515Y197990D01*
G01X360433Y198130D02*
X361614Y196949D01*
G01X351484Y214881D02*
X351475Y214882D01*
G01X351493Y214878D02*
X351484Y214881D01*
G01X351501Y214872D02*
X351493Y214878D01*
G01X351484Y218030D02*
X351475Y218031D01*
G01X351493Y218027D02*
X351484Y218030D01*
G01X351501Y218022D02*
X351493Y218027D01*
G01X350570Y213696D02*
X350571Y213690D01*
G01X350570Y213700D02*
Y213696D01*
G01X350569Y213701D02*
X350570Y213700D01*
G01Y216846D02*
X350571Y216839D01*
G01X350570Y216849D02*
Y216846D01*
G01X350569Y216850D02*
X350570Y216849D01*
G01X350554Y213704D02*
X350569Y213701D01*
G01X350542Y213711D02*
X350554Y213704D01*
G01X350530Y213731D02*
X350542Y213711D01*
G01X351516Y213734D02*
Y213727D01*
G01X351515Y213739D02*
X351516Y213734D01*
G01X351514Y213740D02*
X351515Y213739D01*
G01X351516Y216884D02*
Y216876D01*
G01X351515Y216889D02*
X351516Y216884D01*
G01X351514Y216890D02*
X351515Y216889D01*
G01X350554Y216853D02*
X350569Y216850D01*
G01X350541Y216861D02*
X350554Y216853D01*
G01X350530Y216881D02*
X350541Y216861D01*
G01X351515Y214863D02*
X351516Y214856D01*
G01X351513Y214869D02*
X351515Y214863D01*
G01X351510Y214875D02*
X351513Y214869D01*
G01X351515Y218013D02*
X351516Y218006D01*
G01X351513Y218019D02*
X351515Y218013D01*
G01X351510Y218025D02*
X351513Y218019D01*
G01X351477Y216845D02*
Y216839D01*
G01X351476Y216849D02*
X351477Y216845D01*
G01X351475Y216850D02*
X351476Y216849D01*
G01X350531Y213731D02*
Y213727D01*
G01X350533Y213724D02*
X350531Y213731D01*
G01X350544Y213709D02*
X350533Y213724D01*
G01X350569Y213701D02*
X350544Y213709D01*
G01X350531Y216880D02*
Y216876D01*
G01X350533Y216874D02*
X350531Y216880D01*
G01X350544Y216859D02*
X350533Y216874D01*
G01X350569Y216850D02*
X350544Y216859D01*
G01X350532Y213719D02*
X350531Y213727D01*
G01X350535Y213713D02*
X350532Y213719D01*
G01X350538Y213706D02*
X350535Y213713D01*
G01X350543Y213700D02*
X350538Y213706D01*
G01X350549Y213696D02*
X350543Y213700D01*
G01X350556Y213693D02*
X350549Y213696D01*
G01X350563Y213691D02*
X350556Y213693D01*
G01X350571Y213690D02*
X350563Y213691D01*
G01X350532Y216869D02*
X350531Y216876D01*
G01X350535Y216862D02*
X350532Y216869D01*
G01X350538Y216856D02*
X350535Y216862D01*
G01X350543Y216850D02*
X350538Y216856D01*
G01X350549Y216845D02*
X350543Y216850D01*
G01X350556Y216842D02*
X350549Y216845D01*
G01X350563Y216840D02*
X350556Y216842D01*
G01X350571Y216839D02*
X350563Y216840D01*
G01X351485Y214881D02*
X351495Y214876D01*
G01X351475Y214882D02*
X351485Y214881D01*
G01Y218030D02*
X351495Y218026D01*
G01X351475Y218031D02*
X351485Y218030D01*
G01X351508Y214864D02*
X351501Y214872D01*
G01X351513Y214854D02*
X351508Y214864D01*
G01X351515Y214843D02*
X351513Y214854D01*
G01X351508Y218013D02*
X351501Y218022D01*
G01X351513Y218003D02*
X351508Y218013D01*
G01X351515Y217992D02*
X351513Y218003D01*
G01X350572Y218216D02*
X350571Y218228D01*
G01X350569Y218203D02*
X350572Y218216D01*
G01X350569Y218189D02*
Y218203D01*
G01X350572Y215067D02*
X350571Y215079D01*
G01X350569Y215054D02*
X350572Y215067D01*
G01X350569Y215040D02*
Y215054D01*
G01X350531Y216884D02*
Y216876D01*
G01X350530Y216889D02*
X350531Y216884D01*
G01X350530Y216881D02*
Y216889D01*
G01X350569Y216679D02*
X350567Y216693D01*
G01X350572Y216666D02*
X350569Y216679D01*
G01X350571Y216654D02*
X350572Y216666D01*
G01X350569Y213530D02*
X350567Y213543D01*
G01X350572Y213517D02*
X350569Y213530D01*
G01X350571Y213504D02*
X350572Y213517D01*
G01X351479Y218203D02*
X351480Y218189D01*
G01X351476Y218216D02*
X351479Y218203D01*
G01X351476Y218228D02*
Y218216D01*
G01X351479Y215053D02*
X351480Y215040D01*
G01X351476Y215066D02*
X351479Y215053D01*
G01X351476Y215079D02*
Y215066D01*
G01X350531Y213734D02*
Y213727D01*
G01X350530Y213739D02*
X350531Y213734D01*
G01X350530Y213732D02*
Y213739D01*
G01X351476Y216666D02*
Y216654D01*
G01X351478Y216679D02*
X351476Y216666D01*
G01X351480Y216693D02*
X351478Y216679D01*
G01X351476Y213517D02*
Y213504D01*
G01X351478Y213530D02*
X351476Y213517D01*
G01X351480Y213543D02*
X351478Y213530D01*
G01X350554Y214890D02*
X350551Y214888D01*
G01X350557Y214891D02*
X350554Y214890D01*
G01X350560Y214892D02*
X350557Y214891D01*
G01X350564Y214893D02*
X350560Y214892D01*
G01X350567Y214893D02*
X350564D01*
G01X350571D02*
X350567D01*
G01X351493Y216843D02*
X351496Y216844D01*
G01X351490Y216842D02*
X351493Y216843D01*
G01X351487Y216841D02*
X351490Y216842D01*
G01X351483Y216840D02*
X351487Y216841D01*
G01X351480Y216839D02*
X351483Y216840D01*
G01X351476Y216839D02*
X351480D01*
G01X350554Y218039D02*
X350551Y218038D01*
G01X350557Y218041D02*
X350554Y218039D01*
G01X350560Y218042D02*
X350557Y218041D01*
G01X350564Y218042D02*
X350560D01*
G01X350567Y218043D02*
X350564Y218042D01*
G01X350571Y218043D02*
X350567D01*
G01X351506Y214880D02*
X351510Y214875D01*
G01X351502Y214885D02*
X351506Y214880D01*
G01X351496Y214889D02*
X351502Y214885D01*
G01X351490Y214891D02*
X351496Y214889D01*
G01X351483Y214893D02*
X351490Y214891D01*
G01X351476Y214893D02*
X351483D01*
G01X351506Y218030D02*
X351510Y218025D01*
G01X351502Y218034D02*
X351506Y218030D01*
G01X351496Y218038D02*
X351502Y218034D01*
G01X351490Y218041D02*
X351496Y218038D01*
G01X351483Y218043D02*
X351490Y218041D01*
G01X351476Y218043D02*
X351483D01*
G01X350544Y218023D02*
X350569Y218031D01*
G01X350533Y218009D02*
X350544Y218023D01*
G01X350531Y218002D02*
X350533Y218009D01*
G01X350544Y214874D02*
X350569Y214882D01*
G01X350533Y214859D02*
X350544Y214874D01*
G01X350531Y214852D02*
X350533Y214859D01*
G01X351515Y213719D02*
X351516Y213727D01*
G01X351513Y213713D02*
X351515Y213719D01*
G01X351509Y213706D02*
X351513Y213713D01*
G01X351504Y213700D02*
X351509Y213706D01*
G01X351498Y213696D02*
X351504Y213700D01*
G01X351491Y213693D02*
X351498Y213696D01*
G01X351484Y213691D02*
X351491Y213693D01*
G01X351476Y213690D02*
X351484Y213691D01*
G01X350534Y214862D02*
X350529Y214843D01*
G01X350549Y214877D02*
X350534Y214862D01*
G01X350569Y214882D02*
X350549Y214877D01*
G01X350534Y218012D02*
X350529Y217992D01*
G01X350549Y218026D02*
X350534Y218012D01*
G01X350569Y218031D02*
X350549Y218026D01*
G01X351509Y213720D02*
X351514Y213740D01*
G01X351494Y213706D02*
X351509Y213720D01*
G01X351475Y213701D02*
X351494Y213706D01*
G01X351509Y216870D02*
X351514Y216890D01*
G01X351494Y216856D02*
X351509Y216870D01*
G01X351475Y216850D02*
X351494Y216856D01*
G01X351516Y217998D02*
Y218006D01*
G01X351515Y217994D02*
X351516Y217998D01*
G01X351515Y217992D02*
Y217994D01*
G01X351516Y214849D02*
Y214856D01*
G01X351515Y214844D02*
X351516Y214849D01*
G01X351515Y214843D02*
Y214844D01*
G01X351476Y218037D02*
Y218043D01*
G01Y218033D02*
Y218037D01*
G01X351475Y218031D02*
X351476Y218033D01*
G01Y214887D02*
Y214893D01*
G01Y214883D02*
Y214887D01*
G01X351475Y214882D02*
X351476Y214883D01*
G01X350531Y217998D02*
Y218006D01*
G01X350530Y217994D02*
X350531Y217998D01*
G01X350529Y217992D02*
X350530Y217994D01*
G01X350531Y214849D02*
Y214856D01*
G01X350530Y214844D02*
X350531Y214849D01*
G01X350529Y214843D02*
X350530Y214844D01*
G01X351513Y216864D02*
X351516Y216876D01*
G01X351507Y216853D02*
X351513Y216864D01*
G01X351496Y216844D02*
X351507Y216853D01*
G01X350570Y218037D02*
Y218043D01*
G01Y218033D02*
Y218037D01*
G01X350568Y218031D02*
X350570Y218033D01*
G01Y214887D02*
Y214893D01*
G01Y214883D02*
Y214887D01*
G01X350568Y214882D02*
X350570Y214883D01*
G01X350532Y218012D02*
X350531Y218006D01*
G01X350534Y218019D02*
X350532Y218012D01*
G01X350537Y218024D02*
X350534Y218019D01*
G01X350541Y218030D02*
X350537Y218024D01*
G01X350545Y218034D02*
X350541Y218030D01*
G01X350551Y218038D02*
X350545Y218034D01*
G01X350532Y214863D02*
X350531Y214856D01*
G01X350534Y214869D02*
X350532Y214863D01*
G01X350537Y214874D02*
X350534Y214869D01*
G01X350541Y214880D02*
X350537Y214874D01*
G01X350545Y214884D02*
X350541Y214880D01*
G01X350551Y214888D02*
X350545Y214884D01*
G01X351487Y216852D02*
X351475Y216850D01*
G01X351497Y216857D02*
X351487Y216852D01*
G01Y213703D02*
X351475Y213701D01*
G01X351497Y213708D02*
X351487Y213703D01*
G01X360433Y217854D02*
X361614Y219035D01*
G01X350418Y216890D02*
X350530Y216881D01*
G01X351969Y220197D02*
X348622D01*
G01X361614Y219035D02*
X365551D01*
G01X351476Y218228D02*
X350571D01*
G01X351516Y218189D02*
X350531D01*
G01X351475Y218031D02*
X345591D01*
G01Y217992D02*
X351515D01*
G01X360433Y217854D02*
X364370D01*
G01X351514Y216890D02*
X345591D01*
G01X351475Y216850D02*
X345591D01*
G01X350531Y216693D02*
X351516D01*
G01X350571Y216654D02*
X351476D01*
G01Y215079D02*
X350571D01*
G01X351516Y215039D02*
X350531D01*
G01X351475Y214882D02*
X345591D01*
G01Y214843D02*
X351515D01*
G01X351514Y213740D02*
X345591D01*
G01X351475Y213701D02*
X345591D01*
G01X350531Y213543D02*
X351516D01*
G01X350571Y213504D02*
X351476D01*
G01X351515Y214845D02*
X351516Y214856D01*
G01X351515Y217994D02*
X351516Y218006D01*
G01X361614Y295492D02*
Y219035D01*
G01X360433Y294311D02*
Y217854D01*
G01X351969Y299232D02*
Y220197D01*
G01X351516Y216693D02*
Y218189D01*
G01Y213543D02*
Y215039D01*
G01X351476Y216839D02*
Y216693D01*
G01Y213690D02*
Y213543D01*
G01Y215040D02*
Y214893D01*
G01Y218189D02*
Y218043D01*
G01X350571D02*
Y218190D01*
G01Y216692D02*
Y216839D01*
G01Y213543D02*
Y213690D01*
G01Y214893D02*
Y215040D01*
G01X350531Y215039D02*
Y213543D01*
G01Y218189D02*
Y216693D01*
G01X349350Y218031D02*
Y216850D01*
G01Y214882D02*
Y213701D01*
G01X345591Y216850D02*
Y218031D01*
G01Y213701D02*
Y214882D01*
G01X351516Y216876D02*
X351515Y216887D01*
G01X351516Y213727D02*
X351515Y213738D01*
G01X351475Y213701D02*
X351478Y213690D01*
G01X356890Y307579D02*
G03X355709Y306398I0J-1181D01*
G01X363189D02*
G03X362008Y307579I-1181J0D01*
G01X361339Y302303D02*
G03I-1890J0D01*
G01X361811D02*
G03I-2362J0D01*
G01X360433Y294311D02*
X361614Y295492D01*
G01X356964Y299232D02*
X358268Y301201D01*
G01X362940Y307123D02*
X360630Y302894D01*
G01X370276Y307618D02*
X348622D01*
G01X356890Y307579D02*
X362008D01*
G01X358268Y302894D02*
X360630D01*
G01X358268Y301201D02*
X360630D01*
G01X351969Y299232D02*
X366339D01*
G01X351969Y297854D02*
X355709D01*
G01X351969Y296988D02*
X366929D01*
G01X353740Y295492D02*
X361614D01*
G01X354921Y294311D02*
X360433D01*
G01X360630Y302894D02*
Y301201D01*
G01X358268D02*
Y302894D01*
G01X355709Y297854D02*
Y306398D01*
G01X348622Y316083D02*
Y300335D01*
G01X358268Y302894D02*
X355957Y307123D01*
G01X360630Y301201D02*
X361933Y299232D01*
G01X353740Y295492D02*
X354921Y294311D01*
G01X348622Y300335D02*
X351969Y296988D01*
G01X362327Y378885D02*
G03X396138I16905J-13531D01*
G01X362327D02*
G03X396138I16905J-13531D01*
G01X356102Y317264D02*
G03X355512Y316673I1J-591D01*
G01X358268Y315492D02*
G03Y313524I0J-984D01*
G01X360630D02*
G03Y315492I0J984D01*
G01X350591Y318051D02*
G03X348622Y316083I-1J-1968D01*
G01X368307Y318051D02*
X350591D01*
G01X362795Y317264D02*
X356102D01*
G01X360630Y315492D02*
X358268D01*
G01Y313524D02*
X360630D01*
G01X363386Y312146D02*
X355512D01*
G01Y310571D02*
X363386D01*
G01X355512D02*
Y316673D01*
G01X362327Y378885D02*
G03X369252Y392016I-30737J24602D01*
G01X319488Y374803D02*
G03X320669I590J0D01*
G01Y368504D02*
G03X319488I-591J0D01*
G01X317520D02*
G03X316339I-590J0D01*
G01Y374803D02*
G03X317520I590J0D01*
G01X319488D02*
G03X320669I590J0D01*
G01Y368504D02*
G03X319488I-591J0D01*
G01X317520D02*
G03X316339I-590J0D01*
G01Y374803D02*
G03X317520I590J0D01*
G01X362327Y378885D02*
G03X369252Y392016I-30737J24602D01*
G01X316339Y374803D02*
X315551D01*
G01X316339D02*
X315551D01*
G01X319488D02*
X317520D01*
G01X319488D02*
X317520D01*
G01X321457D02*
X320669D01*
G01X321457D02*
X320669D01*
G01X321457Y373819D02*
X315551D01*
G01Y373622D02*
X321457D01*
G01X315551Y369685D02*
X321457D01*
G01Y369488D02*
X315551D01*
G01X320669Y368504D02*
X321457D01*
G01X320669D02*
X321457D01*
G01X317520D02*
X319488D01*
G01X317520D02*
X319488D01*
G01X315551D02*
X316339D01*
G01X315551D02*
X316339D01*
G01X321457D02*
Y374803D01*
G01Y368504D02*
Y374803D01*
G01X315551Y368504D02*
Y374803D01*
G01D02*
Y368504D01*
G01X355512Y592067D02*
G03X356102Y591476I591J0D01*
G01X360630Y593248D02*
G03Y595217I0J985D01*
G01X358268D02*
G03Y593248I0J-985D01*
G01X348622Y592657D02*
G03X350591Y590689I1969J1D01*
G01X363386Y598169D02*
X355512D01*
G01Y596594D02*
X363386D01*
G01X360630Y595217D02*
X358268D01*
G01Y593248D02*
X360630D01*
G01X362795Y591476D02*
X356102D01*
G01X368307Y590689D02*
X350591D01*
G01X355512Y598169D02*
Y592067D01*
G01X348622Y608406D02*
Y592657D01*
G01X360551Y606437D02*
G03I-1102J0D01*
G01X362008Y601161D02*
G03X363189Y602343I0J1181D01*
G01X355709D02*
G03X356890Y601161I1181J-1D01*
G01X361024Y606437D02*
G03I-1575J0D01*
G01X360433Y614429D02*
X354921D01*
G01X361614Y613248D02*
X353740D01*
G01X366929Y611752D02*
X351969D01*
G01X355709Y610886D02*
X351969D01*
G01Y609508D02*
X366339D01*
G01X360630Y607539D02*
X358268D01*
G01X360630Y605846D02*
X358268D01*
G01X362008Y601161D02*
X356890D01*
G01X370276Y601122D02*
X348622D01*
G01X354921Y614429D02*
X353740Y613248D01*
G01X351969Y611752D02*
X348622Y608406D01*
G01X361933Y609508D02*
X360630Y607539D01*
G01X355957Y601617D02*
X358268Y605846D01*
G01Y607539D02*
X356964Y609508D01*
G01X360433Y614429D02*
X361614Y613248D01*
G01Y649705D02*
Y613248D01*
G01X360630Y607539D02*
Y605846D01*
G01X360433Y650886D02*
Y614429D01*
G01X358268Y605846D02*
Y607539D01*
G01X355709Y602343D02*
Y610886D01*
G01X354921Y614429D02*
Y747067D01*
G01X353740Y613248D02*
Y748248D01*
G01X351969Y648543D02*
Y609508D01*
G01X360630Y605846D02*
X362940Y601617D01*
G01X350531Y663341D02*
Y663333D01*
G01X350530Y663345D02*
X350531Y663341D01*
G01Y663336D02*
X350530Y663345D01*
G01X350572Y670972D02*
X350571Y670984D01*
G01X350569Y670959D02*
X350572Y670972D01*
G01X350569Y670945D02*
Y670959D01*
G01X350572Y667822D02*
X350571Y667835D01*
G01X350569Y667809D02*
X350572Y667822D01*
G01X350569Y667796D02*
Y667809D01*
G01X350572Y664673D02*
X350571Y664685D01*
G01X350569Y664660D02*
X350572Y664673D01*
G01X350569Y664646D02*
Y664660D01*
G01X350572Y661523D02*
X350571Y661535D01*
G01X350569Y661510D02*
X350572Y661523D01*
G01X350569Y661496D02*
Y661510D01*
G01X350572Y658374D02*
X350571Y658386D01*
G01X350569Y658361D02*
X350572Y658374D01*
G01X350569Y658347D02*
Y658361D01*
G01X350572Y655224D02*
X350571Y655236D01*
G01X350569Y655211D02*
X350572Y655224D01*
G01X350569Y655197D02*
Y655211D01*
G01X350572Y652074D02*
X350571Y652087D01*
G01X350569Y652061D02*
X350572Y652074D01*
G01X350569Y652048D02*
Y652061D01*
G01X350549Y660163D02*
X350569Y660157D01*
G01X350536Y660175D02*
X350549Y660163D01*
G01X350529Y660193D02*
X350536Y660175D01*
G01X351508Y658171D02*
X351501Y658180D01*
G01X351513Y658161D02*
X351508Y658171D01*
G01X351515Y658150D02*
X351513Y658161D01*
G01X351508Y651872D02*
X351501Y651880D01*
G01X351513Y651861D02*
X351508Y651872D01*
G01X351515Y651850D02*
X351513Y651861D01*
G01X351508Y655021D02*
X351501Y655030D01*
G01X351513Y655011D02*
X351508Y655021D01*
G01X351515Y655000D02*
X351513Y655011D01*
G01X351508Y661320D02*
X351501Y661329D01*
G01X351513Y661310D02*
X351508Y661320D01*
G01X351515Y661299D02*
X351513Y661310D01*
G01X351508Y664470D02*
X351501Y664479D01*
G01X351513Y664460D02*
X351508Y664470D01*
G01X351515Y664449D02*
X351513Y664460D01*
G01X351508Y667620D02*
X351501Y667628D01*
G01X351513Y667609D02*
X351508Y667620D01*
G01X351515Y667598D02*
X351513Y667609D01*
G01X351508Y670769D02*
X351501Y670778D01*
G01X351513Y670759D02*
X351508Y670769D01*
G01X351515Y670748D02*
X351513Y670759D01*
G01X350531Y669640D02*
Y669632D01*
G01X350530Y669644D02*
X350531Y669640D01*
G01X350530Y669637D02*
Y669644D01*
G01X350569Y669435D02*
X350567Y669448D01*
G01X350572Y669422D02*
X350569Y669435D01*
G01X350571Y669409D02*
X350572Y669422D01*
G01X350569Y666285D02*
X350567Y666299D01*
G01X350572Y666272D02*
X350569Y666285D01*
G01X350571Y666260D02*
X350572Y666272D01*
G01X350569Y663136D02*
X350567Y663149D01*
G01X350572Y663123D02*
X350569Y663136D01*
G01X350571Y663110D02*
X350572Y663123D01*
G01X350569Y659986D02*
X350567Y660000D01*
G01X350572Y659973D02*
X350569Y659986D01*
G01X350571Y659961D02*
X350572Y659973D01*
G01X350569Y656837D02*
X350567Y656850D01*
G01X350572Y656824D02*
X350569Y656837D01*
G01X350571Y656811D02*
X350572Y656824D01*
G01X350569Y653687D02*
X350567Y653700D01*
G01X350572Y653674D02*
X350569Y653687D01*
G01X350571Y653661D02*
X350572Y653674D01*
G01X350569Y650537D02*
X350567Y650551D01*
G01X350572Y650524D02*
X350569Y650537D01*
G01X350571Y650512D02*
X350572Y650524D01*
G01X351479Y670959D02*
X351480Y670945D01*
G01X351476Y670972D02*
X351479Y670959D01*
G01X351476Y670984D02*
Y670972D01*
G01X351479Y667809D02*
X351480Y667796D01*
G01X351476Y667822D02*
X351479Y667809D01*
G01X351476Y667835D02*
Y667822D01*
G01X351479Y664659D02*
X351480Y664646D01*
G01X351476Y664672D02*
X351479Y664659D01*
G01X351476Y664685D02*
Y664672D01*
G01X351479Y661510D02*
X351480Y661496D01*
G01X351476Y661523D02*
X351479Y661510D01*
G01X351476Y661535D02*
Y661523D01*
G01X351479Y658360D02*
X351480Y658347D01*
G01X351476Y658373D02*
X351479Y658360D01*
G01X351476Y658386D02*
Y658373D01*
G01X351479Y655211D02*
X351480Y655197D01*
G01X351476Y655224D02*
X351479Y655211D01*
G01X351476Y655236D02*
Y655224D01*
G01X351479Y652061D02*
X351480Y652048D01*
G01X351476Y652074D02*
X351479Y652061D01*
G01X351476Y652087D02*
Y652074D01*
G01X350531Y657041D02*
Y657034D01*
G01X350530Y657046D02*
X350531Y657041D01*
G01X350530Y657039D02*
Y657046D01*
G01X350531Y666490D02*
Y666483D01*
G01X350530Y666495D02*
X350531Y666490D01*
G01X350530Y666488D02*
Y666495D01*
G01X351476Y669422D02*
Y669409D01*
G01X351478Y669435D02*
X351476Y669422D01*
G01X351480Y669448D02*
X351478Y669435D01*
G01X351476Y666272D02*
Y666260D01*
G01X351478Y666285D02*
X351476Y666272D01*
G01X351480Y666299D02*
X351478Y666285D01*
G01X351476Y663123D02*
Y663110D01*
G01X351478Y663136D02*
X351476Y663123D01*
G01X351480Y663149D02*
X351478Y663136D01*
G01X351476Y659973D02*
Y659961D01*
G01X351478Y659986D02*
X351476Y659973D01*
G01X351480Y660000D02*
X351478Y659986D01*
G01X351476Y656824D02*
Y656811D01*
G01X351478Y656837D02*
X351476Y656824D01*
G01X351480Y656850D02*
X351478Y656837D01*
G01X351476Y653674D02*
Y653661D01*
G01X351478Y653687D02*
X351476Y653674D01*
G01X351480Y653700D02*
X351478Y653687D01*
G01X351476Y650524D02*
Y650512D01*
G01X351478Y650537D02*
X351476Y650524D01*
G01X351480Y650551D02*
X351478Y650537D01*
G01X350531Y650743D02*
Y650735D01*
G01X350530Y650747D02*
X350531Y650743D01*
G01X350530Y650741D02*
Y650747D01*
G01X350544Y670779D02*
X350569Y670787D01*
G01X350533Y670765D02*
X350544Y670779D01*
G01X350531Y670758D02*
X350533Y670765D01*
G01X350544Y667630D02*
X350569Y667638D01*
G01X350533Y667615D02*
X350544Y667630D01*
G01X350531Y667608D02*
X350533Y667615D01*
G01X350544Y664480D02*
X350569Y664488D01*
G01X350533Y664465D02*
X350544Y664480D01*
G01X350531Y664459D02*
X350533Y664465D01*
G01X350544Y661330D02*
X350569Y661339D01*
G01X350533Y661316D02*
X350544Y661330D01*
G01X350531Y661309D02*
X350533Y661316D01*
G01X350544Y658181D02*
X350569Y658189D01*
G01X350533Y658166D02*
X350544Y658181D01*
G01X350531Y658159D02*
X350533Y658166D01*
G01X350544Y655031D02*
X350569Y655039D01*
G01X350533Y655017D02*
X350544Y655031D01*
G01X350531Y655010D02*
X350533Y655017D01*
G01X350544Y651881D02*
X350569Y651890D01*
G01X350533Y651867D02*
X350544Y651881D01*
G01X350531Y651860D02*
X350533Y651867D01*
G01X350554Y653861D02*
X350569Y653858D01*
G01X350543Y653868D02*
X350554Y653861D01*
G01X350531Y653887D02*
X350543Y653868D01*
G01X350554Y663310D02*
X350569Y663307D01*
G01X350543Y663317D02*
X350554Y663310D01*
G01X350531Y663335D02*
X350543Y663317D01*
G01X350554Y657011D02*
X350569Y657008D01*
G01X350542Y657019D02*
X350554Y657011D01*
G01X350530Y657039D02*
X350542Y657019D01*
G01X350554Y666459D02*
X350569Y666457D01*
G01X350542Y666467D02*
X350554Y666459D01*
G01X350530Y666487D02*
X350542Y666467D01*
G01X351516Y650742D02*
Y650735D01*
G01X351515Y650747D02*
X351516Y650742D01*
G01X351514Y650748D02*
X351515Y650747D01*
G01X351516Y653892D02*
Y653884D01*
G01X351515Y653896D02*
X351516Y653892D01*
G01X351514Y653898D02*
X351515Y653896D01*
G01X351516Y657041D02*
Y657034D01*
G01X351515Y657046D02*
X351516Y657041D01*
G01X351514Y657047D02*
X351515Y657046D01*
G01X351516Y660191D02*
Y660183D01*
G01X351515Y660196D02*
X351516Y660191D01*
G01X351514Y660197D02*
X351515Y660196D01*
G01X351516Y663341D02*
Y663333D01*
G01X351515Y663345D02*
X351516Y663341D01*
G01X351514Y663346D02*
X351515Y663345D01*
G01X351516Y666490D02*
Y666483D01*
G01X351515Y666495D02*
X351516Y666490D01*
G01X351514Y666496D02*
X351515Y666495D01*
G01X351516Y669640D02*
Y669632D01*
G01X351515Y669644D02*
X351516Y669640D01*
G01X351514Y669646D02*
X351515Y669644D01*
G01X350554Y669609D02*
X350569Y669606D01*
G01X350541Y669617D02*
X350554Y669609D01*
G01X350530Y669637D02*
X350541Y669617D01*
G01X350554Y650712D02*
X350569Y650709D01*
G01X350541Y650720D02*
X350554Y650712D01*
G01X350530Y650741D02*
X350541Y650720D01*
G01X351515Y651871D02*
X351516Y651864D01*
G01X351513Y651877D02*
X351515Y651871D01*
G01X351510Y651883D02*
X351513Y651877D01*
G01X351515Y655020D02*
X351516Y655014D01*
G01X351513Y655027D02*
X351515Y655020D01*
G01X351510Y655033D02*
X351513Y655027D01*
G01X351515Y658170D02*
X351516Y658163D01*
G01X351513Y658176D02*
X351515Y658170D01*
G01X351510Y658182D02*
X351513Y658176D01*
G01X351515Y661320D02*
X351516Y661313D01*
G01X351513Y661326D02*
X351515Y661320D01*
G01X351510Y661332D02*
X351513Y661326D01*
G01X351515Y664469D02*
X351516Y664463D01*
G01X351513Y664476D02*
X351515Y664469D01*
G01X351510Y664481D02*
X351513Y664476D01*
G01X351515Y667619D02*
X351516Y667612D01*
G01X351513Y667625D02*
X351515Y667619D01*
G01X351510Y667631D02*
X351513Y667625D01*
G01X351515Y670769D02*
X351516Y670762D01*
G01X351513Y670775D02*
X351515Y670769D01*
G01X351510Y670781D02*
X351513Y670775D01*
G01X351477Y650704D02*
Y650698D01*
G01X351476Y650707D02*
X351477Y650704D01*
G01X351475Y650709D02*
X351476Y650707D01*
G01X351477Y653853D02*
Y653847D01*
G01X351476Y653857D02*
X351477Y653853D01*
G01X351475Y653858D02*
X351476Y653857D01*
G01X351477Y657003D02*
Y656997D01*
G01X351476Y657007D02*
X351477Y657003D01*
G01X351475Y657008D02*
X351476Y657007D01*
G01X351477Y660152D02*
Y660146D01*
G01X351476Y660156D02*
X351477Y660152D01*
G01X351475Y660157D02*
X351476Y660156D01*
G01X351477Y663302D02*
Y663296D01*
G01X351476Y663306D02*
X351477Y663302D01*
G01X351475Y663307D02*
X351476Y663306D01*
G01X351477Y669601D02*
Y669595D01*
G01X351476Y669605D02*
X351477Y669601D01*
G01X351475Y669606D02*
X351476Y669605D01*
G01X351516Y670754D02*
Y670761D01*
G01X351515Y670750D02*
X351516Y670754D01*
G01X351515Y670748D02*
Y670750D01*
G01X351516Y667605D02*
Y667612D01*
G01X351515Y667600D02*
X351516Y667605D01*
G01X351515Y667598D02*
Y667600D01*
G01X351516Y664455D02*
Y664462D01*
G01X351515Y664451D02*
X351516Y664455D01*
G01X351515Y664449D02*
Y664451D01*
G01X351516Y661306D02*
Y661313D01*
G01X351515Y661301D02*
X351516Y661306D01*
G01X351515Y661299D02*
Y661301D01*
G01X351516Y658156D02*
Y658163D01*
G01X351515Y658152D02*
X351516Y658156D01*
G01X351515Y658150D02*
Y658152D01*
G01X351516Y655006D02*
Y655013D01*
G01X351515Y655002D02*
X351516Y655006D01*
G01X351515Y655000D02*
Y655002D01*
G01X351516Y651857D02*
Y651864D01*
G01X351515Y651852D02*
X351516Y651857D01*
G01X351515Y651850D02*
Y651852D01*
G01X350531Y660191D02*
Y660183D01*
G01X350530Y660196D02*
X350531Y660191D01*
G01X350529Y660193D02*
X350530Y660196D01*
G01X350531Y653892D02*
Y653884D01*
G01X350530Y653896D02*
X350531Y653892D01*
G01X350529Y653894D02*
X350530Y653896D01*
G01X351476Y670793D02*
Y670799D01*
G01Y670789D02*
Y670793D01*
G01X351475Y670787D02*
X351476Y670789D01*
G01Y667643D02*
Y667649D01*
G01Y667639D02*
Y667643D01*
G01X351475Y667638D02*
X351476Y667639D01*
G01Y664493D02*
Y664500D01*
G01Y664490D02*
Y664493D01*
G01X351475Y664488D02*
X351476Y664490D01*
G01Y661344D02*
Y661350D01*
G01Y661340D02*
Y661344D01*
G01X351475Y661339D02*
X351476Y661340D01*
G01Y658194D02*
Y658200D01*
G01Y658191D02*
Y658194D01*
G01X351475Y658189D02*
X351476Y658191D01*
G01Y655044D02*
Y655051D01*
G01Y655041D02*
Y655044D01*
G01X351475Y655039D02*
X351476Y655041D01*
G01Y651895D02*
Y651901D01*
G01Y651891D02*
Y651895D01*
G01X351475Y651890D02*
X351476Y651891D01*
G01X351484Y658188D02*
X351475Y658189D01*
G01X351493Y658185D02*
X351484Y658188D01*
G01X351501Y658180D02*
X351493Y658185D01*
G01X351484Y651889D02*
X351475Y651890D01*
G01X351493Y651885D02*
X351484Y651889D01*
G01X351501Y651880D02*
X351493Y651885D01*
G01X351484Y655038D02*
X351475Y655039D01*
G01X351493Y655035D02*
X351484Y655038D01*
G01X351501Y655030D02*
X351493Y655035D01*
G01X351484Y661337D02*
X351475Y661339D01*
G01X351493Y661334D02*
X351484Y661337D01*
G01X351501Y661329D02*
X351493Y661334D01*
G01X351484Y664487D02*
X351475Y664488D01*
G01X351493Y664484D02*
X351484Y664487D01*
G01X351501Y664479D02*
X351493Y664484D01*
G01X351484Y667637D02*
X351475Y667638D01*
G01X351493Y667633D02*
X351484Y667637D01*
G01X351501Y667628D02*
X351493Y667633D01*
G01X351484Y670786D02*
X351475Y670787D01*
G01X351493Y670783D02*
X351484Y670786D01*
G01X351501Y670778D02*
X351493Y670783D01*
G01X350570Y650704D02*
X350571Y650698D01*
G01X350570Y650707D02*
Y650704D01*
G01X350569Y650709D02*
X350570Y650707D01*
G01Y653854D02*
X350571Y653847D01*
G01X350570Y653857D02*
Y653854D01*
G01X350569Y653858D02*
X350570Y653857D01*
G01Y657003D02*
X350571Y656997D01*
G01X350570Y657007D02*
Y657003D01*
G01X350569Y657008D02*
X350570Y657007D01*
G01Y660153D02*
X350571Y660146D01*
G01X350570Y660156D02*
Y660153D01*
G01X350569Y660157D02*
X350570Y660156D01*
G01Y663302D02*
X350571Y663296D01*
G01X350570Y663306D02*
Y663302D01*
G01X350569Y663307D02*
X350570Y663306D01*
G01Y666452D02*
X350571Y666446D01*
G01X350570Y666456D02*
Y666452D01*
G01X350569Y666457D02*
X350570Y666456D01*
G01Y669602D02*
X350571Y669595D01*
G01X350570Y669605D02*
Y669602D01*
G01X350569Y669606D02*
X350570Y669605D01*
G01X350531Y670754D02*
Y670762D01*
G01X350530Y670750D02*
X350531Y670754D01*
G01X350529Y670748D02*
X350530Y670750D01*
G01X350531Y667605D02*
Y667612D01*
G01X350530Y667600D02*
X350531Y667605D01*
G01X350529Y667598D02*
X350530Y667600D01*
G01X350531Y664455D02*
Y664463D01*
G01X350530Y664450D02*
X350531Y664455D01*
G01X350529Y664449D02*
X350530Y664450D01*
G01X350531Y661306D02*
Y661313D01*
G01X350530Y661301D02*
X350531Y661306D01*
G01X350529Y661299D02*
X350530Y661301D01*
G01X350531Y658156D02*
Y658163D01*
G01X350530Y658151D02*
X350531Y658156D01*
G01X350529Y658150D02*
X350530Y658151D01*
G01X350531Y655006D02*
Y655014D01*
G01X350530Y655002D02*
X350531Y655006D01*
G01X350529Y655000D02*
X350530Y655002D01*
G01X350531Y651857D02*
Y651864D01*
G01X350530Y651852D02*
X350531Y651857D01*
G01X350529Y651850D02*
X350530Y651852D01*
G01X350531Y660187D02*
Y660183D01*
G01X350533Y660182D02*
X350531Y660187D01*
G01X350543Y660167D02*
X350533Y660182D01*
G01X350566Y660158D02*
X350543Y660167D01*
G01X351513Y669620D02*
X351516Y669632D01*
G01X351507Y669609D02*
X351513Y669620D01*
G01X351496Y669600D02*
X351507Y669609D01*
G01X351513Y663320D02*
X351516Y663333D01*
G01X351507Y663309D02*
X351513Y663320D01*
G01X351496Y663301D02*
X351507Y663309D01*
G01X351513Y660171D02*
X351516Y660183D01*
G01X351507Y660160D02*
X351513Y660171D01*
G01X351496Y660152D02*
X351507Y660160D01*
G01X351513Y657021D02*
X351516Y657034D01*
G01X351507Y657010D02*
X351513Y657021D01*
G01X351496Y657002D02*
X351507Y657010D01*
G01X351513Y653872D02*
X351516Y653884D01*
G01X351507Y653861D02*
X351513Y653872D01*
G01X351496Y653852D02*
X351507Y653861D01*
G01X351513Y650722D02*
X351516Y650735D01*
G01X351507Y650711D02*
X351513Y650722D01*
G01X351496Y650703D02*
X351507Y650711D01*
G01X350570Y670793D02*
Y670799D01*
G01Y670789D02*
Y670793D01*
G01X350568Y670787D02*
X350570Y670789D01*
G01Y667643D02*
Y667649D01*
G01Y667639D02*
Y667643D01*
G01X350568Y667638D02*
X350570Y667639D01*
G01Y664493D02*
Y664500D01*
G01Y664489D02*
Y664493D01*
G01X350568Y664488D02*
X350570Y664489D01*
G01Y661344D02*
Y661350D01*
G01Y661340D02*
Y661344D01*
G01X350568Y661339D02*
X350570Y661340D01*
G01X350531Y653888D02*
Y653884D01*
G01X350533Y653882D02*
X350531Y653888D01*
G01X350545Y653867D02*
X350533Y653882D01*
G01X350570Y653858D02*
X350545Y653867D01*
G01X350531Y657038D02*
Y657034D01*
G01X350533Y657031D02*
X350531Y657038D01*
G01X350544Y657016D02*
X350533Y657031D01*
G01X350569Y657008D02*
X350544Y657016D01*
G01X350531Y663337D02*
Y663333D01*
G01X350533Y663331D02*
X350531Y663337D01*
G01X350544Y663315D02*
X350533Y663331D01*
G01X350569Y663307D02*
X350544Y663315D01*
G01X350531Y666487D02*
Y666483D01*
G01X350533Y666480D02*
X350531Y666487D01*
G01X350544Y666465D02*
X350533Y666480D01*
G01X350569Y666457D02*
X350544Y666465D01*
G01X350531Y650739D02*
Y650735D01*
G01X350533Y650732D02*
X350531Y650739D01*
G01X350544Y650717D02*
X350533Y650732D01*
G01X350569Y650709D02*
X350544Y650717D01*
G01X350531Y669636D02*
Y669632D01*
G01X350533Y669630D02*
X350531Y669636D01*
G01X350544Y669615D02*
X350533Y669630D01*
G01X350569Y669606D02*
X350544Y669615D01*
G01X350570Y658194D02*
Y658200D01*
G01Y658190D02*
Y658194D01*
G01X350568Y658189D02*
X350570Y658190D01*
G01Y655044D02*
Y655051D01*
G01Y655041D02*
Y655044D01*
G01X350568Y655039D02*
X350570Y655041D01*
G01Y651895D02*
Y651901D01*
G01Y651891D02*
Y651895D01*
G01X350568Y651890D02*
X350570Y651891D01*
G01X350532Y670768D02*
X350531Y670762D01*
G01X350534Y670774D02*
X350532Y670768D01*
G01X350537Y670780D02*
X350534Y670774D01*
G01X350541Y670785D02*
X350537Y670780D01*
G01X350545Y670790D02*
X350541Y670785D01*
G01X350551Y670794D02*
X350545Y670790D01*
G01X350532Y667619D02*
X350531Y667612D01*
G01X350534Y667625D02*
X350532Y667619D01*
G01X350537Y667630D02*
X350534Y667625D01*
G01X350541Y667636D02*
X350537Y667630D01*
G01X350545Y667640D02*
X350541Y667636D01*
G01X350551Y667644D02*
X350545Y667640D01*
G01X350532Y664469D02*
X350531Y664463D01*
G01X350534Y664475D02*
X350532Y664469D01*
G01X350537Y664481D02*
X350534Y664475D01*
G01X350541Y664486D02*
X350537Y664481D01*
G01X350545Y664491D02*
X350541Y664486D01*
G01X350551Y664494D02*
X350545Y664491D01*
G01X350532Y661319D02*
X350531Y661313D01*
G01X350534Y661326D02*
X350532Y661319D01*
G01X350537Y661331D02*
X350534Y661326D01*
G01X350541Y661337D02*
X350537Y661331D01*
G01X350545Y661341D02*
X350541Y661337D01*
G01X350551Y661345D02*
X350545Y661341D01*
G01X350532Y658170D02*
X350531Y658163D01*
G01X350534Y658176D02*
X350532Y658170D01*
G01X350537Y658181D02*
X350534Y658176D01*
G01X350541Y658187D02*
X350537Y658181D01*
G01X350545Y658191D02*
X350541Y658187D01*
G01X350551Y658195D02*
X350545Y658191D01*
G01X350532Y655020D02*
X350531Y655014D01*
G01X350534Y655026D02*
X350532Y655020D01*
G01X350537Y655032D02*
X350534Y655026D01*
G01X350541Y655037D02*
X350537Y655032D01*
G01X350545Y655042D02*
X350541Y655037D01*
G01X350551Y655046D02*
X350545Y655042D01*
G01X350532Y651870D02*
X350531Y651864D01*
G01X350534Y651877D02*
X350532Y651870D01*
G01X350537Y651882D02*
X350534Y651877D01*
G01X350541Y651888D02*
X350537Y651882D01*
G01X350545Y651892D02*
X350541Y651888D01*
G01X350551Y651896D02*
X350545Y651892D01*
G01X351487Y669608D02*
X351475Y669606D01*
G01X351497Y669613D02*
X351487Y669608D01*
G01Y666459D02*
X351475Y666457D01*
G01X351497Y666464D02*
X351487Y666459D01*
G01X351506Y651888D02*
X351510Y651883D01*
G01X351502Y651893D02*
X351506Y651888D01*
G01X351496Y651896D02*
X351502Y651893D01*
G01X351490Y651899D02*
X351496Y651896D01*
G01X351483Y651901D02*
X351490Y651899D01*
G01X351476Y651901D02*
X351483D01*
G01X351506Y655038D02*
X351510Y655033D01*
G01X351502Y655042D02*
X351506Y655038D01*
G01X351496Y655046D02*
X351502Y655042D01*
G01X351490Y655048D02*
X351496Y655046D01*
G01X351483Y655050D02*
X351490Y655048D01*
G01X351476Y655051D02*
X351483Y655050D01*
G01X351506Y658187D02*
X351510Y658182D01*
G01X351502Y658192D02*
X351506Y658187D01*
G01X351496Y658196D02*
X351502Y658192D01*
G01X351490Y658198D02*
X351496Y658196D01*
G01X351483Y658200D02*
X351490Y658198D01*
G01X351476Y658200D02*
X351483D01*
G01X351506Y661337D02*
X351510Y661332D01*
G01X351502Y661341D02*
X351506Y661337D01*
G01X351496Y661345D02*
X351502Y661341D01*
G01X351490Y661348D02*
X351496Y661345D01*
G01X351483Y661350D02*
X351490Y661348D01*
G01X351476Y661350D02*
X351483D01*
G01X351506Y664487D02*
X351510Y664481D01*
G01X351502Y664491D02*
X351506Y664487D01*
G01X351496Y664495D02*
X351502Y664491D01*
G01X351490Y664497D02*
X351496Y664495D01*
G01X351483Y664499D02*
X351490Y664497D01*
G01X351476Y664500D02*
X351483Y664499D01*
G01X350532Y650727D02*
X350531Y650735D01*
G01X350535Y650720D02*
X350532Y650727D01*
G01X350538Y650714D02*
X350535Y650720D01*
G01X350543Y650708D02*
X350538Y650714D01*
G01X350549Y650704D02*
X350543Y650708D01*
G01X350556Y650700D02*
X350549Y650704D01*
G01X350563Y650698D02*
X350556Y650700D01*
G01X350571Y650698D02*
X350563D01*
G01X350532Y653877D02*
X350531Y653884D01*
G01X350535Y653870D02*
X350532Y653877D01*
G01X350538Y653864D02*
X350535Y653870D01*
G01X350543Y653858D02*
X350538Y653864D01*
G01X350549Y653853D02*
X350543Y653858D01*
G01X350556Y653850D02*
X350549Y653853D01*
G01X350563Y653848D02*
X350556Y653850D01*
G01X350571Y653847D02*
X350563Y653848D01*
G01X350532Y657026D02*
X350531Y657034D01*
G01X350535Y657020D02*
X350532Y657026D01*
G01X350538Y657013D02*
X350535Y657020D01*
G01X350543Y657007D02*
X350538Y657013D01*
G01X350549Y657003D02*
X350543Y657007D01*
G01X350556Y657000D02*
X350549Y657003D01*
G01X350563Y656998D02*
X350556Y657000D01*
G01X350571Y656997D02*
X350563Y656998D01*
G01X350532Y660176D02*
X350531Y660183D01*
G01X350535Y660169D02*
X350532Y660176D01*
G01X350538Y660163D02*
X350535Y660169D01*
G01X350543Y660157D02*
X350538Y660163D01*
G01X350549Y660152D02*
X350543Y660157D01*
G01X350556Y660149D02*
X350549Y660152D01*
G01X350563Y660147D02*
X350556Y660149D01*
G01X350571Y660146D02*
X350563Y660147D01*
G01X350532Y663326D02*
X350531Y663333D01*
G01X350535Y663319D02*
X350532Y663326D01*
G01X350538Y663313D02*
X350535Y663319D01*
G01X350543Y663307D02*
X350538Y663313D01*
G01X350549Y663302D02*
X350543Y663307D01*
G01X350556Y663299D02*
X350549Y663302D01*
G01X350563Y663297D02*
X350556Y663299D01*
G01X350571Y663296D02*
X350563Y663297D01*
G01X350532Y666475D02*
X350531Y666483D01*
G01X350535Y666469D02*
X350532Y666475D01*
G01X350538Y666462D02*
X350535Y666469D01*
G01X350543Y666456D02*
X350538Y666462D01*
G01X350549Y666452D02*
X350543Y666456D01*
G01X350556Y666448D02*
X350549Y666452D01*
G01X350563Y666446D02*
X350556Y666448D01*
G01X350571Y666446D02*
X350563D01*
G01X350532Y669625D02*
X350531Y669632D01*
G01X350535Y669618D02*
X350532Y669625D01*
G01X350538Y669612D02*
X350535Y669618D01*
G01X350543Y669606D02*
X350538Y669612D01*
G01X350549Y669601D02*
X350543Y669606D01*
G01X350556Y669598D02*
X350549Y669601D01*
G01X350563Y669596D02*
X350556Y669598D01*
G01X350571Y669595D02*
X350563Y669596D01*
G01X351485Y651889D02*
X351495Y651884D01*
G01X351475Y651890D02*
X351485Y651889D01*
G01Y655038D02*
X351495Y655034D01*
G01X351475Y655039D02*
X351485Y655038D01*
G01Y658188D02*
X351495Y658183D01*
G01X351475Y658189D02*
X351485Y658188D01*
G01Y661337D02*
X351495Y661333D01*
G01X351475Y661339D02*
X351485Y661337D01*
G01Y664487D02*
X351495Y664483D01*
G01X351475Y664488D02*
X351485Y664487D01*
G01Y667637D02*
X351495Y667632D01*
G01X351475Y667638D02*
X351485Y667637D01*
G01Y670786D02*
X351495Y670782D01*
G01X351475Y670787D02*
X351485Y670786D01*
G01X351487Y663309D02*
X351475Y663307D01*
G01X351497Y663314D02*
X351487Y663309D01*
G01Y660159D02*
X351475Y660157D01*
G01X351497Y660165D02*
X351487Y660159D01*
G01Y657010D02*
X351475Y657008D01*
G01X351497Y657015D02*
X351487Y657010D01*
G01Y653860D02*
X351475Y653858D01*
G01X351497Y653865D02*
X351487Y653860D01*
G01Y650711D02*
X351475Y650709D01*
G01X351497Y650716D02*
X351487Y650711D01*
G01X351493Y650701D02*
X351496Y650703D01*
G01X351490Y650700D02*
X351493Y650701D01*
G01X351487Y650699D02*
X351490Y650700D01*
G01X351483Y650698D02*
X351487Y650699D01*
G01X351480Y650698D02*
X351483D01*
G01X351476D02*
X351480D01*
G01X350554Y651898D02*
X350551Y651896D01*
G01X350557Y651899D02*
X350554Y651898D01*
G01X350560Y651900D02*
X350557Y651899D01*
G01X350564Y651900D02*
X350560D01*
G01X350567Y651901D02*
X350564Y651900D01*
G01X350571Y651901D02*
X350567D01*
G01X351493Y653851D02*
X351496Y653852D01*
G01X351490Y653850D02*
X351493Y653851D01*
G01X351487Y653848D02*
X351490Y653850D01*
G01X351483Y653848D02*
X351487D01*
G01X351480Y653847D02*
X351483Y653848D01*
G01X351476Y653847D02*
X351480D01*
G01X350554Y655047D02*
X350551Y655046D01*
G01X350557Y655048D02*
X350554Y655047D01*
G01X350560Y655050D02*
X350557Y655048D01*
G01X350564Y655050D02*
X350560D01*
G01X350567Y655051D02*
X350564Y655050D01*
G01X350571Y655051D02*
X350567D01*
G01X351493Y657000D02*
X351496Y657002D01*
G01X351490Y656999D02*
X351493Y657000D01*
G01X351487Y656998D02*
X351490Y656999D01*
G01X351483Y656997D02*
X351487Y656998D01*
G01X351480Y656997D02*
X351483D01*
G01X351476D02*
X351480D01*
G01X350554Y658197D02*
X350551Y658195D01*
G01X350557Y658198D02*
X350554Y658197D01*
G01X350560Y658199D02*
X350557Y658198D01*
G01X350564Y658200D02*
X350560Y658199D01*
G01X350567Y658200D02*
X350564D01*
G01X350571D02*
X350567D01*
G01X351493Y660150D02*
X351496Y660152D01*
G01X351490Y660149D02*
X351493Y660150D01*
G01X351487Y660148D02*
X351490Y660149D01*
G01X351483Y660147D02*
X351487Y660148D01*
G01X351480Y660146D02*
X351483Y660147D01*
G01X351476Y660146D02*
X351480D01*
G01X350554Y661346D02*
X350551Y661345D01*
G01X350557Y661348D02*
X350554Y661346D01*
G01X350560Y661349D02*
X350557Y661348D01*
G01X350564Y661349D02*
X350560D01*
G01X350567Y661350D02*
X350564Y661349D01*
G01X350571Y661350D02*
X350567D01*
G01X351493Y663300D02*
X351496Y663301D01*
G01X351490Y663298D02*
X351493Y663300D01*
G01X351487Y663297D02*
X351490Y663298D01*
G01X351483Y663296D02*
X351487Y663297D01*
G01X351480Y663296D02*
X351483D01*
G01X351476D02*
X351480D01*
G01X350554Y664496D02*
X350551Y664494D01*
G01X350557Y664497D02*
X350554Y664496D01*
G01X350560Y664498D02*
X350557Y664497D01*
G01X350564Y664499D02*
X350560Y664498D01*
G01X350567Y664500D02*
X350564Y664499D01*
G01X350571Y664500D02*
X350567D01*
G01X350554Y667646D02*
X350551Y667644D01*
G01X350557Y667647D02*
X350554Y667646D01*
G01X350560Y667648D02*
X350557Y667647D01*
G01X350564Y667648D02*
X350560D01*
G01X350567Y667649D02*
X350564Y667648D01*
G01X350571Y667649D02*
X350567D01*
G01X351493Y669599D02*
X351496Y669600D01*
G01X351490Y669598D02*
X351493Y669599D01*
G01X351487Y669596D02*
X351490Y669598D01*
G01X351483Y669596D02*
X351487D01*
G01X351480Y669595D02*
X351483Y669596D01*
G01X351476Y669595D02*
X351480D01*
G01X350554Y670795D02*
X350551Y670794D01*
G01X350557Y670796D02*
X350554Y670795D01*
G01X350560Y670798D02*
X350557Y670796D01*
G01X350564Y670798D02*
X350560D01*
G01X350567Y670799D02*
X350564Y670798D01*
G01X350571Y670799D02*
X350567D01*
G01X349784Y653898D02*
X349350D01*
G01X350158D02*
X349784D01*
G01Y660197D02*
X349350D01*
G01X350158D02*
X349784D01*
G01Y663346D02*
X349350D01*
G01X350157D02*
X349784D01*
G01X351506Y667636D02*
X351510Y667631D01*
G01X351502Y667641D02*
X351506Y667636D01*
G01X351496Y667644D02*
X351502Y667641D01*
G01X351490Y667647D02*
X351496Y667644D01*
G01X351483Y667649D02*
X351490Y667647D01*
G01X351476Y667649D02*
X351483D01*
G01X351506Y670786D02*
X351510Y670781D01*
G01X351502Y670790D02*
X351506Y670786D01*
G01X351496Y670794D02*
X351502Y670790D01*
G01X351490Y670796D02*
X351496Y670794D01*
G01X351483Y670798D02*
X351490Y670796D01*
G01X351476Y670799D02*
X351483Y670798D01*
G01X351515Y666475D02*
X351516Y666483D01*
G01X351513Y666469D02*
X351515Y666475D01*
G01X351509Y666462D02*
X351513Y666469D01*
G01X351504Y666456D02*
X351509Y666462D01*
G01X351498Y666452D02*
X351504Y666456D01*
G01X351491Y666448D02*
X351498Y666452D01*
G01X351484Y666446D02*
X351491Y666448D01*
G01X351476Y666446D02*
X351484D01*
G01X350534Y651870D02*
X350529Y651850D01*
G01X350549Y651885D02*
X350534Y651870D01*
G01X350569Y651890D02*
X350549Y651885D01*
G01X350534Y655020D02*
X350529Y655000D01*
G01X350549Y655034D02*
X350534Y655020D01*
G01X350569Y655039D02*
X350549Y655034D01*
G01X350534Y658169D02*
X350529Y658150D01*
G01X350549Y658184D02*
X350534Y658169D01*
G01X350569Y658189D02*
X350549Y658184D01*
G01X350534Y661319D02*
X350529Y661299D01*
G01X350549Y661333D02*
X350534Y661319D01*
G01X350569Y661339D02*
X350549Y661333D01*
G01X350534Y664469D02*
X350529Y664449D01*
G01X350549Y664483D02*
X350534Y664469D01*
G01X350569Y664488D02*
X350549Y664483D01*
G01X350534Y667618D02*
X350529Y667598D01*
G01X350549Y667633D02*
X350534Y667618D01*
G01X350569Y667638D02*
X350549Y667633D01*
G01X350534Y670768D02*
X350529Y670748D01*
G01X350549Y670782D02*
X350534Y670768D01*
G01X350569Y670787D02*
X350549Y670782D01*
G01X351509Y650728D02*
X351514Y650748D01*
G01X351494Y650714D02*
X351509Y650728D01*
G01X351475Y650709D02*
X351494Y650714D01*
G01X351509Y653878D02*
X351514Y653898D01*
G01X351494Y653864D02*
X351509Y653878D01*
G01X351475Y653858D02*
X351494Y653864D01*
G01X351509Y657028D02*
X351514Y657047D01*
G01X351494Y657013D02*
X351509Y657028D01*
G01X351475Y657008D02*
X351494Y657013D01*
G01X351509Y660177D02*
X351514Y660197D01*
G01X351494Y660163D02*
X351509Y660177D01*
G01X351475Y660157D02*
X351494Y660163D01*
G01X351509Y663327D02*
X351514Y663346D01*
G01X351494Y663313D02*
X351509Y663327D01*
G01X351475Y663307D02*
X351494Y663313D01*
G01X351509Y666476D02*
X351514Y666496D01*
G01X351494Y666462D02*
X351509Y666476D01*
G01X351475Y666457D02*
X351494Y666462D01*
G01X351509Y669626D02*
X351514Y669646D01*
G01X351494Y669612D02*
X351509Y669626D01*
G01X351475Y669606D02*
X351494Y669612D01*
G01X350418Y669646D02*
X350530Y669637D01*
G01X350529Y660193D02*
X350418Y660197D01*
G01X350529Y653894D02*
X350418Y653898D01*
G01X350529Y663343D02*
X350418Y663346D01*
G01X351969Y672953D02*
X348622D01*
G01X361614Y671791D02*
X365551D01*
G01X351476Y670984D02*
X350571D01*
G01X351516Y670945D02*
X350531D01*
G01X351475Y670787D02*
X345591D01*
G01Y670748D02*
X351515D01*
G01X360433Y670610D02*
X364370D01*
G01X351514Y669646D02*
X345591D01*
G01X351475Y669606D02*
X345591D01*
G01X350531Y669449D02*
X351516D01*
G01X350571Y669409D02*
X351476D01*
G01Y667835D02*
X350571D01*
G01X351516Y667795D02*
X350531D01*
G01X351475Y667638D02*
X345591D01*
G01Y667598D02*
X351515D01*
G01X351514Y666496D02*
X345591D01*
G01X351475Y666457D02*
X345591D01*
G01X350531Y666299D02*
X351516D01*
G01X350571Y666260D02*
X351476D01*
G01Y664685D02*
X350571D01*
G01X351516Y664646D02*
X350531D01*
G01X351475Y664488D02*
X345591D01*
G01Y664449D02*
X351515D01*
G01X351514Y663346D02*
X345591D01*
G01X351475Y663307D02*
X345591D01*
G01X350531Y663150D02*
X351516D01*
G01X350571Y663110D02*
X351476D01*
G01Y661535D02*
X350571D01*
G01X351516Y661496D02*
X350531D01*
G01X351475Y661339D02*
X345591D01*
G01Y661299D02*
X351515D01*
G01X351514Y660197D02*
X345591D01*
G01X351475Y660157D02*
X345591D01*
G01X350531Y660000D02*
X351516D01*
G01X350571Y659961D02*
X351476D01*
G01Y658386D02*
X350571D01*
G01X351516Y658346D02*
X350531D01*
G01X351475Y658189D02*
X345591D01*
G01Y658150D02*
X351515D01*
G01X351514Y657047D02*
X345591D01*
G01X351475Y657008D02*
X345591D01*
G01X350531Y656850D02*
X351516D01*
G01X350571Y656811D02*
X351476D01*
G01Y655236D02*
X350571D01*
G01X351516Y655197D02*
X350531D01*
G01X351475Y655039D02*
X345591D01*
G01Y655000D02*
X351515D01*
G01X351514Y653898D02*
X345591D01*
G01X351475Y653858D02*
X345591D01*
G01X350531Y653701D02*
X351516D01*
G01X350571Y653661D02*
X351476D01*
G01Y652087D02*
X350571D01*
G01X351516Y652047D02*
X350531D01*
G01X351475Y651890D02*
X345591D01*
G01Y651850D02*
X351515D01*
G01X364370Y650886D02*
X360433D01*
G01X351514Y650748D02*
X345591D01*
G01X351475Y650709D02*
X345591D01*
G01X350531Y650551D02*
X351516D01*
G01X350571Y650512D02*
X351476D01*
G01X365551Y649705D02*
X361614D01*
G01X351969Y648543D02*
X348622D01*
G01X360433Y670610D02*
X361614Y671791D01*
G01X360433Y650886D02*
X361614Y649705D01*
G01X351515Y651853D02*
X351516Y651864D01*
G01X351515Y655002D02*
X351516Y655013D01*
G01X351515Y658152D02*
X351516Y658163D01*
G01X351515Y661302D02*
X351516Y661313D01*
G01X351515Y664451D02*
X351516Y664462D01*
G01X351515Y667601D02*
X351516Y667612D01*
G01X351515Y670750D02*
X351516Y670761D01*
G01X361614Y748248D02*
Y671791D01*
G01X360433Y747067D02*
Y670610D01*
G01X351969Y751988D02*
Y672953D01*
G01X351516Y669449D02*
Y670945D01*
G01Y666299D02*
Y667795D01*
G01Y663150D02*
Y664646D01*
G01Y660000D02*
Y661496D01*
G01Y656850D02*
Y658346D01*
G01Y653701D02*
Y655197D01*
G01Y650551D02*
Y652047D01*
G01X351476Y650698D02*
Y650551D01*
G01Y652048D02*
Y651901D01*
G01Y656997D02*
Y656850D01*
G01Y653847D02*
Y653700D01*
G01Y655197D02*
Y655051D01*
G01Y660146D02*
Y660000D01*
G01Y661496D02*
Y661350D01*
G01Y658347D02*
Y658200D01*
G01Y666446D02*
Y666299D01*
G01Y663296D02*
Y663149D01*
G01Y664646D02*
Y664500D01*
G01Y669595D02*
Y669448D01*
G01Y670945D02*
Y670799D01*
G01Y667796D02*
Y667649D01*
G01X351475Y666457D02*
X351478Y666446D01*
G01X350571Y669448D02*
Y669595D01*
G01Y670799D02*
Y670946D01*
G01Y667649D02*
Y667796D01*
G01Y666298D02*
Y666446D01*
G01Y663149D02*
Y663296D01*
G01Y664500D02*
Y664646D01*
G01Y659999D02*
Y660146D01*
G01Y661350D02*
Y661497D01*
G01Y658200D02*
Y658347D01*
G01Y656850D02*
Y656997D01*
G01Y653700D02*
Y653847D01*
G01Y655051D02*
Y655198D01*
G01Y650550D02*
Y650698D01*
G01Y651901D02*
Y652048D01*
G01X350531Y652047D02*
Y650551D01*
G01Y655197D02*
Y653701D01*
G01Y661496D02*
Y660000D01*
G01Y658346D02*
Y656850D01*
G01Y664646D02*
Y663150D01*
G01Y670945D02*
Y669449D01*
G01Y667795D02*
Y666299D01*
G01X349350Y651890D02*
Y650709D01*
G01Y658189D02*
Y657008D01*
G01Y655039D02*
Y653858D01*
G01Y661339D02*
Y660157D01*
G01Y667638D02*
Y666457D01*
G01Y664488D02*
Y663307D01*
G01Y670787D02*
Y669606D01*
G01X349016Y672953D02*
Y648543D01*
G01X348622D02*
Y672953D01*
G01X345591Y669606D02*
Y670787D01*
G01Y666457D02*
Y667638D01*
G01Y663307D02*
Y664488D01*
G01Y660157D02*
Y661339D01*
G01Y657008D02*
Y658189D01*
G01Y653858D02*
Y655039D01*
G01Y650709D02*
Y651890D01*
G01X351516Y669632D02*
X351515Y669643D01*
G01X351516Y666483D02*
X351515Y666494D01*
G01X351516Y663333D02*
X351515Y663344D01*
G01X351516Y660183D02*
X351515Y660194D01*
G01X351516Y657034D02*
X351515Y657045D01*
G01X351516Y653884D02*
X351515Y653895D01*
G01X351516Y650735D02*
X351515Y650746D01*
G01X356102Y770020D02*
G03X355512Y769429I1J-591D01*
G01X358268Y768248D02*
G03Y766280I0J-984D01*
G01X360630D02*
G03Y768248I0J984D01*
G01X350591Y770807D02*
G03X348622Y768839I-1J-1968D01*
G01X356890Y760335D02*
G03X355709Y759154I0J-1181D01*
G01X363189D02*
G03X362008Y760335I-1181J0D01*
G01X361339Y755059D02*
G03I-1890J0D01*
G01X361811D02*
G03I-2362J0D01*
G01X368307Y770807D02*
X350591D01*
G01X362795Y770020D02*
X356102D01*
G01X360630Y768248D02*
X358268D01*
G01Y766280D02*
X360630D01*
G01X363386Y764902D02*
X355512D01*
G01Y763327D02*
X363386D01*
G01X370276Y760374D02*
X348622D01*
G01X356890Y760335D02*
X362008D01*
G01X358268Y755650D02*
X360630D01*
G01X358268Y753957D02*
X360630D01*
G01X351969Y751988D02*
X366339D01*
G01X351969Y750610D02*
X355709D01*
G01X351969Y749744D02*
X366929D01*
G01X353740Y748248D02*
X361614D01*
G01X354921Y747067D02*
X360433D01*
G01D02*
X361614Y748248D01*
G01X360630Y753957D02*
X361933Y751988D01*
G01X353740Y748248D02*
X354921Y747067D01*
G01X348622Y753091D02*
X351969Y749744D01*
G01X356964Y751988D02*
X358268Y753957D01*
G01X362940Y759879D02*
X360630Y755650D01*
G01X358268D02*
X355957Y759879D01*
G01X360630Y755650D02*
Y753957D01*
G01X358268D02*
Y755650D01*
G01X355709Y750610D02*
Y759154D01*
G01X355512Y763327D02*
Y769429D01*
G01X348622Y768839D02*
Y753091D01*
G01X362327Y831641D02*
G03X396138I16905J-13531D01*
G01X362327D02*
G03X369252Y844772I-30737J24602D01*
G01X319488Y827559D02*
G03X320669I590J0D01*
G01Y821260D02*
G03X319488I-591J0D01*
G01X317520D02*
G03X316339I-590J0D01*
G01Y827559D02*
G03X317520I590J0D01*
G01X319488D02*
G03X320669I590J0D01*
G01Y821260D02*
G03X319488I-591J0D01*
G01X317520D02*
G03X316339I-590J0D01*
G01Y827559D02*
G03X317520I590J0D01*
G01X362327Y831641D02*
G03X396138I16905J-13531D01*
G01X362327D02*
G03X369252Y844772I-30737J24602D01*
G01X316339Y827559D02*
X315551D01*
G01X316339D02*
X315551D01*
G01X319488D02*
X317520D01*
G01X319488D02*
X317520D01*
G01X321457D02*
X320669D01*
G01X321457D02*
X320669D01*
G01X321457Y826575D02*
X315551D01*
G01Y826378D02*
X321457D01*
G01X315551Y822441D02*
X321457D01*
G01Y822244D02*
X315551D01*
G01X320669Y821260D02*
X321457D01*
G01X320669D02*
X321457D01*
G01X317520D02*
X319488D01*
G01X317520D02*
X319488D01*
G01X315551D02*
X316339D01*
G01X315551D02*
X316339D01*
G01X321457D02*
Y827559D01*
G01Y821260D02*
Y827559D01*
G01X315551Y821260D02*
Y827559D01*
G01D02*
Y821260D01*
G01X355512Y1044823D02*
G03X356102Y1044232I591J0D01*
G01X360630Y1046004D02*
G03Y1047972I0J984D01*
G01X358268D02*
G03Y1046004I0J-984D01*
G01X360551Y1059193D02*
G03I-1102J0D01*
G01X362008Y1053917D02*
G03X363189Y1055098I0J1181D01*
G01X355709D02*
G03X356890Y1053917I1181J0D01*
G01X361024Y1059193D02*
G03I-1575J0D01*
G01X348622Y1045413D02*
G03X350591Y1043445I1969J1D01*
G01X360433Y1067185D02*
X354921D01*
G01X361614Y1066004D02*
X353740D01*
G01X366929Y1064508D02*
X351969D01*
G01X355709Y1063642D02*
X351969D01*
G01Y1062264D02*
X366339D01*
G01X360630Y1060295D02*
X358268D01*
G01X360630Y1058602D02*
X358268D01*
G01X362008Y1053917D02*
X356890D01*
G01X370276Y1053878D02*
X348622D01*
G01X363386Y1050925D02*
X355512D01*
G01Y1049350D02*
X363386D01*
G01X360630Y1047972D02*
X358268D01*
G01Y1046004D02*
X360630D01*
G01X362795Y1044232D02*
X356102D01*
G01X368307Y1043445D02*
X350591D01*
G01X360433Y1067185D02*
X361614Y1066004D01*
G01X360630Y1058602D02*
X362940Y1054373D01*
G01X358268Y1060295D02*
X356964Y1062264D01*
G01X361614Y1102461D02*
Y1066004D01*
G01X360630Y1060295D02*
Y1058602D01*
G01X360433Y1103642D02*
Y1067185D01*
G01X358268Y1058602D02*
Y1060295D01*
G01X355709Y1055098D02*
Y1063642D01*
G01X355512Y1050925D02*
Y1044823D01*
G01X354921Y1067185D02*
Y1199823D01*
G01X353740Y1066004D02*
Y1201004D01*
G01X351969Y1101299D02*
Y1062264D01*
G01X354921Y1067185D02*
X353740Y1066004D01*
G01X351969Y1064508D02*
X348622Y1061161D01*
G01X361933Y1062264D02*
X360630Y1060295D01*
G01X355957Y1054373D02*
X358268Y1058602D01*
G01X348622Y1061161D02*
Y1045413D01*
G01X350572Y1123728D02*
X350571Y1123740D01*
G01X350569Y1123715D02*
X350572Y1123728D01*
G01X350569Y1123701D02*
Y1123715D01*
G01X350572Y1120578D02*
X350571Y1120591D01*
G01X350569Y1120565D02*
X350572Y1120578D01*
G01X350569Y1120552D02*
Y1120565D01*
G01X350572Y1117429D02*
X350571Y1117441D01*
G01X350569Y1117416D02*
X350572Y1117429D01*
G01X350569Y1117402D02*
Y1117416D01*
G01X350572Y1114279D02*
X350571Y1114291D01*
G01X350569Y1114266D02*
X350572Y1114279D01*
G01X350569Y1114252D02*
Y1114266D01*
G01X350572Y1111130D02*
X350571Y1111142D01*
G01X350569Y1111117D02*
X350572Y1111130D01*
G01X350569Y1111103D02*
Y1111117D01*
G01X350572Y1107980D02*
X350571Y1107992D01*
G01X350569Y1107967D02*
X350572Y1107980D01*
G01X350569Y1107953D02*
Y1107967D01*
G01X350572Y1104830D02*
X350571Y1104843D01*
G01X350569Y1104817D02*
X350572Y1104830D01*
G01X350569Y1104804D02*
Y1104817D01*
G01X350531Y1122396D02*
Y1122388D01*
G01X350530Y1122400D02*
X350531Y1122396D01*
G01X350530Y1122393D02*
Y1122400D01*
G01X350569Y1122191D02*
X350567Y1122204D01*
G01X350572Y1122178D02*
X350569Y1122191D01*
G01X350571Y1122165D02*
X350572Y1122178D01*
G01X350569Y1119041D02*
X350567Y1119055D01*
G01X350572Y1119028D02*
X350569Y1119041D01*
G01X350571Y1119016D02*
X350572Y1119028D01*
G01X350569Y1115892D02*
X350567Y1115905D01*
G01X350572Y1115879D02*
X350569Y1115892D01*
G01X350571Y1115866D02*
X350572Y1115879D01*
G01X350569Y1112742D02*
X350567Y1112756D01*
G01X350572Y1112729D02*
X350569Y1112742D01*
G01X350571Y1112717D02*
X350572Y1112729D01*
G01X350569Y1109593D02*
X350567Y1109606D01*
G01X350572Y1109580D02*
X350569Y1109593D01*
G01X350571Y1109567D02*
X350572Y1109580D01*
G01X350569Y1106443D02*
X350567Y1106456D01*
G01X350572Y1106430D02*
X350569Y1106443D01*
G01X350571Y1106417D02*
X350572Y1106430D01*
G01X350569Y1103293D02*
X350567Y1103307D01*
G01X350572Y1103280D02*
X350569Y1103293D01*
G01X350571Y1103268D02*
X350572Y1103280D01*
G01X351479Y1123715D02*
X351480Y1123701D01*
G01X351476Y1123728D02*
X351479Y1123715D01*
G01X351476Y1123740D02*
Y1123728D01*
G01X351479Y1120565D02*
X351480Y1120552D01*
G01X351476Y1120578D02*
X351479Y1120565D01*
G01X351476Y1120591D02*
Y1120578D01*
G01X351479Y1117415D02*
X351480Y1117402D01*
G01X351476Y1117428D02*
X351479Y1117415D01*
G01X351476Y1117441D02*
Y1117428D01*
G01X351479Y1114266D02*
X351480Y1114252D01*
G01X351476Y1114279D02*
X351479Y1114266D01*
G01X351476Y1114291D02*
Y1114279D01*
G01X351479Y1111116D02*
X351480Y1111103D01*
G01X351476Y1111129D02*
X351479Y1111116D01*
G01X351476Y1111142D02*
Y1111129D01*
G01X351479Y1107967D02*
X351480Y1107953D01*
G01X351476Y1107980D02*
X351479Y1107967D01*
G01X351476Y1107992D02*
Y1107980D01*
G01X351479Y1104817D02*
X351480Y1104804D01*
G01X351476Y1104830D02*
X351479Y1104817D01*
G01X351476Y1104843D02*
Y1104830D01*
G01X350531Y1109797D02*
Y1109790D01*
G01X350530Y1109802D02*
X350531Y1109797D01*
G01X350530Y1109795D02*
Y1109802D01*
G01X350531Y1119246D02*
Y1119239D01*
G01X350530Y1119251D02*
X350531Y1119246D01*
G01X350530Y1119244D02*
Y1119251D01*
G01X351476Y1122178D02*
Y1122165D01*
G01X351478Y1122191D02*
X351476Y1122178D01*
G01X351480Y1122204D02*
X351478Y1122191D01*
G01X351476Y1119028D02*
Y1119016D01*
G01X351478Y1119041D02*
X351476Y1119028D01*
G01X351480Y1119055D02*
X351478Y1119041D01*
G01X351476Y1115879D02*
Y1115866D01*
G01X351478Y1115892D02*
X351476Y1115879D01*
G01X351480Y1115905D02*
X351478Y1115892D01*
G01X351476Y1112729D02*
Y1112717D01*
G01X351478Y1112742D02*
X351476Y1112729D01*
G01X351480Y1112756D02*
X351478Y1112742D01*
G01X351476Y1109580D02*
Y1109567D01*
G01X351478Y1109593D02*
X351476Y1109580D01*
G01X351480Y1109606D02*
X351478Y1109593D01*
G01X351476Y1106430D02*
Y1106417D01*
G01X351478Y1106443D02*
X351476Y1106430D01*
G01X351480Y1106456D02*
X351478Y1106443D01*
G01X351476Y1103280D02*
Y1103268D01*
G01X351478Y1103293D02*
X351476Y1103280D01*
G01X351480Y1103307D02*
X351478Y1103293D01*
G01X350531Y1103498D02*
Y1103491D01*
G01X350530Y1103503D02*
X350531Y1103498D01*
G01X350530Y1103496D02*
Y1103503D01*
G01X350544Y1123535D02*
X350569Y1123543D01*
G01X350533Y1123520D02*
X350544Y1123535D01*
G01X350531Y1123514D02*
X350533Y1123520D01*
G01X350544Y1120385D02*
X350569Y1120394D01*
G01X350533Y1120371D02*
X350544Y1120385D01*
G01X350531Y1120364D02*
X350533Y1120371D01*
G01X350544Y1117236D02*
X350569Y1117244D01*
G01X350533Y1117221D02*
X350544Y1117236D01*
G01X350531Y1117215D02*
X350533Y1117221D01*
G01X350544Y1114086D02*
X350569Y1114094D01*
G01X350533Y1114072D02*
X350544Y1114086D01*
G01X350531Y1114065D02*
X350533Y1114072D01*
G01X350544Y1110937D02*
X350569Y1110945D01*
G01X350533Y1110922D02*
X350544Y1110937D01*
G01X350531Y1110915D02*
X350533Y1110922D01*
G01X350544Y1107787D02*
X350569Y1107795D01*
G01X350533Y1107772D02*
X350544Y1107787D01*
G01X350531Y1107766D02*
X350533Y1107772D01*
G01X350544Y1104637D02*
X350569Y1104646D01*
G01X350533Y1104623D02*
X350544Y1104637D01*
G01X350531Y1104616D02*
X350533Y1104623D01*
G01X351516Y1123510D02*
Y1123517D01*
G01X351515Y1123506D02*
X351516Y1123510D01*
G01X351515Y1123504D02*
Y1123506D01*
G01X351516Y1120361D02*
Y1120368D01*
G01X351515Y1120356D02*
X351516Y1120361D01*
G01X351515Y1120354D02*
Y1120356D01*
G01X351516Y1117211D02*
Y1117218D01*
G01X351515Y1117207D02*
X351516Y1117211D01*
G01X351515Y1117205D02*
Y1117207D01*
G01X351516Y1114061D02*
Y1114069D01*
G01X351515Y1114057D02*
X351516Y1114061D01*
G01X351515Y1114055D02*
Y1114057D01*
G01X351516Y1110912D02*
Y1110919D01*
G01X351515Y1110907D02*
X351516Y1110912D01*
G01X351515Y1110906D02*
Y1110907D01*
G01X351516Y1107762D02*
Y1107769D01*
G01X351515Y1107758D02*
X351516Y1107762D01*
G01X351515Y1107756D02*
Y1107758D01*
G01X351516Y1104613D02*
Y1104620D01*
G01X351515Y1104608D02*
X351516Y1104613D01*
G01X351515Y1104606D02*
Y1104608D01*
G01X350531Y1112947D02*
Y1112939D01*
G01X350530Y1112952D02*
X350531Y1112947D01*
G01X350529Y1112949D02*
X350530Y1112952D01*
G01X350531Y1106648D02*
Y1106640D01*
G01X350530Y1106652D02*
X350531Y1106648D01*
G01X350529Y1106650D02*
X350530Y1106652D01*
G01X351476Y1123548D02*
Y1123555D01*
G01Y1123545D02*
Y1123548D01*
G01X351475Y1123543D02*
X351476Y1123545D01*
G01Y1120399D02*
Y1120405D01*
G01Y1120395D02*
Y1120399D01*
G01X351475Y1120394D02*
X351476Y1120395D01*
G01Y1117249D02*
Y1117256D01*
G01Y1117246D02*
Y1117249D01*
G01X351475Y1117244D02*
X351476Y1117246D01*
G01Y1114100D02*
Y1114106D01*
G01Y1114096D02*
Y1114100D01*
G01X351475Y1114094D02*
X351476Y1114096D01*
G01Y1110950D02*
Y1110956D01*
G01Y1110946D02*
Y1110950D01*
G01X351475Y1110945D02*
X351476Y1110946D01*
G01Y1107800D02*
Y1107807D01*
G01Y1107797D02*
Y1107800D01*
G01X351475Y1107795D02*
X351476Y1107797D01*
G01Y1104651D02*
Y1104657D01*
G01Y1104647D02*
Y1104651D01*
G01X351475Y1104646D02*
X351476Y1104647D01*
G01X350531Y1123510D02*
Y1123518D01*
G01X350530Y1123506D02*
X350531Y1123510D01*
G01X350529Y1123504D02*
X350530Y1123506D01*
G01X350531Y1120361D02*
Y1120368D01*
G01X350530Y1120356D02*
X350531Y1120361D01*
G01X350529Y1120354D02*
X350530Y1120356D01*
G01X350531Y1117211D02*
Y1117219D01*
G01X350530Y1117206D02*
X350531Y1117211D01*
G01X350529Y1117205D02*
X350530Y1117206D01*
G01X350531Y1114061D02*
Y1114069D01*
G01X350530Y1114057D02*
X350531Y1114061D01*
G01X350529Y1114055D02*
X350530Y1114057D01*
G01X350531Y1110912D02*
Y1110919D01*
G01X350530Y1110907D02*
X350531Y1110912D01*
G01X350529Y1110906D02*
X350530Y1110907D01*
G01X350531Y1107762D02*
Y1107770D01*
G01X350530Y1107757D02*
X350531Y1107762D01*
G01X350529Y1107756D02*
X350530Y1107757D01*
G01X350531Y1104613D02*
Y1104620D01*
G01X350530Y1104608D02*
X350531Y1104613D01*
G01X350529Y1104606D02*
X350530Y1104608D01*
G01X351513Y1122376D02*
X351516Y1122388D01*
G01X351507Y1122365D02*
X351513Y1122376D01*
G01X351496Y1122356D02*
X351507Y1122365D01*
G01X351513Y1116076D02*
X351516Y1116089D01*
G01X351507Y1116065D02*
X351513Y1116076D01*
G01X351496Y1116057D02*
X351507Y1116065D01*
G01X351513Y1112927D02*
X351516Y1112939D01*
G01X351507Y1112916D02*
X351513Y1112927D01*
G01X351496Y1112907D02*
X351507Y1112916D01*
G01X351513Y1109777D02*
X351516Y1109790D01*
G01X351507Y1109766D02*
X351513Y1109777D01*
G01X351496Y1109758D02*
X351507Y1109766D01*
G01X351513Y1106628D02*
X351516Y1106640D01*
G01X351507Y1106617D02*
X351513Y1106628D01*
G01X351496Y1106608D02*
X351507Y1106617D01*
G01X351513Y1103478D02*
X351516Y1103491D01*
G01X351507Y1103467D02*
X351513Y1103478D01*
G01X351496Y1103459D02*
X351507Y1103467D01*
G01X350570Y1123548D02*
Y1123555D01*
G01Y1123544D02*
Y1123548D01*
G01X350568Y1123543D02*
X350570Y1123544D01*
G01Y1120399D02*
Y1120405D01*
G01Y1120395D02*
Y1120399D01*
G01X350568Y1120394D02*
X350570Y1120395D01*
G01Y1117249D02*
Y1117256D01*
G01Y1117245D02*
Y1117249D01*
G01X350568Y1117244D02*
X350570Y1117245D01*
G01Y1114100D02*
Y1114106D01*
G01Y1114096D02*
Y1114100D01*
G01X350568Y1114094D02*
X350570Y1114096D01*
G01Y1110950D02*
Y1110956D01*
G01Y1110946D02*
Y1110950D01*
G01X350568Y1110945D02*
X350570Y1110946D01*
G01Y1107800D02*
Y1107807D01*
G01Y1107796D02*
Y1107800D01*
G01X350568Y1107795D02*
X350570Y1107796D01*
G01Y1104651D02*
Y1104657D01*
G01Y1104647D02*
Y1104651D01*
G01X350568Y1104646D02*
X350570Y1104647D01*
G01X350532Y1123524D02*
X350531Y1123518D01*
G01X350534Y1123530D02*
X350532Y1123524D01*
G01X350537Y1123536D02*
X350534Y1123530D01*
G01X350541Y1123541D02*
X350537Y1123536D01*
G01X350545Y1123546D02*
X350541Y1123541D01*
G01X350551Y1123550D02*
X350545Y1123546D01*
G01X350532Y1120374D02*
X350531Y1120368D01*
G01X350534Y1120381D02*
X350532Y1120374D01*
G01X350537Y1120386D02*
X350534Y1120381D01*
G01X350541Y1120392D02*
X350537Y1120386D01*
G01X350545Y1120396D02*
X350541Y1120392D01*
G01X350551Y1120400D02*
X350545Y1120396D01*
G01X350532Y1117225D02*
X350531Y1117219D01*
G01X350534Y1117231D02*
X350532Y1117225D01*
G01X350537Y1117237D02*
X350534Y1117231D01*
G01X350541Y1117242D02*
X350537Y1117237D01*
G01X350545Y1117246D02*
X350541Y1117242D01*
G01X350551Y1117250D02*
X350545Y1117246D01*
G01X350532Y1114075D02*
X350531Y1114069D01*
G01X350534Y1114081D02*
X350532Y1114075D01*
G01X350537Y1114087D02*
X350534Y1114081D01*
G01X350541Y1114093D02*
X350537Y1114087D01*
G01X350545Y1114097D02*
X350541Y1114093D01*
G01X350551Y1114101D02*
X350545Y1114097D01*
G01X350532Y1110926D02*
X350531Y1110919D01*
G01X350534Y1110932D02*
X350532Y1110926D01*
G01X350537Y1110937D02*
X350534Y1110932D01*
G01X350541Y1110943D02*
X350537Y1110937D01*
G01X350545Y1110947D02*
X350541Y1110943D01*
G01X350551Y1110951D02*
X350545Y1110947D01*
G01X350531Y1116096D02*
Y1116089D01*
G01X350530Y1116101D02*
X350531Y1116096D01*
G01Y1116092D02*
X350530Y1116101D01*
G01X350532Y1107776D02*
X350531Y1107770D01*
G01X350534Y1107782D02*
X350532Y1107776D01*
G01X350537Y1107788D02*
X350534Y1107782D01*
G01X350541Y1107793D02*
X350537Y1107788D01*
G01X350545Y1107798D02*
X350541Y1107793D01*
G01X350551Y1107802D02*
X350545Y1107798D01*
G01X350532Y1104626D02*
X350531Y1104620D01*
G01X350534Y1104633D02*
X350532Y1104626D01*
G01X350537Y1104638D02*
X350534Y1104633D01*
G01X350541Y1104644D02*
X350537Y1104638D01*
G01X350545Y1104648D02*
X350541Y1104644D01*
G01X350551Y1104652D02*
X350545Y1104648D01*
G01X351487Y1122364D02*
X351475Y1122362D01*
G01X351497Y1122369D02*
X351487Y1122364D01*
G01Y1119215D02*
X351475Y1119213D01*
G01X351497Y1119220D02*
X351487Y1119215D01*
G01Y1116065D02*
X351475Y1116063D01*
G01X351497Y1116070D02*
X351487Y1116065D01*
G01Y1112915D02*
X351475Y1112913D01*
G01X351497Y1112920D02*
X351487Y1112915D01*
G01Y1109766D02*
X351475Y1109764D01*
G01X351497Y1109771D02*
X351487Y1109766D01*
G01Y1106616D02*
X351475Y1106614D01*
G01X351497Y1106621D02*
X351487Y1106616D01*
G01Y1103467D02*
X351475Y1103465D01*
G01X351497Y1103472D02*
X351487Y1103467D01*
G01X351508Y1110927D02*
X351501Y1110935D01*
G01X351513Y1110917D02*
X351508Y1110927D01*
G01X351515Y1110906D02*
X351513Y1110917D01*
G01X351508Y1104628D02*
X351501Y1104636D01*
G01X351513Y1104617D02*
X351508Y1104628D01*
G01X351515Y1104606D02*
X351513Y1104617D01*
G01X351508Y1107777D02*
X351501Y1107786D01*
G01X351513Y1107767D02*
X351508Y1107777D01*
G01X351515Y1107756D02*
X351513Y1107767D01*
G01X351508Y1114076D02*
X351501Y1114085D01*
G01X351513Y1114066D02*
X351508Y1114076D01*
G01X351515Y1114055D02*
X351513Y1114066D01*
G01X351508Y1117226D02*
X351501Y1117235D01*
G01X351513Y1117216D02*
X351508Y1117226D01*
G01X351515Y1117205D02*
X351513Y1117216D01*
G01X351508Y1120376D02*
X351501Y1120384D01*
G01X351513Y1120365D02*
X351508Y1120376D01*
G01X351515Y1120354D02*
X351513Y1120365D01*
G01X351508Y1123525D02*
X351501Y1123534D01*
G01X351513Y1123515D02*
X351508Y1123525D01*
G01X351515Y1123504D02*
X351513Y1123515D01*
G01X350549Y1112919D02*
X350569Y1112913D01*
G01X350536Y1112931D02*
X350549Y1112919D01*
G01X350529Y1112949D02*
X350536Y1112931D01*
G01X350554Y1109767D02*
X350569Y1109764D01*
G01X350542Y1109774D02*
X350554Y1109767D01*
G01X350530Y1109794D02*
X350542Y1109774D01*
G01X350554Y1119215D02*
X350569Y1119213D01*
G01X350542Y1119223D02*
X350554Y1119215D01*
G01X350530Y1119243D02*
X350542Y1119223D01*
G01X351516Y1103498D02*
Y1103491D01*
G01X351515Y1103503D02*
X351516Y1103498D01*
G01X351514Y1103504D02*
X351515Y1103503D01*
G01X351516Y1106648D02*
Y1106640D01*
G01X351515Y1106652D02*
X351516Y1106648D01*
G01X351514Y1106654D02*
X351515Y1106652D01*
G01X351516Y1109797D02*
Y1109790D01*
G01X351515Y1109802D02*
X351516Y1109797D01*
G01X351514Y1109803D02*
X351515Y1109802D01*
G01X351516Y1112947D02*
Y1112939D01*
G01X351515Y1112952D02*
X351516Y1112947D01*
G01X351514Y1112953D02*
X351515Y1112952D01*
G01X351516Y1116096D02*
Y1116089D01*
G01X351515Y1116101D02*
X351516Y1116096D01*
G01X351514Y1116102D02*
X351515Y1116101D01*
G01X351516Y1119246D02*
Y1119239D01*
G01X351515Y1119251D02*
X351516Y1119246D01*
G01X351514Y1119252D02*
X351515Y1119251D01*
G01X351516Y1122396D02*
Y1122388D01*
G01X351515Y1122400D02*
X351516Y1122396D01*
G01X351514Y1122402D02*
X351515Y1122400D01*
G01X350554Y1122365D02*
X350569Y1122362D01*
G01X350541Y1122373D02*
X350554Y1122365D01*
G01X350530Y1122393D02*
X350541Y1122373D01*
G01X350554Y1103468D02*
X350569Y1103465D01*
G01X350541Y1103476D02*
X350554Y1103468D01*
G01X350530Y1103496D02*
X350541Y1103476D01*
G01X351515Y1104627D02*
X351516Y1104620D01*
G01X351513Y1104633D02*
X351515Y1104627D01*
G01X351510Y1104639D02*
X351513Y1104633D01*
G01X351515Y1107776D02*
X351516Y1107770D01*
G01X351513Y1107783D02*
X351515Y1107776D01*
G01X351510Y1107789D02*
X351513Y1107783D01*
G01X351515Y1110926D02*
X351516Y1110919D01*
G01X351513Y1110932D02*
X351515Y1110926D01*
G01X351510Y1110938D02*
X351513Y1110932D01*
G01X351515Y1114076D02*
X351516Y1114069D01*
G01X351513Y1114082D02*
X351515Y1114076D01*
G01X351510Y1114088D02*
X351513Y1114082D01*
G01X351515Y1117225D02*
X351516Y1117219D01*
G01X351513Y1117231D02*
X351515Y1117225D01*
G01X351510Y1117237D02*
X351513Y1117231D01*
G01X351515Y1120375D02*
X351516Y1120368D01*
G01X351513Y1120381D02*
X351515Y1120375D01*
G01X351510Y1120387D02*
X351513Y1120381D01*
G01X351515Y1123524D02*
X351516Y1123518D01*
G01X351513Y1123531D02*
X351515Y1123524D01*
G01X351510Y1123537D02*
X351513Y1123531D01*
G01X351477Y1103459D02*
Y1103454D01*
G01X351476Y1103463D02*
X351477Y1103459D01*
G01X351475Y1103465D02*
X351476Y1103463D01*
G01X351477Y1106609D02*
Y1106603D01*
G01X351476Y1106613D02*
X351477Y1106609D01*
G01X351475Y1106614D02*
X351476Y1106613D01*
G01X351477Y1109759D02*
Y1109753D01*
G01X351476Y1109763D02*
X351477Y1109759D01*
G01X351475Y1109764D02*
X351476Y1109763D01*
G01X351477Y1112908D02*
Y1112902D01*
G01X351476Y1112912D02*
X351477Y1112908D01*
G01X351475Y1112913D02*
X351476Y1112912D01*
G01X351477Y1116058D02*
Y1116052D01*
G01X351476Y1116062D02*
X351477Y1116058D01*
G01X351475Y1116063D02*
X351476Y1116062D01*
G01X351477Y1122357D02*
Y1122351D01*
G01X351476Y1122361D02*
X351477Y1122357D01*
G01X351475Y1122362D02*
X351476Y1122361D01*
G01X350554Y1106617D02*
X350569Y1106614D01*
G01X350543Y1106624D02*
X350554Y1106617D01*
G01X350531Y1106643D02*
X350543Y1106624D01*
G01X350554Y1116066D02*
X350569Y1116063D01*
G01X350543Y1116073D02*
X350554Y1116066D01*
G01X350531Y1116091D02*
X350543Y1116073D01*
G01X351484Y1104644D02*
X351475Y1104646D01*
G01X351493Y1104641D02*
X351484Y1104644D01*
G01X351501Y1104636D02*
X351493Y1104641D01*
G01X351484Y1107794D02*
X351475Y1107795D01*
G01X351493Y1107791D02*
X351484Y1107794D01*
G01X351501Y1107786D02*
X351493Y1107791D01*
G01X350570Y1103460D02*
X350571Y1103454D01*
G01X350570Y1103463D02*
Y1103460D01*
G01X350569Y1103465D02*
X350570Y1103463D01*
G01Y1106609D02*
X350571Y1106603D01*
G01X350570Y1106613D02*
Y1106609D01*
G01X350569Y1106614D02*
X350570Y1106613D01*
G01Y1109759D02*
X350571Y1109753D01*
G01X350570Y1109763D02*
Y1109759D01*
G01X350569Y1109764D02*
X350570Y1109763D01*
G01Y1112909D02*
X350571Y1112902D01*
G01X350570Y1112912D02*
Y1112909D01*
G01X350569Y1112913D02*
X350570Y1112912D01*
G01Y1116058D02*
X350571Y1116052D01*
G01X350570Y1116062D02*
Y1116058D01*
G01X350569Y1116063D02*
X350570Y1116062D01*
G01Y1119208D02*
X350571Y1119202D01*
G01X350570Y1119211D02*
Y1119208D01*
G01X350569Y1119213D02*
X350570Y1119211D01*
G01Y1122357D02*
X350571Y1122351D01*
G01X350570Y1122361D02*
Y1122357D01*
G01X350569Y1122362D02*
X350570Y1122361D01*
G01X351484Y1110944D02*
X351475Y1110945D01*
G01X351493Y1110941D02*
X351484Y1110944D01*
G01X351501Y1110935D02*
X351493Y1110941D01*
G01X351484Y1114093D02*
X351475Y1114094D01*
G01X351493Y1114090D02*
X351484Y1114093D01*
G01X351501Y1114085D02*
X351493Y1114090D01*
G01X351484Y1117243D02*
X351475Y1117244D01*
G01X351493Y1117240D02*
X351484Y1117243D01*
G01X351501Y1117235D02*
X351493Y1117240D01*
G01X351484Y1120393D02*
X351475Y1120394D01*
G01X351493Y1120389D02*
X351484Y1120393D01*
G01X351501Y1120384D02*
X351493Y1120389D01*
G01X351484Y1123542D02*
X351475Y1123543D01*
G01X351493Y1123539D02*
X351484Y1123542D01*
G01X351501Y1123534D02*
X351493Y1123539D01*
G01X350531Y1112943D02*
Y1112939D01*
G01X350533Y1112938D02*
X350531Y1112943D01*
G01X350543Y1112923D02*
X350533Y1112938D01*
G01X350566Y1112914D02*
X350543Y1112923D01*
G01X350531Y1106644D02*
Y1106640D01*
G01X350533Y1106638D02*
X350531Y1106644D01*
G01X350545Y1106622D02*
X350533Y1106638D01*
G01X350570Y1106614D02*
X350545Y1106622D01*
G01X350531Y1109794D02*
Y1109790D01*
G01X350533Y1109787D02*
X350531Y1109794D01*
G01X350544Y1109772D02*
X350533Y1109787D01*
G01X350569Y1109764D02*
X350544Y1109772D01*
G01X350531Y1116093D02*
Y1116089D01*
G01X350533Y1116087D02*
X350531Y1116093D01*
G01X350544Y1116071D02*
X350533Y1116087D01*
G01X350569Y1116063D02*
X350544Y1116071D01*
G01X350531Y1119243D02*
Y1119239D01*
G01X350533Y1119236D02*
X350531Y1119243D01*
G01X350544Y1119221D02*
X350533Y1119236D01*
G01X350569Y1119213D02*
X350544Y1119221D01*
G01X350531Y1103494D02*
Y1103491D01*
G01X350533Y1103488D02*
X350531Y1103494D01*
G01X350544Y1103473D02*
X350533Y1103488D01*
G01X350569Y1103465D02*
X350544Y1103473D01*
G01X350531Y1122392D02*
Y1122388D01*
G01X350533Y1122386D02*
X350531Y1122392D01*
G01X350544Y1122370D02*
X350533Y1122386D01*
G01X350569Y1122362D02*
X350544Y1122370D01*
G01X351506Y1104644D02*
X351510Y1104639D01*
G01X351502Y1104648D02*
X351506Y1104644D01*
G01X351496Y1104652D02*
X351502Y1104648D01*
G01X351490Y1104655D02*
X351496Y1104652D01*
G01X351483Y1104657D02*
X351490Y1104655D01*
G01X351476Y1104657D02*
X351483D01*
G01X351506Y1107794D02*
X351510Y1107789D01*
G01X351502Y1107798D02*
X351506Y1107794D01*
G01X351496Y1107802D02*
X351502Y1107798D01*
G01X351490Y1107804D02*
X351496Y1107802D01*
G01X351483Y1107806D02*
X351490Y1107804D01*
G01X351476Y1107807D02*
X351483Y1107806D01*
G01X351506Y1110943D02*
X351510Y1110938D01*
G01X351502Y1110948D02*
X351506Y1110943D01*
G01X351496Y1110952D02*
X351502Y1110948D01*
G01X351490Y1110954D02*
X351496Y1110952D01*
G01X351483Y1110956D02*
X351490Y1110954D01*
G01X351476Y1110956D02*
X351483D01*
G01X351506Y1114093D02*
X351510Y1114088D01*
G01X351502Y1114097D02*
X351506Y1114093D01*
G01X351496Y1114101D02*
X351502Y1114097D01*
G01X351490Y1114104D02*
X351496Y1114101D01*
G01X351483Y1114106D02*
X351490Y1114104D01*
G01X351476Y1114106D02*
X351483D01*
G01X350532Y1103483D02*
X350531Y1103491D01*
G01X350535Y1103476D02*
X350532Y1103483D01*
G01X350538Y1103470D02*
X350535Y1103476D01*
G01X350543Y1103464D02*
X350538Y1103470D01*
G01X350549Y1103459D02*
X350543Y1103464D01*
G01X350556Y1103456D02*
X350549Y1103459D01*
G01X350563Y1103454D02*
X350556Y1103456D01*
G01X350571Y1103454D02*
X350563D01*
G01X350532Y1106633D02*
X350531Y1106640D01*
G01X350535Y1106626D02*
X350532Y1106633D01*
G01X350538Y1106620D02*
X350535Y1106626D01*
G01X350543Y1106614D02*
X350538Y1106620D01*
G01X350549Y1106609D02*
X350543Y1106614D01*
G01X350556Y1106606D02*
X350549Y1106609D01*
G01X350563Y1106604D02*
X350556Y1106606D01*
G01X350571Y1106603D02*
X350563Y1106604D01*
G01X350532Y1109782D02*
X350531Y1109790D01*
G01X350535Y1109776D02*
X350532Y1109782D01*
G01X350538Y1109769D02*
X350535Y1109776D01*
G01X350543Y1109763D02*
X350538Y1109769D01*
G01X350549Y1109759D02*
X350543Y1109763D01*
G01X350556Y1109756D02*
X350549Y1109759D01*
G01X350563Y1109754D02*
X350556Y1109756D01*
G01X350571Y1109753D02*
X350563Y1109754D01*
G01X350532Y1112932D02*
X350531Y1112939D01*
G01X350535Y1112925D02*
X350532Y1112932D01*
G01X350538Y1112919D02*
X350535Y1112925D01*
G01X350543Y1112913D02*
X350538Y1112919D01*
G01X350549Y1112908D02*
X350543Y1112913D01*
G01X350556Y1112905D02*
X350549Y1112908D01*
G01X350563Y1112903D02*
X350556Y1112905D01*
G01X350571Y1112902D02*
X350563Y1112903D01*
G01X350532Y1116081D02*
X350531Y1116089D01*
G01X350535Y1116075D02*
X350532Y1116081D01*
G01X350538Y1116069D02*
X350535Y1116075D01*
G01X350543Y1116063D02*
X350538Y1116069D01*
G01X350549Y1116058D02*
X350543Y1116063D01*
G01X350556Y1116055D02*
X350549Y1116058D01*
G01X350563Y1116053D02*
X350556Y1116055D01*
G01X350571Y1116052D02*
X350563Y1116053D01*
G01X350532Y1119231D02*
X350531Y1119239D01*
G01X350535Y1119224D02*
X350532Y1119231D01*
G01X350538Y1119218D02*
X350535Y1119224D01*
G01X350543Y1119212D02*
X350538Y1119218D01*
G01X350549Y1119207D02*
X350543Y1119212D01*
G01X350556Y1119204D02*
X350549Y1119207D01*
G01X350563Y1119202D02*
X350556Y1119204D01*
G01X350571Y1119202D02*
X350563D01*
G01X351485Y1104644D02*
X351495Y1104640D01*
G01X351475Y1104646D02*
X351485Y1104644D01*
G01Y1107794D02*
X351495Y1107790D01*
G01X351475Y1107795D02*
X351485Y1107794D01*
G01Y1110944D02*
X351495Y1110939D01*
G01X351475Y1110945D02*
X351485Y1110944D01*
G01Y1114093D02*
X351495Y1114089D01*
G01X351475Y1114094D02*
X351485Y1114093D01*
G01Y1117243D02*
X351495Y1117239D01*
G01X351475Y1117244D02*
X351485Y1117243D01*
G01Y1120393D02*
X351495Y1120388D01*
G01X351475Y1120394D02*
X351485Y1120393D01*
G01Y1123542D02*
X351495Y1123538D01*
G01X351475Y1123543D02*
X351485Y1123542D01*
G01X351493Y1103457D02*
X351496Y1103459D01*
G01X351490Y1103456D02*
X351493Y1103457D01*
G01X351487Y1103455D02*
X351490Y1103456D01*
G01X351483Y1103454D02*
X351487Y1103455D01*
G01X351480Y1103454D02*
X351483D01*
G01X351476D02*
X351480D01*
G01X350554Y1104654D02*
X350551Y1104652D01*
G01X350557Y1104655D02*
X350554Y1104654D01*
G01X350560Y1104656D02*
X350557Y1104655D01*
G01X350564Y1104656D02*
X350560D01*
G01X350567Y1104657D02*
X350564Y1104656D01*
G01X350571Y1104657D02*
X350567D01*
G01X351493Y1106607D02*
X351496Y1106608D01*
G01X351490Y1106606D02*
X351493Y1106607D01*
G01X351487Y1106604D02*
X351490Y1106606D01*
G01X351483Y1106604D02*
X351487D01*
G01X351480Y1106603D02*
X351483Y1106604D01*
G01X351476Y1106603D02*
X351480D01*
G01X350554Y1107803D02*
X350551Y1107802D01*
G01X350557Y1107804D02*
X350554Y1107803D01*
G01X350560Y1107806D02*
X350557Y1107804D01*
G01X350564Y1107806D02*
X350560D01*
G01X350567Y1107807D02*
X350564Y1107806D01*
G01X350571Y1107807D02*
X350567D01*
G01X351493Y1109756D02*
X351496Y1109758D01*
G01X351490Y1109755D02*
X351493Y1109756D01*
G01X351487Y1109754D02*
X351490Y1109755D01*
G01X351483Y1109753D02*
X351487Y1109754D01*
G01X351480Y1109753D02*
X351483D01*
G01X351476D02*
X351480D01*
G01X350554Y1110953D02*
X350551Y1110951D01*
G01X350557Y1110954D02*
X350554Y1110953D01*
G01X350560Y1110955D02*
X350557Y1110954D01*
G01X350564Y1110956D02*
X350560Y1110955D01*
G01X350567Y1110956D02*
X350564D01*
G01X350571D02*
X350567D01*
G01X351493Y1112906D02*
X351496Y1112907D01*
G01X351490Y1112905D02*
X351493Y1112906D01*
G01X351487Y1112904D02*
X351490Y1112905D01*
G01X351483Y1112903D02*
X351487Y1112904D01*
G01X351480Y1112902D02*
X351483Y1112903D01*
G01X351476Y1112902D02*
X351480D01*
G01X350554Y1114102D02*
X350551Y1114101D01*
G01X350557Y1114104D02*
X350554Y1114102D01*
G01X350560Y1114105D02*
X350557Y1114104D01*
G01X350564Y1114105D02*
X350560D01*
G01X350567Y1114106D02*
X350564Y1114105D01*
G01X350571Y1114106D02*
X350567D01*
G01X351493Y1116056D02*
X351496Y1116057D01*
G01X351490Y1116054D02*
X351493Y1116056D01*
G01X351487Y1116053D02*
X351490Y1116054D01*
G01X351483Y1116052D02*
X351487Y1116053D01*
G01X351480Y1116052D02*
X351483D01*
G01X351476D02*
X351480D01*
G01X350554Y1117252D02*
X350551Y1117250D01*
G01X350557Y1117253D02*
X350554Y1117252D01*
G01X350560Y1117254D02*
X350557Y1117253D01*
G01X350564Y1117255D02*
X350560Y1117254D01*
G01X350567Y1117256D02*
X350564Y1117255D01*
G01X350571Y1117256D02*
X350567D01*
G01X350554Y1120402D02*
X350551Y1120400D01*
G01X350557Y1120403D02*
X350554Y1120402D01*
G01X350560Y1120404D02*
X350557Y1120403D01*
G01X350564Y1120404D02*
X350560D01*
G01X350567Y1120405D02*
X350564Y1120404D01*
G01X350571Y1120405D02*
X350567D01*
G01X351493Y1122355D02*
X351496Y1122356D01*
G01X351490Y1122354D02*
X351493Y1122355D01*
G01X351487Y1122352D02*
X351490Y1122354D01*
G01X351483Y1122352D02*
X351487D01*
G01X351480Y1122351D02*
X351483Y1122352D01*
G01X351476Y1122351D02*
X351480D01*
G01X350554Y1123551D02*
X350551Y1123550D01*
G01X350557Y1123552D02*
X350554Y1123551D01*
G01X350560Y1123554D02*
X350557Y1123552D01*
G01X350564Y1123554D02*
X350560D01*
G01X350567Y1123555D02*
X350564Y1123554D01*
G01X350571Y1123555D02*
X350567D01*
G01X349784Y1106654D02*
X349350D01*
G01X350158D02*
X349784D01*
G01Y1112953D02*
X349350D01*
G01X350158D02*
X349784D01*
G01Y1116102D02*
X349350D01*
G01X350157D02*
X349784D01*
G01X351506Y1117243D02*
X351510Y1117237D01*
G01X351502Y1117247D02*
X351506Y1117243D01*
G01X351496Y1117251D02*
X351502Y1117247D01*
G01X351490Y1117253D02*
X351496Y1117251D01*
G01X351483Y1117255D02*
X351490Y1117253D01*
G01X351476Y1117256D02*
X351483Y1117255D01*
G01X351506Y1120392D02*
X351510Y1120387D01*
G01X351502Y1120396D02*
X351506Y1120392D01*
G01X351496Y1120400D02*
X351502Y1120396D01*
G01X351490Y1120403D02*
X351496Y1120400D01*
G01X351483Y1120405D02*
X351490Y1120403D01*
G01X351476Y1120405D02*
X351483D01*
G01X351506Y1123542D02*
X351510Y1123537D01*
G01X351502Y1123546D02*
X351506Y1123542D01*
G01X351496Y1123550D02*
X351502Y1123546D01*
G01X351490Y1123552D02*
X351496Y1123550D01*
G01X351483Y1123554D02*
X351490Y1123552D01*
G01X351476Y1123555D02*
X351483Y1123554D01*
G01X350532Y1122381D02*
X350531Y1122388D01*
G01X350535Y1122374D02*
X350532Y1122381D01*
G01X350538Y1122368D02*
X350535Y1122374D01*
G01X350543Y1122362D02*
X350538Y1122368D01*
G01X350549Y1122357D02*
X350543Y1122362D01*
G01X350556Y1122354D02*
X350549Y1122357D01*
G01X350563Y1122352D02*
X350556Y1122354D01*
G01X350571Y1122351D02*
X350563Y1122352D01*
G01X351515Y1119231D02*
X351516Y1119239D01*
G01X351513Y1119224D02*
X351515Y1119231D01*
G01X351509Y1119218D02*
X351513Y1119224D01*
G01X351504Y1119212D02*
X351509Y1119218D01*
G01X351498Y1119207D02*
X351504Y1119212D01*
G01X351491Y1119204D02*
X351498Y1119207D01*
G01X351484Y1119202D02*
X351491Y1119204D01*
G01X351476Y1119202D02*
X351484D01*
G01X350534Y1104626D02*
X350529Y1104606D01*
G01X350549Y1104641D02*
X350534Y1104626D01*
G01X350569Y1104646D02*
X350549Y1104641D01*
G01X350534Y1107776D02*
X350529Y1107756D01*
G01X350549Y1107790D02*
X350534Y1107776D01*
G01X350569Y1107795D02*
X350549Y1107790D01*
G01X350534Y1110925D02*
X350529Y1110906D01*
G01X350549Y1110940D02*
X350534Y1110925D01*
G01X350569Y1110945D02*
X350549Y1110940D01*
G01X350534Y1114075D02*
X350529Y1114055D01*
G01X350549Y1114089D02*
X350534Y1114075D01*
G01X350569Y1114094D02*
X350549Y1114089D01*
G01X350534Y1117224D02*
X350529Y1117205D01*
G01X350549Y1117239D02*
X350534Y1117224D01*
G01X350569Y1117244D02*
X350549Y1117239D01*
G01X350534Y1120374D02*
X350529Y1120354D01*
G01X350549Y1120389D02*
X350534Y1120374D01*
G01X350569Y1120394D02*
X350549Y1120389D01*
G01X350534Y1123524D02*
X350529Y1123504D01*
G01X350549Y1123538D02*
X350534Y1123524D01*
G01X350569Y1123543D02*
X350549Y1123538D01*
G01X351509Y1103484D02*
X351514Y1103504D01*
G01X351494Y1103470D02*
X351509Y1103484D01*
G01X351475Y1103465D02*
X351494Y1103470D01*
G01X351509Y1106634D02*
X351514Y1106654D01*
G01X351494Y1106620D02*
X351509Y1106634D01*
G01X351475Y1106614D02*
X351494Y1106620D01*
G01X351509Y1109783D02*
X351514Y1109803D01*
G01X351494Y1109769D02*
X351509Y1109783D01*
G01X351475Y1109764D02*
X351494Y1109769D01*
G01X351509Y1112933D02*
X351514Y1112953D01*
G01X351494Y1112919D02*
X351509Y1112933D01*
G01X351475Y1112913D02*
X351494Y1112919D01*
G01X351509Y1116083D02*
X351514Y1116102D01*
G01X351494Y1116069D02*
X351509Y1116083D01*
G01X351475Y1116063D02*
X351494Y1116069D01*
G01X351509Y1119232D02*
X351514Y1119252D01*
G01X351494Y1119218D02*
X351509Y1119232D01*
G01X351475Y1119213D02*
X351494Y1119218D01*
G01X351509Y1122382D02*
X351514Y1122402D01*
G01X351494Y1122368D02*
X351509Y1122382D01*
G01X351475Y1122362D02*
X351494Y1122368D01*
G01X350418Y1122402D02*
X350530Y1122393D01*
G01X350529Y1112949D02*
X350418Y1112953D01*
G01X350529Y1106650D02*
X350418Y1106654D01*
G01X350529Y1116099D02*
X350418Y1116102D01*
G01X351969Y1125709D02*
X348622D01*
G01X361614Y1124547D02*
X365551D01*
G01X351476Y1123740D02*
X350571D01*
G01X351516Y1123701D02*
X350531D01*
G01X351475Y1123543D02*
X345591D01*
G01Y1123504D02*
X351515D01*
G01X360433Y1123366D02*
X364370D01*
G01X351514Y1122402D02*
X345591D01*
G01X351475Y1122362D02*
X345591D01*
G01X350531Y1122205D02*
X351516D01*
G01X350571Y1122165D02*
X351476D01*
G01Y1120591D02*
X350571D01*
G01X351516Y1120551D02*
X350531D01*
G01X351475Y1120394D02*
X345591D01*
G01Y1120354D02*
X351515D01*
G01X351514Y1119252D02*
X345591D01*
G01X351475Y1119213D02*
X345591D01*
G01X350531Y1119055D02*
X351516D01*
G01X350571Y1119016D02*
X351476D01*
G01Y1117441D02*
X350571D01*
G01X351516Y1117402D02*
X350531D01*
G01X351475Y1117244D02*
X345591D01*
G01Y1117205D02*
X351515D01*
G01X351514Y1116102D02*
X345591D01*
G01X351475Y1116063D02*
X345591D01*
G01X350531Y1115906D02*
X351516D01*
G01X350571Y1115866D02*
X351476D01*
G01Y1114291D02*
X350571D01*
G01X351516Y1114252D02*
X350531D01*
G01X351475Y1114094D02*
X345591D01*
G01Y1114055D02*
X351515D01*
G01X351514Y1112953D02*
X345591D01*
G01X351475Y1112913D02*
X345591D01*
G01X350531Y1112756D02*
X351516D01*
G01X350571Y1112717D02*
X351476D01*
G01Y1111142D02*
X350571D01*
G01X351516Y1111102D02*
X350531D01*
G01X351475Y1110945D02*
X345591D01*
G01Y1110906D02*
X351515D01*
G01X351514Y1109803D02*
X345591D01*
G01X351475Y1109764D02*
X345591D01*
G01X350531Y1109606D02*
X351516D01*
G01X350571Y1109567D02*
X351476D01*
G01Y1107992D02*
X350571D01*
G01X351516Y1107953D02*
X350531D01*
G01X351475Y1107795D02*
X345591D01*
G01Y1107756D02*
X351515D01*
G01X351514Y1106654D02*
X345591D01*
G01X351475Y1106614D02*
X345591D01*
G01X350531Y1106457D02*
X351516D01*
G01X350571Y1106417D02*
X351476D01*
G01Y1104843D02*
X350571D01*
G01X351516Y1104803D02*
X350531D01*
G01X351475Y1104646D02*
X345591D01*
G01Y1104606D02*
X351515D01*
G01X364370Y1103642D02*
X360433D01*
G01X351514Y1103504D02*
X345591D01*
G01X351475Y1103465D02*
X345591D01*
G01X350531Y1103307D02*
X351516D01*
G01X350571Y1103268D02*
X351476D01*
G01X365551Y1102461D02*
X361614D01*
G01X351969Y1101299D02*
X348622D01*
G01X360433Y1103642D02*
X361614Y1102461D01*
G01X351475Y1119213D02*
X351478Y1119202D01*
G01X361614Y1201004D02*
Y1124547D01*
G01X360433Y1199823D02*
Y1123366D01*
G01X351969Y1204744D02*
Y1125709D01*
G01X351516Y1122205D02*
Y1123701D01*
G01Y1119055D02*
Y1120551D01*
G01Y1115906D02*
Y1117402D01*
G01Y1112756D02*
Y1114252D01*
G01Y1109606D02*
Y1111102D01*
G01Y1106457D02*
Y1107953D01*
G01Y1103307D02*
Y1104803D01*
G01X351476Y1106603D02*
Y1106456D01*
G01Y1103454D02*
Y1103307D01*
G01Y1104804D02*
Y1104657D01*
G01Y1109753D02*
Y1109606D01*
G01Y1111103D02*
Y1110956D01*
G01Y1107953D02*
Y1107807D01*
G01Y1116052D02*
Y1115905D01*
G01Y1112902D02*
Y1112756D01*
G01Y1114252D02*
Y1114106D01*
G01Y1119202D02*
Y1119055D01*
G01Y1120552D02*
Y1120405D01*
G01Y1117402D02*
Y1117256D01*
G01Y1122351D02*
Y1122204D01*
G01Y1123701D02*
Y1123555D01*
G01X351516Y1122388D02*
X351515Y1122399D01*
G01X351516Y1119239D02*
X351515Y1119250D01*
G01X351516Y1116089D02*
X351515Y1116100D01*
G01X351516Y1112939D02*
X351515Y1112950D01*
G01X351516Y1109790D02*
X351515Y1109801D01*
G01X351516Y1106640D02*
X351515Y1106651D01*
G01X351516Y1103491D02*
X351515Y1103502D01*
G01X360433Y1123366D02*
X361614Y1124547D01*
G01X351515Y1104609D02*
X351516Y1104620D01*
G01X351515Y1107758D02*
X351516Y1107769D01*
G01X351515Y1110908D02*
X351516Y1110919D01*
G01X351515Y1114057D02*
X351516Y1114069D01*
G01X351515Y1117207D02*
X351516Y1117218D01*
G01X351515Y1120357D02*
X351516Y1120368D01*
G01X351515Y1123506D02*
X351516Y1123517D01*
G01X350571Y1122204D02*
Y1122351D01*
G01Y1123555D02*
Y1123702D01*
G01Y1119054D02*
Y1119202D01*
G01Y1120405D02*
Y1120552D01*
G01Y1117256D02*
Y1117402D01*
G01Y1115905D02*
Y1116052D01*
G01Y1112755D02*
Y1112902D01*
G01Y1114106D02*
Y1114253D01*
G01Y1109606D02*
Y1109753D01*
G01Y1110956D02*
Y1111103D01*
G01Y1107807D02*
Y1107954D01*
G01Y1106456D02*
Y1106603D01*
G01Y1103306D02*
Y1103454D01*
G01Y1104657D02*
Y1104804D01*
G01X350531Y1104803D02*
Y1103307D01*
G01Y1111102D02*
Y1109606D01*
G01Y1107953D02*
Y1106457D01*
G01Y1114252D02*
Y1112756D01*
G01Y1120551D02*
Y1119055D01*
G01Y1117402D02*
Y1115906D01*
G01Y1123701D02*
Y1122205D01*
G01X349350Y1107795D02*
Y1106614D01*
G01Y1104646D02*
Y1103465D01*
G01Y1110945D02*
Y1109764D01*
G01Y1117244D02*
Y1116063D01*
G01Y1114094D02*
Y1112913D01*
G01Y1120394D02*
Y1119213D01*
G01Y1123543D02*
Y1122362D01*
G01X349016Y1125709D02*
Y1101299D01*
G01X348622D02*
Y1125709D01*
G01X345591Y1122362D02*
Y1123543D01*
G01Y1119213D02*
Y1120394D01*
G01Y1116063D02*
Y1117244D01*
G01Y1112913D02*
Y1114094D01*
G01Y1109764D02*
Y1110945D01*
G01Y1106614D02*
Y1107795D01*
G01Y1103465D02*
Y1104646D01*
G01X356102Y1222776D02*
G03X355512Y1222185I1J-591D01*
G01X358268Y1221004D02*
G03Y1219035I0J-985D01*
G01X360630D02*
G03Y1221004I0J985D01*
G01X350591Y1223563D02*
G03X348622Y1221594I-1J-1968D01*
G01X356890Y1213091D02*
G03X355709Y1211909I0J-1181D01*
G01X363189D02*
G03X362008Y1213091I-1181J1D01*
G01X361339Y1207815D02*
G03I-1890J0D01*
G01X361811D02*
G03I-2362J0D01*
G01X368307Y1223563D02*
X350591D01*
G01X362795Y1222776D02*
X356102D01*
G01X360630Y1221004D02*
X358268D01*
G01Y1219035D02*
X360630D01*
G01X363386Y1217657D02*
X355512D01*
G01Y1216083D02*
X363386D01*
G01X370276Y1213130D02*
X348622D01*
G01X356890Y1213091D02*
X362008D01*
G01X358268Y1208406D02*
X360630D01*
G01X358268Y1206713D02*
X360630D01*
G01X351969Y1204744D02*
X366339D01*
G01X351969Y1203366D02*
X355709D01*
G01X351969Y1202500D02*
X366929D01*
G01X353740Y1201004D02*
X361614D01*
G01X354921Y1199823D02*
X360433D01*
G01X353740Y1201004D02*
X354921Y1199823D01*
G01X348622Y1205846D02*
X351969Y1202500D01*
G01X358268Y1208406D02*
X355957Y1212635D01*
G01X360630Y1206713D02*
X361933Y1204744D01*
G01X360630Y1208406D02*
Y1206713D01*
G01X358268D02*
Y1208406D01*
G01X355709Y1203366D02*
Y1211909D01*
G01X355512Y1216083D02*
Y1222185D01*
G01X348622Y1221594D02*
Y1205846D01*
G01X360433Y1199823D02*
X361614Y1201004D01*
G01X356964Y1204744D02*
X358268Y1206713D01*
G01X362940Y1212635D02*
X360630Y1208406D01*
G01X362327Y1284397D02*
G03X396138I16905J-13531D01*
G01X362327D02*
G03X396138I16905J-13531D01*
G01X320669Y1274016D02*
G03X319488I-591J0D01*
G01X317520D02*
G03X316339I-590J0D01*
G01X320669D02*
G03X319488I-591J0D01*
G01X317520D02*
G03X316339I-590J0D01*
G01X315551Y1275197D02*
X321457D01*
G01Y1275000D02*
X315551D01*
G01X320669Y1274016D02*
X321457D01*
G01X320669D02*
X321457D01*
G01X317520D02*
X319488D01*
G01X317520D02*
X319488D01*
G01X315551D02*
X316339D01*
G01X315551D02*
X316339D01*
G01X321457D02*
Y1280315D01*
G01Y1274016D02*
Y1280315D01*
G01X315551Y1274016D02*
Y1280315D01*
G01D02*
Y1274016D01*
G01X362327Y1284397D02*
G03X369252Y1297528I-30737J24602D01*
G01X362327Y1284397D02*
G03X369252Y1297528I-30737J24602D01*
G01X319488Y1280315D02*
G03X320669I590J0D01*
G01X316339D02*
G03X317520I590J0D01*
G01X319488D02*
G03X320669I590J0D01*
G01X316339D02*
G03X317520I590J0D01*
G01X316339D02*
X315551D01*
G01X316339D02*
X315551D01*
G01X319488D02*
X317520D01*
G01X319488D02*
X317520D01*
G01X321457D02*
X320669D01*
G01X321457D02*
X320669D01*
G01X321457Y1279331D02*
X315551D01*
G01Y1279134D02*
X321457D01*
G01X353740Y1374803D02*
G03Y1382677I0J3937D01*
G01Y1374803D02*
G03Y1382677I0J3937D01*
G01X320567Y1841823D02*
Y1822886D01*
G01X397638Y-7874D02*
G03X409449Y3937I0J11811D01*
G01D02*
Y51181D01*
G01X362598Y-7874D02*
X397638D01*
G01X401575Y3937D02*
Y55118D01*
G01X397638Y0D02*
G03X401575Y3937I0J3937D01*
G01X362598Y-7874D02*
X397638D01*
G01D02*
G03X409449Y3937I0J11811D01*
G01D02*
Y51181D01*
G01X397638Y0D02*
G03X401575Y3937I0J3937D01*
G01D02*
Y55118D01*
G01X409449Y51181D02*
X582677D01*
G01X405512Y59055D02*
X586614D01*
G01X405512D02*
G03X401575Y55118I0J-3937D01*
G01X409449Y51181D02*
X582677D01*
G01X405512Y59055D02*
G03X401575Y55118I0J-3937D01*
G01X405512Y59055D02*
X586614D01*
G01X362795Y138720D02*
G03X363386Y139311I0J591D01*
G01X368307Y137933D02*
G03X370276Y139902I0J1969D01*
G01D02*
Y155650D01*
G01X366929Y296988D02*
Y158996D01*
G01X366339Y299232D02*
Y156752D01*
G01X363386Y145413D02*
Y139311D01*
G01X363189Y158130D02*
Y149587D01*
G01Y158130D02*
X366339D01*
G01X366929Y158996D02*
X370276Y155650D01*
G01X364941Y166148D02*
Y166156D01*
G01X364942Y166144D02*
X364941Y166148D01*
G01X364943Y166142D02*
X364942Y166144D01*
G01X364941Y171148D02*
Y171156D01*
G01X364942Y171144D02*
X364941Y171148D01*
G01X364943Y171142D02*
X364942Y171144D01*
G01X364941Y176148D02*
Y176156D01*
G01X364942Y176144D02*
X364941Y176148D01*
G01X364943Y176142D02*
X364942Y176144D01*
G01X364941Y181148D02*
Y181156D01*
G01X364942Y181144D02*
X364941Y181148D01*
G01X364943Y181142D02*
X364942Y181144D01*
G01X364941Y186148D02*
Y186156D01*
G01X364942Y186144D02*
X364941Y186148D01*
G01X364943Y186142D02*
X364942Y186144D01*
G01X364941Y191148D02*
Y191156D01*
G01X364942Y191144D02*
X364941Y191148D01*
G01X364943Y191142D02*
X364942Y191144D01*
G01X364941Y196148D02*
Y196156D01*
G01X364942Y196144D02*
X364941Y196148D01*
G01X364943Y196142D02*
X364942Y196144D01*
G01X363957Y166189D02*
Y166198D01*
G01Y166183D02*
Y166189D01*
G01X363958Y166181D02*
X363957Y166183D01*
G01Y171189D02*
Y171198D01*
G01Y171183D02*
Y171189D01*
G01X363958Y171181D02*
X363957Y171183D01*
G01Y176189D02*
Y176198D01*
G01Y176183D02*
Y176189D01*
G01X363958Y176181D02*
X363957Y176183D01*
G01X364933Y166325D02*
X364941Y166299D01*
G01X364923Y166352D02*
X364933Y166325D01*
G01X364912Y166378D02*
X364923Y166352D01*
G01X364928Y166173D02*
X364939Y166157D01*
G01X364904Y166181D02*
X364928Y166173D01*
G01Y171173D02*
X364939Y171157D01*
G01X364904Y171181D02*
X364928Y171173D01*
G01Y176173D02*
X364939Y176157D01*
G01X364904Y176181D02*
X364928Y176173D01*
G01Y181173D02*
X364939Y181157D01*
G01X364904Y181181D02*
X364928Y181173D01*
G01Y186173D02*
X364939Y186157D01*
G01X364904Y186181D02*
X364928Y186173D01*
G01Y191173D02*
X364939Y191157D01*
G01X364904Y191181D02*
X364928Y191173D01*
G01Y196173D02*
X364939Y196157D01*
G01X364904Y196181D02*
X364928Y196173D01*
G01X363957Y181189D02*
Y181198D01*
G01Y181183D02*
Y181189D01*
G01X363958Y181181D02*
X363957Y181183D01*
G01Y186189D02*
Y186198D01*
G01Y186183D02*
Y186189D01*
G01X363958Y186181D02*
X363957Y186183D01*
G01Y191189D02*
Y191198D01*
G01Y191183D02*
Y191189D01*
G01X363958Y191181D02*
X363957Y191183D01*
G01Y196189D02*
Y196198D01*
G01Y196183D02*
Y196189D01*
G01X363958Y196181D02*
X363957Y196183D01*
G01X364933Y171325D02*
X364941Y171299D01*
G01X364923Y171352D02*
X364933Y171325D01*
G01X364912Y171378D02*
X364923Y171352D01*
G01X364933Y176325D02*
X364941Y176299D01*
G01X364923Y176352D02*
X364933Y176325D01*
G01X364912Y176378D02*
X364923Y176352D01*
G01X364933Y181325D02*
X364941Y181299D01*
G01X364923Y181352D02*
X364933Y181325D01*
G01X364912Y181378D02*
X364923Y181352D01*
G01X364933Y186325D02*
X364941Y186299D01*
G01X364923Y186352D02*
X364933Y186325D01*
G01X364912Y186378D02*
X364923Y186352D01*
G01X364933Y191325D02*
X364941Y191299D01*
G01X364923Y191352D02*
X364933Y191325D01*
G01X364912Y191378D02*
X364923Y191352D01*
G01X364933Y196325D02*
X364941Y196299D01*
G01X364923Y196352D02*
X364933Y196325D01*
G01X364912Y196378D02*
X364923Y196352D01*
G01X364924Y166176D02*
X364904Y166181D01*
G01X364938Y166162D02*
X364924Y166176D01*
G01X364943Y166142D02*
X364938Y166162D01*
G01X364924Y171176D02*
X364904Y171181D01*
G01X364938Y171162D02*
X364924Y171176D01*
G01X364943Y171142D02*
X364938Y171162D01*
G01X364924Y176176D02*
X364904Y176181D01*
G01X364938Y176162D02*
X364924Y176176D01*
G01X364943Y176142D02*
X364938Y176162D01*
G01X364924Y181176D02*
X364904Y181181D01*
G01X364938Y181162D02*
X364924Y181176D01*
G01X364943Y181142D02*
X364938Y181162D01*
G01X364924Y186176D02*
X364904Y186181D01*
G01X364938Y186162D02*
X364924Y186176D01*
G01X364943Y186142D02*
X364938Y186162D01*
G01X364924Y191176D02*
X364904Y191181D01*
G01X364938Y191162D02*
X364924Y191176D01*
G01X364943Y191142D02*
X364938Y191162D01*
G01X364924Y196176D02*
X364904Y196181D01*
G01X364938Y196162D02*
X364924Y196176D01*
G01X364943Y196142D02*
X364938Y196162D01*
G01X364908Y166279D02*
X364912Y166378D01*
G01X364902Y166207D02*
X364908Y166279D01*
G01X364904Y166181D02*
X364902Y166207D01*
G01X364908Y171279D02*
X364912Y171378D01*
G01X364902Y171207D02*
X364908Y171279D01*
G01X364904Y171181D02*
X364902Y171207D01*
G01X364908Y176279D02*
X364912Y176378D01*
G01X364902Y176207D02*
X364908Y176279D01*
G01X364904Y176181D02*
X364902Y176207D01*
G01X364908Y181279D02*
X364912Y181378D01*
G01X364902Y181207D02*
X364908Y181279D01*
G01X364904Y181181D02*
X364902Y181207D01*
G01X364908Y186279D02*
X364912Y186378D01*
G01X364902Y186207D02*
X364908Y186279D01*
G01X364904Y186181D02*
X364902Y186207D01*
G01X364908Y191279D02*
X364912Y191378D01*
G01X364902Y191207D02*
X364908Y191279D01*
G01X364904Y191181D02*
X364902Y191207D01*
G01X364908Y196279D02*
X364912Y196378D01*
G01X364902Y196207D02*
X364908Y196279D01*
G01X364904Y196181D02*
X364902Y196207D01*
G01X363957Y194802D02*
X363958Y194803D01*
G01X363957Y194796D02*
Y194802D01*
G01Y194787D02*
Y194796D01*
G01Y189802D02*
X363958Y189803D01*
G01X363957Y189796D02*
Y189802D01*
G01Y189787D02*
Y189796D01*
G01Y184802D02*
X363958Y184803D01*
G01X363957Y184796D02*
Y184802D01*
G01Y184787D02*
Y184796D01*
G01Y179802D02*
X363958Y179803D01*
G01X363957Y179796D02*
Y179802D01*
G01Y179787D02*
Y179796D01*
G01Y174802D02*
X363958Y174803D01*
G01X363957Y174796D02*
Y174802D01*
G01Y174787D02*
Y174796D01*
G01Y169802D02*
X363958Y169803D01*
G01X363957Y169796D02*
Y169802D01*
G01Y169787D02*
Y169796D01*
G01Y164802D02*
X363958Y164803D01*
G01X363957Y164796D02*
Y164802D01*
G01Y164787D02*
Y164796D01*
G01X364941Y194796D02*
Y194787D01*
G01X364942Y194802D02*
X364941Y194796D01*
G01X364944Y194803D02*
X364942Y194802D01*
G01X364941Y189796D02*
Y189787D01*
G01X364942Y189802D02*
X364941Y189796D01*
G01X364944Y189803D02*
X364942Y189802D01*
G01X364941Y184796D02*
Y184787D01*
G01X364942Y184802D02*
X364941Y184796D01*
G01X364944Y184803D02*
X364942Y184802D01*
G01X364941Y179796D02*
Y179787D01*
G01X364942Y179802D02*
X364941Y179796D01*
G01X364944Y179803D02*
X364942Y179802D01*
G01X364941Y174796D02*
Y174787D01*
G01X364942Y174802D02*
X364941Y174796D01*
G01X364944Y174803D02*
X364942Y174802D01*
G01X364941Y169796D02*
Y169787D01*
G01X364942Y169802D02*
X364941Y169796D01*
G01X364944Y169803D02*
X364942Y169802D01*
G01X364941Y164796D02*
Y164787D01*
G01X364942Y164802D02*
X364941Y164796D01*
G01X364944Y164803D02*
X364942Y164802D01*
G01X364941Y196673D02*
X363957D01*
G01X363958Y196181D02*
X369291D01*
G01Y196142D02*
X364943D01*
G01X369291Y194803D02*
X363958D01*
G01X363957Y194311D02*
X364941D01*
G01Y191673D02*
X363957D01*
G01X363958Y191181D02*
X369291D01*
G01Y191142D02*
X364943D01*
G01X369291Y189803D02*
X363958D01*
G01X363957Y189311D02*
X364941D01*
G01Y186673D02*
X363957D01*
G01X363958Y186181D02*
X369291D01*
G01Y186142D02*
X364943D01*
G01X369291Y184803D02*
X363958D01*
G01X363957Y184311D02*
X364941D01*
G01Y181673D02*
X363957D01*
G01X363958Y181181D02*
X369291D01*
G01Y181142D02*
X364943D01*
G01X369291Y179803D02*
X363958D01*
G01X363957Y179311D02*
X364941D01*
G01Y176673D02*
X363957D01*
G01X363958Y176181D02*
X369291D01*
G01Y176142D02*
X364943D01*
G01X369291Y174803D02*
X363958D01*
G01X363957Y174311D02*
X364941D01*
G01Y171673D02*
X363957D01*
G01X363958Y171181D02*
X369291D01*
G01Y171142D02*
X364943D01*
G01X369291Y169803D02*
X363958D01*
G01X363957Y169311D02*
X364941D01*
G01X363957Y196377D02*
X364912Y196378D01*
G01X364941Y194607D02*
X363957Y194606D01*
G01Y191377D02*
X364912Y191378D01*
G01X364941Y189607D02*
X363957Y189606D01*
G01Y186377D02*
X364912Y186378D01*
G01X364941Y184607D02*
X363957Y184606D01*
G01Y181377D02*
X364912Y181378D01*
G01X364941Y179607D02*
X363957Y179606D01*
G01Y176377D02*
X364912Y176378D01*
G01X364941Y174607D02*
X363957Y174606D01*
G01Y171377D02*
X364912Y171378D01*
G01X364941Y169607D02*
X363957Y169606D01*
G01Y166377D02*
X364912Y166378D01*
G01X364941Y166155D02*
Y166164D01*
G01Y171155D02*
Y171164D01*
G01Y176155D02*
Y176164D01*
G01Y181155D02*
Y181164D01*
G01Y186155D02*
Y186164D01*
G01Y191155D02*
Y191164D01*
G01Y196155D02*
Y196164D01*
G01X369291Y194803D02*
Y196181D01*
G01Y189803D02*
Y191181D01*
G01Y184803D02*
Y186181D01*
G01Y179803D02*
Y181181D01*
G01Y174803D02*
Y176181D01*
G01Y169803D02*
Y171181D01*
G01Y164803D02*
Y166181D01*
G01X366122D02*
Y164803D01*
G01Y171181D02*
Y169803D01*
G01Y176181D02*
Y174803D01*
G01Y181181D02*
Y179803D01*
G01Y186181D02*
Y184803D01*
G01Y191181D02*
Y189803D01*
G01Y196181D02*
Y194803D01*
G01X365551Y219035D02*
Y196949D01*
G01X364941Y166156D02*
Y166299D01*
G01Y176156D02*
Y176299D01*
G01Y171156D02*
Y171299D01*
G01Y186156D02*
Y186299D01*
G01Y181156D02*
Y181299D01*
G01Y196156D02*
Y196299D01*
G01Y191156D02*
Y191299D01*
G01Y194311D02*
Y196673D01*
G01Y189311D02*
Y191673D01*
G01Y184311D02*
Y186673D01*
G01Y179311D02*
Y181673D01*
G01Y174311D02*
Y176673D01*
G01Y169311D02*
Y171673D01*
G01Y164311D02*
Y166673D01*
G01X364370Y217854D02*
Y198130D01*
G01X363957Y166673D02*
Y164311D01*
G01Y171673D02*
Y169311D01*
G01Y176673D02*
Y174311D01*
G01Y181673D02*
Y179311D01*
G01Y186673D02*
Y184311D01*
G01Y191673D02*
Y189311D01*
G01Y196673D02*
Y194311D01*
G01X364941Y166673D02*
X363957D01*
G01X363958Y166181D02*
X369291D01*
G01Y166142D02*
X364943D01*
G01X369291Y164803D02*
X363958D01*
G01X363957Y164311D02*
X364941D01*
G01Y164607D02*
X363957Y164606D01*
G01X364370Y198130D02*
X365551Y196949D01*
G01X364941Y221148D02*
Y221156D01*
G01X364942Y221144D02*
X364941Y221148D01*
G01X364943Y221142D02*
X364942Y221144D01*
G01X364941Y226148D02*
Y226156D01*
G01X364942Y226144D02*
X364941Y226148D01*
G01X364943Y226142D02*
X364942Y226144D01*
G01X364941Y231148D02*
Y231156D01*
G01X364942Y231144D02*
X364941Y231148D01*
G01X364943Y231142D02*
X364942Y231144D01*
G01X364941Y236148D02*
Y236156D01*
G01X364942Y236144D02*
X364941Y236148D01*
G01X364943Y236142D02*
X364942Y236144D01*
G01X364941Y241148D02*
Y241156D01*
G01X364942Y241144D02*
X364941Y241148D01*
G01X364943Y241142D02*
X364942Y241144D01*
G01X364941Y246148D02*
Y246156D01*
G01X364942Y246144D02*
X364941Y246148D01*
G01X364943Y246142D02*
X364942Y246144D01*
G01X364941Y251148D02*
Y251156D01*
G01X364942Y251144D02*
X364941Y251148D01*
G01X364943Y251142D02*
X364942Y251144D01*
G01X364941Y256148D02*
Y256156D01*
G01X364942Y256144D02*
X364941Y256148D01*
G01X364943Y256142D02*
X364942Y256144D01*
G01X364928Y221173D02*
X364939Y221157D01*
G01X364904Y221181D02*
X364928Y221173D01*
G01Y226173D02*
X364939Y226157D01*
G01X364904Y226181D02*
X364928Y226173D01*
G01Y231173D02*
X364939Y231157D01*
G01X364904Y231181D02*
X364928Y231173D01*
G01Y236173D02*
X364939Y236157D01*
G01X364904Y236181D02*
X364928Y236173D01*
G01Y241173D02*
X364939Y241157D01*
G01X364904Y241181D02*
X364928Y241173D01*
G01Y246173D02*
X364939Y246157D01*
G01X364904Y246181D02*
X364928Y246173D01*
G01X363957Y221189D02*
Y221198D01*
G01Y221183D02*
Y221189D01*
G01X363958Y221181D02*
X363957Y221183D01*
G01Y226189D02*
Y226198D01*
G01Y226183D02*
Y226189D01*
G01X363958Y226181D02*
X363957Y226183D01*
G01Y231189D02*
Y231198D01*
G01Y231183D02*
Y231189D01*
G01X363958Y231181D02*
X363957Y231183D01*
G01Y236189D02*
Y236198D01*
G01Y236183D02*
Y236189D01*
G01X363958Y236181D02*
X363957Y236183D01*
G01Y241189D02*
Y241198D01*
G01Y241183D02*
Y241189D01*
G01X363958Y241181D02*
X363957Y241183D01*
G01Y246189D02*
Y246198D01*
G01Y246183D02*
Y246189D01*
G01X363958Y246181D02*
X363957Y246183D01*
G01Y251189D02*
Y251198D01*
G01Y251183D02*
Y251189D01*
G01X363958Y251181D02*
X363957Y251183D01*
G01Y256189D02*
Y256198D01*
G01Y256183D02*
Y256189D01*
G01X363958Y256181D02*
X363957Y256183D01*
G01X364933Y221325D02*
X364941Y221299D01*
G01X364923Y221352D02*
X364933Y221325D01*
G01X364912Y221378D02*
X364923Y221352D01*
G01X364933Y226325D02*
X364941Y226299D01*
G01X364923Y226352D02*
X364933Y226325D01*
G01X364912Y226378D02*
X364923Y226352D01*
G01X364933Y231325D02*
X364941Y231299D01*
G01X364923Y231352D02*
X364933Y231325D01*
G01X364912Y231378D02*
X364923Y231352D01*
G01X364933Y236325D02*
X364941Y236299D01*
G01X364923Y236352D02*
X364933Y236325D01*
G01X364912Y236378D02*
X364923Y236352D01*
G01X364933Y241325D02*
X364941Y241299D01*
G01X364923Y241352D02*
X364933Y241325D01*
G01X364912Y241378D02*
X364923Y241352D01*
G01X364933Y246325D02*
X364941Y246299D01*
G01X364923Y246352D02*
X364933Y246325D01*
G01X364912Y246378D02*
X364923Y246352D01*
G01X364933Y251325D02*
X364941Y251299D01*
G01X364923Y251352D02*
X364933Y251325D01*
G01X364912Y251378D02*
X364923Y251352D01*
G01X364933Y256325D02*
X364941Y256299D01*
G01X364923Y256352D02*
X364933Y256325D01*
G01X364912Y256378D02*
X364923Y256352D01*
G01X364924Y221176D02*
X364904Y221181D01*
G01X364938Y221162D02*
X364924Y221176D01*
G01X364943Y221142D02*
X364938Y221162D01*
G01X364924Y226176D02*
X364904Y226181D01*
G01X364938Y226162D02*
X364924Y226176D01*
G01X364943Y226142D02*
X364938Y226162D01*
G01X364924Y231176D02*
X364904Y231181D01*
G01X364938Y231162D02*
X364924Y231176D01*
G01X364943Y231142D02*
X364938Y231162D01*
G01X364924Y236176D02*
X364904Y236181D01*
G01X364938Y236162D02*
X364924Y236176D01*
G01X364943Y236142D02*
X364938Y236162D01*
G01X364924Y241176D02*
X364904Y241181D01*
G01X364938Y241162D02*
X364924Y241176D01*
G01X364943Y241142D02*
X364938Y241162D01*
G01X364924Y246176D02*
X364904Y246181D01*
G01X364938Y246162D02*
X364924Y246176D01*
G01X364943Y246142D02*
X364938Y246162D01*
G01X364924Y251176D02*
X364904Y251181D01*
G01X364938Y251162D02*
X364924Y251176D01*
G01X364943Y251142D02*
X364938Y251162D01*
G01X364924Y256176D02*
X364904Y256181D01*
G01X364938Y256162D02*
X364924Y256176D01*
G01X364943Y256142D02*
X364938Y256162D01*
G01X364908Y221279D02*
X364912Y221378D01*
G01X364902Y221207D02*
X364908Y221279D01*
G01X364904Y221181D02*
X364902Y221207D01*
G01X364908Y226279D02*
X364912Y226378D01*
G01X364902Y226207D02*
X364908Y226279D01*
G01X364904Y226181D02*
X364902Y226207D01*
G01X364908Y231279D02*
X364912Y231378D01*
G01X364902Y231207D02*
X364908Y231279D01*
G01X364904Y231181D02*
X364902Y231207D01*
G01X364908Y236279D02*
X364912Y236378D01*
G01X364902Y236207D02*
X364908Y236279D01*
G01X364904Y236181D02*
X364902Y236207D01*
G01X364908Y241279D02*
X364912Y241378D01*
G01X364902Y241207D02*
X364908Y241279D01*
G01X364904Y241181D02*
X364902Y241207D01*
G01X364908Y246279D02*
X364912Y246378D01*
G01X364902Y246207D02*
X364908Y246279D01*
G01X364904Y246181D02*
X364902Y246207D01*
G01X364908Y251279D02*
X364912Y251378D01*
G01X364902Y251207D02*
X364908Y251279D01*
G01X364904Y251181D02*
X364902Y251207D01*
G01X364908Y256279D02*
X364912Y256378D01*
G01X364902Y256207D02*
X364908Y256279D01*
G01X364904Y256181D02*
X364902Y256207D01*
G01X364928Y251173D02*
X364939Y251157D01*
G01X364904Y251181D02*
X364928Y251173D01*
G01Y256173D02*
X364939Y256157D01*
G01X364904Y256181D02*
X364928Y256173D01*
G01X363957Y259802D02*
X363958Y259803D01*
G01X363957Y259796D02*
Y259802D01*
G01Y259787D02*
Y259796D01*
G01Y254802D02*
X363958Y254803D01*
G01X363957Y254796D02*
Y254802D01*
G01Y254787D02*
Y254796D01*
G01Y249802D02*
X363958Y249803D01*
G01X363957Y249796D02*
Y249802D01*
G01Y249787D02*
Y249796D01*
G01Y244802D02*
X363958Y244803D01*
G01X363957Y244796D02*
Y244802D01*
G01Y244787D02*
Y244796D01*
G01Y239802D02*
X363958Y239803D01*
G01X363957Y239796D02*
Y239802D01*
G01Y239787D02*
Y239796D01*
G01Y234802D02*
X363958Y234803D01*
G01X363957Y234796D02*
Y234802D01*
G01Y234787D02*
Y234796D01*
G01Y229802D02*
X363958Y229803D01*
G01X363957Y229796D02*
Y229802D01*
G01Y229787D02*
Y229796D01*
G01Y224802D02*
X363958Y224803D01*
G01X363957Y224796D02*
Y224802D01*
G01Y224787D02*
Y224796D01*
G01Y219802D02*
X363958Y219803D01*
G01X363957Y219796D02*
Y219802D01*
G01Y219787D02*
Y219796D01*
G01X364941Y259796D02*
Y259787D01*
G01X364942Y259802D02*
X364941Y259796D01*
G01X364944Y259803D02*
X364942Y259802D01*
G01X364941Y254796D02*
Y254787D01*
G01X364942Y254802D02*
X364941Y254796D01*
G01X364944Y254803D02*
X364942Y254802D01*
G01X364941Y249796D02*
Y249787D01*
G01X364942Y249802D02*
X364941Y249796D01*
G01X364944Y249803D02*
X364942Y249802D01*
G01X364941Y244796D02*
Y244787D01*
G01X364942Y244802D02*
X364941Y244796D01*
G01X364944Y244803D02*
X364942Y244802D01*
G01X364941Y239796D02*
Y239787D01*
G01X364942Y239802D02*
X364941Y239796D01*
G01X364944Y239803D02*
X364942Y239802D01*
G01X364941Y234796D02*
Y234787D01*
G01X364942Y234802D02*
X364941Y234796D01*
G01X364944Y234803D02*
X364942Y234802D01*
G01X364941Y229796D02*
Y229787D01*
G01X364942Y229802D02*
X364941Y229796D01*
G01X364944Y229803D02*
X364942Y229802D01*
G01X364941Y224796D02*
Y224787D01*
G01X364942Y224802D02*
X364941Y224796D01*
G01X364944Y224803D02*
X364942Y224802D01*
G01X364941Y219796D02*
Y219787D01*
G01X364942Y219802D02*
X364941Y219796D01*
G01X364944Y219803D02*
X364942Y219802D01*
G01X364370Y217854D02*
X365551Y219035D01*
G01X369291Y259803D02*
X363958D01*
G01X363957Y259311D02*
X364941D01*
G01Y256673D02*
X363957D01*
G01X364941Y259607D02*
X363957Y259606D01*
G01Y256377D02*
X364912Y256378D01*
G01X363958Y256181D02*
X369291D01*
G01Y256142D02*
X364943D01*
G01X369291Y254803D02*
X363958D01*
G01X363957Y254311D02*
X364941D01*
G01Y251673D02*
X363957D01*
G01X363958Y251181D02*
X369291D01*
G01Y251142D02*
X364943D01*
G01X369291Y249803D02*
X363958D01*
G01X363957Y249311D02*
X364941D01*
G01Y246673D02*
X363957D01*
G01X363958Y246181D02*
X369291D01*
G01Y246142D02*
X364943D01*
G01X369291Y244803D02*
X363958D01*
G01X363957Y244311D02*
X364941D01*
G01Y241673D02*
X363957D01*
G01X363958Y241181D02*
X369291D01*
G01Y241142D02*
X364943D01*
G01X369291Y239803D02*
X363958D01*
G01X363957Y239311D02*
X364941D01*
G01Y236673D02*
X363957D01*
G01X363958Y236181D02*
X369291D01*
G01Y236142D02*
X364943D01*
G01X369291Y234803D02*
X363958D01*
G01X363957Y234311D02*
X364941D01*
G01Y231673D02*
X363957D01*
G01X363958Y231181D02*
X369291D01*
G01Y231142D02*
X364943D01*
G01X369291Y229803D02*
X363958D01*
G01X363957Y229311D02*
X364941D01*
G01Y226673D02*
X363957D01*
G01X363958Y226181D02*
X369291D01*
G01Y226142D02*
X364943D01*
G01X369291Y224803D02*
X363958D01*
G01X363957Y224311D02*
X364941D01*
G01Y221673D02*
X363957D01*
G01X363958Y221181D02*
X369291D01*
G01Y221142D02*
X364943D01*
G01X369291Y219803D02*
X363958D01*
G01X363957Y219311D02*
X364941D01*
G01Y254607D02*
X363957Y254606D01*
G01Y251377D02*
X364912Y251378D01*
G01X364941Y249607D02*
X363957Y249606D01*
G01Y246377D02*
X364912Y246378D01*
G01X364941Y244607D02*
X363957Y244606D01*
G01Y241377D02*
X364912Y241378D01*
G01X364941Y239607D02*
X363957Y239606D01*
G01Y236377D02*
X364912Y236378D01*
G01X364941Y234607D02*
X363957Y234606D01*
G01Y231377D02*
X364912Y231378D01*
G01X364941Y229607D02*
X363957Y229606D01*
G01Y226377D02*
X364912Y226378D01*
G01X364941Y224607D02*
X363957Y224606D01*
G01Y221377D02*
X364912Y221378D01*
G01X364941Y219607D02*
X363957Y219606D01*
G01X364941Y221155D02*
Y221164D01*
G01Y226155D02*
Y226164D01*
G01Y231155D02*
Y231164D01*
G01Y236155D02*
Y236164D01*
G01Y241155D02*
Y241164D01*
G01Y246155D02*
Y246164D01*
G01Y251155D02*
Y251164D01*
G01Y256155D02*
Y256164D01*
G01X369291Y259803D02*
Y261181D01*
G01Y254803D02*
Y256181D01*
G01Y249803D02*
Y251181D01*
G01Y244803D02*
Y246181D01*
G01Y239803D02*
Y241181D01*
G01Y234803D02*
Y236181D01*
G01Y229803D02*
Y231181D01*
G01Y224803D02*
Y226181D01*
G01Y219803D02*
Y221181D01*
G01X366122D02*
Y219803D01*
G01Y226181D02*
Y224803D01*
G01Y231181D02*
Y229803D01*
G01Y236181D02*
Y234803D01*
G01Y241181D02*
Y239803D01*
G01Y246181D02*
Y244803D01*
G01Y251181D02*
Y249803D01*
G01Y256181D02*
Y254803D01*
G01Y261181D02*
Y259803D01*
G01X364941Y226156D02*
Y226299D01*
G01Y221156D02*
Y221299D01*
G01Y231156D02*
Y231299D01*
G01Y241156D02*
Y241299D01*
G01Y236156D02*
Y236299D01*
G01Y251156D02*
Y251299D01*
G01Y246156D02*
Y246299D01*
G01Y256156D02*
Y256299D01*
G01Y259311D02*
Y261673D01*
G01Y254311D02*
Y256673D01*
G01Y249311D02*
Y251673D01*
G01Y244311D02*
Y246673D01*
G01Y239311D02*
Y241673D01*
G01Y234311D02*
Y236673D01*
G01Y229311D02*
Y231673D01*
G01Y224311D02*
Y226673D01*
G01Y219311D02*
Y221673D01*
G01X363957D02*
Y219311D01*
G01Y226673D02*
Y224311D01*
G01Y231673D02*
Y229311D01*
G01Y236673D02*
Y234311D01*
G01Y241673D02*
Y239311D01*
G01Y246673D02*
Y244311D01*
G01Y251673D02*
Y249311D01*
G01Y256673D02*
Y254311D01*
G01Y261673D02*
Y259311D01*
G01X364941Y261148D02*
Y261156D01*
G01X364942Y261144D02*
X364941Y261148D01*
G01X364943Y261142D02*
X364942Y261144D01*
G01X364941Y266148D02*
Y266156D01*
G01X364942Y266144D02*
X364941Y266148D01*
G01X364943Y266142D02*
X364942Y266144D01*
G01X364941Y271148D02*
Y271156D01*
G01X364942Y271144D02*
X364941Y271148D01*
G01X364943Y271142D02*
X364942Y271144D01*
G01X364941Y276148D02*
Y276156D01*
G01X364942Y276144D02*
X364941Y276148D01*
G01X364943Y276142D02*
X364942Y276144D01*
G01X364941Y281148D02*
Y281156D01*
G01X364942Y281144D02*
X364941Y281148D01*
G01X364943Y281142D02*
X364942Y281144D01*
G01X364941Y286148D02*
Y286156D01*
G01X364942Y286144D02*
X364941Y286148D01*
G01X364943Y286142D02*
X364942Y286144D01*
G01X364941Y291148D02*
Y291156D01*
G01X364942Y291144D02*
X364941Y291148D01*
G01X364943Y291142D02*
X364942Y291144D01*
G01X363957Y261189D02*
Y261198D01*
G01Y261183D02*
Y261189D01*
G01X363958Y261181D02*
X363957Y261183D01*
G01Y266189D02*
Y266198D01*
G01Y266183D02*
Y266189D01*
G01X363958Y266181D02*
X363957Y266183D01*
G01Y271189D02*
Y271198D01*
G01Y271183D02*
Y271189D01*
G01X363958Y271181D02*
X363957Y271183D01*
G01Y276189D02*
Y276198D01*
G01Y276183D02*
Y276189D01*
G01X363958Y276181D02*
X363957Y276183D01*
G01Y281189D02*
Y281198D01*
G01Y281183D02*
Y281189D01*
G01X363958Y281181D02*
X363957Y281183D01*
G01Y286189D02*
Y286198D01*
G01Y286183D02*
Y286189D01*
G01X363958Y286181D02*
X363957Y286183D01*
G01Y291189D02*
Y291198D01*
G01Y291183D02*
Y291189D01*
G01X363958Y291181D02*
X363957Y291183D01*
G01X364933Y261325D02*
X364941Y261299D01*
G01X364923Y261352D02*
X364933Y261325D01*
G01X364912Y261378D02*
X364923Y261352D01*
G01X364933Y266325D02*
X364941Y266299D01*
G01X364923Y266352D02*
X364933Y266325D01*
G01X364912Y266378D02*
X364923Y266352D01*
G01X364933Y271325D02*
X364941Y271299D01*
G01X364923Y271352D02*
X364933Y271325D01*
G01X364912Y271378D02*
X364923Y271352D01*
G01X364933Y276325D02*
X364941Y276299D01*
G01X364923Y276352D02*
X364933Y276325D01*
G01X364912Y276378D02*
X364923Y276352D01*
G01X364933Y281325D02*
X364941Y281299D01*
G01X364923Y281352D02*
X364933Y281325D01*
G01X364912Y281378D02*
X364923Y281352D01*
G01X364933Y286325D02*
X364941Y286299D01*
G01X364923Y286352D02*
X364933Y286325D01*
G01X364912Y286378D02*
X364923Y286352D01*
G01X364933Y291325D02*
X364941Y291299D01*
G01X364923Y291352D02*
X364933Y291325D01*
G01X364912Y291378D02*
X364923Y291352D01*
G01X364924Y261176D02*
X364904Y261181D01*
G01X364938Y261162D02*
X364924Y261176D01*
G01X364943Y261142D02*
X364938Y261162D01*
G01X364924Y266176D02*
X364904Y266181D01*
G01X364938Y266162D02*
X364924Y266176D01*
G01X364943Y266142D02*
X364938Y266162D01*
G01X364924Y271176D02*
X364904Y271181D01*
G01X364938Y271162D02*
X364924Y271176D01*
G01X364943Y271142D02*
X364938Y271162D01*
G01X364924Y276176D02*
X364904Y276181D01*
G01X364938Y276162D02*
X364924Y276176D01*
G01X364943Y276142D02*
X364938Y276162D01*
G01X364924Y281176D02*
X364904Y281181D01*
G01X364938Y281162D02*
X364924Y281176D01*
G01X364943Y281142D02*
X364938Y281162D01*
G01X364924Y286176D02*
X364904Y286181D01*
G01X364938Y286162D02*
X364924Y286176D01*
G01X364943Y286142D02*
X364938Y286162D01*
G01X364924Y291176D02*
X364904Y291181D01*
G01X364938Y291162D02*
X364924Y291176D01*
G01X364943Y291142D02*
X364938Y291162D01*
G01X364908Y261279D02*
X364912Y261378D01*
G01X364902Y261207D02*
X364908Y261279D01*
G01X364904Y261181D02*
X364902Y261207D01*
G01X364908Y266279D02*
X364912Y266378D01*
G01X364902Y266207D02*
X364908Y266279D01*
G01X364904Y266181D02*
X364902Y266207D01*
G01X364908Y271279D02*
X364912Y271378D01*
G01X364902Y271207D02*
X364908Y271279D01*
G01X364904Y271181D02*
X364902Y271207D01*
G01X364908Y276279D02*
X364912Y276378D01*
G01X364902Y276207D02*
X364908Y276279D01*
G01X364904Y276181D02*
X364902Y276207D01*
G01X364908Y281279D02*
X364912Y281378D01*
G01X364902Y281207D02*
X364908Y281279D01*
G01X364904Y281181D02*
X364902Y281207D01*
G01X364908Y286279D02*
X364912Y286378D01*
G01X364902Y286207D02*
X364908Y286279D01*
G01X364904Y286181D02*
X364902Y286207D01*
G01X364908Y291279D02*
X364912Y291378D01*
G01X364902Y291207D02*
X364908Y291279D01*
G01X364904Y291181D02*
X364902Y291207D01*
G01X364928Y261173D02*
X364939Y261157D01*
G01X364904Y261181D02*
X364928Y261173D01*
G01Y266173D02*
X364939Y266157D01*
G01X364904Y266181D02*
X364928Y266173D01*
G01Y271173D02*
X364939Y271157D01*
G01X364904Y271181D02*
X364928Y271173D01*
G01Y276173D02*
X364939Y276157D01*
G01X364904Y276181D02*
X364928Y276173D01*
G01Y281173D02*
X364939Y281157D01*
G01X364904Y281181D02*
X364928Y281173D01*
G01Y286173D02*
X364939Y286157D01*
G01X364904Y286181D02*
X364928Y286173D01*
G01Y291173D02*
X364939Y291157D01*
G01X364904Y291181D02*
X364928Y291173D01*
G01X363957Y289802D02*
X363958Y289803D01*
G01X363957Y289796D02*
Y289802D01*
G01Y289787D02*
Y289796D01*
G01Y284802D02*
X363958Y284803D01*
G01X363957Y284796D02*
Y284802D01*
G01Y284787D02*
Y284796D01*
G01Y279802D02*
X363958Y279803D01*
G01X363957Y279796D02*
Y279802D01*
G01Y279787D02*
Y279796D01*
G01Y274802D02*
X363958Y274803D01*
G01X363957Y274796D02*
Y274802D01*
G01Y274787D02*
Y274796D01*
G01Y269802D02*
X363958Y269803D01*
G01X363957Y269796D02*
Y269802D01*
G01Y269787D02*
Y269796D01*
G01Y264802D02*
X363958Y264803D01*
G01X363957Y264796D02*
Y264802D01*
G01Y264787D02*
Y264796D01*
G01X364941Y289796D02*
Y289787D01*
G01X364942Y289802D02*
X364941Y289796D01*
G01X364944Y289803D02*
X364942Y289802D01*
G01X364941Y284796D02*
Y284787D01*
G01X364942Y284802D02*
X364941Y284796D01*
G01X364944Y284803D02*
X364942Y284802D01*
G01X364941Y279796D02*
Y279787D01*
G01X364942Y279802D02*
X364941Y279796D01*
G01X364944Y279803D02*
X364942Y279802D01*
G01X364941Y274796D02*
Y274787D01*
G01X364942Y274802D02*
X364941Y274796D01*
G01X364944Y274803D02*
X364942Y274802D01*
G01X364941Y269796D02*
Y269787D01*
G01X364942Y269802D02*
X364941Y269796D01*
G01X364944Y269803D02*
X364942Y269802D01*
G01X364941Y264796D02*
Y264787D01*
G01X364942Y264802D02*
X364941Y264796D01*
G01X364944Y264803D02*
X364942Y264802D01*
G01X370276Y300335D02*
X366929Y296988D01*
G01X366339Y297854D02*
X363189D01*
G01X364941Y291673D02*
X363957D01*
G01X363958Y291181D02*
X369291D01*
G01Y291142D02*
X364943D01*
G01X369291Y289803D02*
X363958D01*
G01X363957Y289311D02*
X364941D01*
G01Y286673D02*
X363957D01*
G01X363958Y286181D02*
X369291D01*
G01Y286142D02*
X364943D01*
G01X369291Y284803D02*
X363958D01*
G01X363957Y284311D02*
X364941D01*
G01Y281673D02*
X363957D01*
G01X363958Y281181D02*
X369291D01*
G01Y281142D02*
X364943D01*
G01X369291Y279803D02*
X363958D01*
G01X363957Y279311D02*
X364941D01*
G01Y276673D02*
X363957D01*
G01X363958Y276181D02*
X369291D01*
G01Y276142D02*
X364943D01*
G01X369291Y274803D02*
X363958D01*
G01X363957Y274311D02*
X364941D01*
G01Y271673D02*
X363957D01*
G01X363958Y271181D02*
X369291D01*
G01Y271142D02*
X364943D01*
G01X369291Y269803D02*
X363958D01*
G01X363957Y269311D02*
X364941D01*
G01Y266673D02*
X363957D01*
G01X363958Y266181D02*
X369291D01*
G01Y266142D02*
X364943D01*
G01X369291Y264803D02*
X363958D01*
G01X363957Y264311D02*
X364941D01*
G01Y261673D02*
X363957D01*
G01X363958Y261181D02*
X369291D01*
G01Y261142D02*
X364943D01*
G01X363957Y291377D02*
X364912Y291378D01*
G01X364941Y289607D02*
X363957Y289606D01*
G01Y286377D02*
X364912Y286378D01*
G01X364941Y284607D02*
X363957Y284606D01*
G01Y281377D02*
X364912Y281378D01*
G01X364941Y279607D02*
X363957Y279606D01*
G01Y276377D02*
X364912Y276378D01*
G01X364941Y274607D02*
X363957Y274606D01*
G01Y271377D02*
X364912Y271378D01*
G01X364941Y269607D02*
X363957Y269606D01*
G01Y266377D02*
X364912Y266378D01*
G01X364941Y264607D02*
X363957Y264606D01*
G01Y261377D02*
X364912Y261378D01*
G01X364941Y261155D02*
Y261164D01*
G01Y266155D02*
Y266164D01*
G01Y271155D02*
Y271164D01*
G01Y276155D02*
Y276164D01*
G01Y281155D02*
Y281164D01*
G01Y286155D02*
Y286164D01*
G01Y291155D02*
Y291164D01*
G01X370276Y300335D02*
Y316083D01*
G01X369291Y289803D02*
Y291181D01*
G01Y284803D02*
Y286181D01*
G01Y279803D02*
Y281181D01*
G01Y274803D02*
Y276181D01*
G01Y269803D02*
Y271181D01*
G01Y264803D02*
Y266181D01*
G01X366122D02*
Y264803D01*
G01Y271181D02*
Y269803D01*
G01Y276181D02*
Y274803D01*
G01Y281181D02*
Y279803D01*
G01Y286181D02*
Y284803D01*
G01Y291181D02*
Y289803D01*
G01X364941Y261156D02*
Y261299D01*
G01Y271156D02*
Y271299D01*
G01Y266156D02*
Y266299D01*
G01Y281156D02*
Y281299D01*
G01Y276156D02*
Y276299D01*
G01Y291156D02*
Y291299D01*
G01Y286156D02*
Y286299D01*
G01Y289311D02*
Y291673D01*
G01Y284311D02*
Y286673D01*
G01Y279311D02*
Y281673D01*
G01Y274311D02*
Y276673D01*
G01Y269311D02*
Y271673D01*
G01Y264311D02*
Y266673D01*
G01X363957D02*
Y264311D01*
G01Y271673D02*
Y269311D01*
G01Y276673D02*
Y274311D01*
G01Y281673D02*
Y279311D01*
G01Y286673D02*
Y284311D01*
G01Y291673D02*
Y289311D01*
G01X363189Y306398D02*
Y297854D01*
G01X363386Y316673D02*
G03X362795Y317264I-591J0D01*
G01X370276Y316083D02*
G03X368307Y318051I-1969J-1D01*
G01X363386Y310571D02*
Y316673D01*
G01X389213Y392016D02*
G03X396138Y378885I37662J11471D01*
G01X389213Y392016D02*
G03X369252I-9981J-3039D01*
G01X389213D02*
G03X396138Y378885I37662J11471D01*
G01X389213Y392016D02*
G03X369252I-9981J-3039D01*
G01X362795Y591476D02*
G03X363386Y592067I0J591D01*
G01X368307Y590689D02*
G03X370276Y592657I0J1969D01*
G01D02*
Y608406D01*
G01X363386Y598169D02*
Y592067D01*
G01X363957Y618944D02*
Y618954D01*
G01Y618939D02*
Y618944D01*
G01X363958Y618937D02*
X363957Y618939D01*
G01Y623944D02*
Y623954D01*
G01Y623939D02*
Y623944D01*
G01X363958Y623937D02*
X363957Y623939D01*
G01X364933Y619081D02*
X364941Y619055D01*
G01X364923Y619107D02*
X364933Y619081D01*
G01X364912Y619134D02*
X364923Y619107D01*
G01X364933Y624081D02*
X364941Y624055D01*
G01X364923Y624107D02*
X364933Y624081D01*
G01X364912Y624134D02*
X364923Y624107D01*
G01X364924Y618932D02*
X364904Y618937D01*
G01X364938Y618918D02*
X364924Y618932D01*
G01X364943Y618898D02*
X364938Y618918D01*
G01X364924Y623932D02*
X364904Y623937D01*
G01X364938Y623918D02*
X364924Y623932D01*
G01X364943Y623898D02*
X364938Y623918D01*
G01X364924Y628932D02*
X364904Y628937D01*
G01X364938Y628918D02*
X364924Y628932D01*
G01X364943Y628898D02*
X364938Y628918D01*
G01X364924Y633932D02*
X364904Y633937D01*
G01X364938Y633918D02*
X364924Y633932D01*
G01X364943Y633898D02*
X364938Y633918D01*
G01X364924Y638932D02*
X364904Y638937D01*
G01X364938Y638918D02*
X364924Y638932D01*
G01X364943Y638898D02*
X364938Y638918D01*
G01X364924Y643932D02*
X364904Y643937D01*
G01X364938Y643918D02*
X364924Y643932D01*
G01X364943Y643898D02*
X364938Y643918D01*
G01X364908Y619035D02*
X364912Y619134D01*
G01X364902Y618963D02*
X364908Y619035D01*
G01X364904Y618937D02*
X364902Y618963D01*
G01X364908Y624035D02*
X364912Y624134D01*
G01X364902Y623963D02*
X364908Y624035D01*
G01X364904Y623937D02*
X364902Y623963D01*
G01X364908Y629035D02*
X364912Y629134D01*
G01X364902Y628963D02*
X364908Y629035D01*
G01X364904Y628937D02*
X364902Y628963D01*
G01X364908Y634035D02*
X364912Y634134D01*
G01X364902Y633963D02*
X364908Y634035D01*
G01X364904Y633937D02*
X364902Y633963D01*
G01X364908Y639035D02*
X364912Y639134D01*
G01X364902Y638963D02*
X364908Y639035D01*
G01X364904Y638937D02*
X364902Y638963D01*
G01X364908Y644035D02*
X364912Y644134D01*
G01X364902Y643963D02*
X364908Y644035D01*
G01X364904Y643937D02*
X364902Y643963D01*
G01X363957Y647557D02*
X363958Y647559D01*
G01X363957Y647552D02*
Y647557D01*
G01Y647543D02*
Y647552D01*
G01Y642557D02*
X363958Y642559D01*
G01X363957Y642552D02*
Y642557D01*
G01Y642543D02*
Y642552D01*
G01Y637557D02*
X363958Y637559D01*
G01X363957Y637552D02*
Y637557D01*
G01Y637543D02*
Y637552D01*
G01Y632557D02*
X363958Y632559D01*
G01X363957Y632552D02*
Y632557D01*
G01Y632543D02*
Y632552D01*
G01Y627557D02*
X363958Y627559D01*
G01X363957Y627552D02*
Y627557D01*
G01Y627543D02*
Y627552D01*
G01Y622557D02*
X363958Y622559D01*
G01X363957Y622552D02*
Y622557D01*
G01Y622543D02*
Y622552D01*
G01Y617557D02*
X363958Y617559D01*
G01X363957Y617552D02*
Y617557D01*
G01Y617543D02*
Y617552D01*
G01X364941Y618904D02*
Y618911D01*
G01X364942Y618900D02*
X364941Y618904D01*
G01X364943Y618898D02*
X364942Y618900D01*
G01X364941Y623904D02*
Y623911D01*
G01X364942Y623900D02*
X364941Y623904D01*
G01X364943Y623898D02*
X364942Y623900D01*
G01X364941Y628904D02*
Y628911D01*
G01X364942Y628900D02*
X364941Y628904D01*
G01X364943Y628898D02*
X364942Y628900D01*
G01X364941Y633904D02*
Y633911D01*
G01X364942Y633900D02*
X364941Y633904D01*
G01X364943Y633898D02*
X364942Y633900D01*
G01X364941Y638904D02*
Y638911D01*
G01X364942Y638900D02*
X364941Y638904D01*
G01X364943Y638898D02*
X364942Y638900D01*
G01X364941Y643904D02*
Y643911D01*
G01X364942Y643900D02*
X364941Y643904D01*
G01X364943Y643898D02*
X364942Y643900D01*
G01X363957Y628944D02*
Y628954D01*
G01Y628939D02*
Y628944D01*
G01X363958Y628937D02*
X363957Y628939D01*
G01Y633944D02*
Y633954D01*
G01Y633939D02*
Y633944D01*
G01X363958Y633937D02*
X363957Y633939D01*
G01Y638944D02*
Y638954D01*
G01Y638939D02*
Y638944D01*
G01X363958Y638937D02*
X363957Y638939D01*
G01Y643944D02*
Y643954D01*
G01Y643939D02*
Y643944D01*
G01X363958Y643937D02*
X363957Y643939D01*
G01X364933Y629081D02*
X364941Y629055D01*
G01X364923Y629107D02*
X364933Y629081D01*
G01X364912Y629134D02*
X364923Y629107D01*
G01X364933Y634081D02*
X364941Y634055D01*
G01X364923Y634107D02*
X364933Y634081D01*
G01X364912Y634134D02*
X364923Y634107D01*
G01X364933Y639081D02*
X364941Y639055D01*
G01X364923Y639107D02*
X364933Y639081D01*
G01X364912Y639134D02*
X364923Y639107D01*
G01X364933Y644081D02*
X364941Y644055D01*
G01X364923Y644107D02*
X364933Y644081D01*
G01X364912Y644134D02*
X364923Y644107D01*
G01X364941Y647552D02*
Y647543D01*
G01X364942Y647557D02*
X364941Y647552D01*
G01X364944Y647559D02*
X364942Y647557D01*
G01X364941Y642552D02*
Y642543D01*
G01X364942Y642557D02*
X364941Y642552D01*
G01X364944Y642559D02*
X364942Y642557D01*
G01X364941Y637552D02*
Y637543D01*
G01X364942Y637557D02*
X364941Y637552D01*
G01X364944Y637559D02*
X364942Y637557D01*
G01X364941Y632552D02*
Y632543D01*
G01X364942Y632557D02*
X364941Y632552D01*
G01X364944Y632559D02*
X364942Y632557D01*
G01X364941Y627552D02*
Y627543D01*
G01X364942Y627557D02*
X364941Y627552D01*
G01X364944Y627559D02*
X364942Y627557D01*
G01X364941Y622552D02*
Y622543D01*
G01X364942Y622557D02*
X364941Y622552D01*
G01X364944Y622559D02*
X364942Y622557D01*
G01X364941Y617552D02*
Y617543D01*
G01X364942Y617557D02*
X364941Y617552D01*
G01X364944Y617559D02*
X364942Y617557D01*
G01X364928Y618929D02*
X364939Y618913D01*
G01X364904Y618937D02*
X364928Y618929D01*
G01Y623929D02*
X364939Y623913D01*
G01X364904Y623937D02*
X364928Y623929D01*
G01Y628929D02*
X364939Y628913D01*
G01X364904Y628937D02*
X364928Y628929D01*
G01Y633929D02*
X364939Y633913D01*
G01X364904Y633937D02*
X364928Y633929D01*
G01Y638929D02*
X364939Y638913D01*
G01X364904Y638937D02*
X364928Y638929D01*
G01Y643929D02*
X364939Y643913D01*
G01X364904Y643937D02*
X364928Y643929D01*
G01X369291Y647559D02*
X363958D01*
G01X363957Y647067D02*
X364941D01*
G01Y644429D02*
X363957D01*
G01X363958Y643937D02*
X369291D01*
G01Y643898D02*
X364943D01*
G01X369291Y642559D02*
X363958D01*
G01X363957Y642067D02*
X364941D01*
G01Y639429D02*
X363957D01*
G01X363958Y638937D02*
X369291D01*
G01Y638898D02*
X364943D01*
G01X369291Y637559D02*
X363958D01*
G01X363957Y637067D02*
X364941D01*
G01Y634429D02*
X363957D01*
G01X363958Y633937D02*
X369291D01*
G01Y633898D02*
X364943D01*
G01X369291Y632559D02*
X363958D01*
G01X363957Y632067D02*
X364941D01*
G01Y629429D02*
X363957D01*
G01X363958Y628937D02*
X369291D01*
G01Y628898D02*
X364943D01*
G01X369291Y627559D02*
X363958D01*
G01X363957Y627067D02*
X364941D01*
G01Y624429D02*
X363957D01*
G01X363958Y623937D02*
X369291D01*
G01Y623898D02*
X364943D01*
G01X369291Y622559D02*
X363958D01*
G01X363957Y622067D02*
X364941D01*
G01Y619429D02*
X363957D01*
G01X363958Y618937D02*
X369291D01*
G01Y618898D02*
X364943D01*
G01X369291Y617559D02*
X363958D01*
G01X363957Y617067D02*
X364941D01*
G01Y647363D02*
X363957Y647362D01*
G01Y644133D02*
X364912Y644134D01*
G01X364941Y642363D02*
X363957Y642362D01*
G01Y639133D02*
X364912Y639134D01*
G01X364941Y637363D02*
X363957Y637362D01*
G01Y634133D02*
X364912Y634134D01*
G01X364941Y632363D02*
X363957Y632362D01*
G01Y629133D02*
X364912Y629134D01*
G01X364941Y627363D02*
X363957Y627362D01*
G01Y624133D02*
X364912Y624134D01*
G01X364941Y622363D02*
X363957Y622362D01*
G01Y619133D02*
X364912Y619134D01*
G01X364941Y617363D02*
X363957Y617362D01*
G01X363189Y610886D02*
X366339D01*
G01X366929Y611752D02*
X370276Y608406D01*
G01X364941Y618911D02*
Y618920D01*
G01Y623911D02*
Y623920D01*
G01Y628911D02*
Y628920D01*
G01Y633911D02*
Y633920D01*
G01Y638911D02*
Y638920D01*
G01Y643911D02*
Y643920D01*
G01X369291Y647559D02*
Y648937D01*
G01Y642559D02*
Y643937D01*
G01Y637559D02*
Y638937D01*
G01Y632559D02*
Y633937D01*
G01Y627559D02*
Y628937D01*
G01Y622559D02*
Y623937D01*
G01Y617559D02*
Y618937D01*
G01X366929Y749744D02*
Y611752D01*
G01X366339Y751988D02*
Y609508D01*
G01X366122Y618937D02*
Y617559D01*
G01Y623937D02*
Y622559D01*
G01Y628937D02*
Y627559D01*
G01Y633937D02*
Y632559D01*
G01Y638937D02*
Y637559D01*
G01Y643937D02*
Y642559D01*
G01Y648937D02*
Y647559D01*
G01X364941Y647067D02*
Y649429D01*
G01Y642067D02*
Y644429D01*
G01Y637067D02*
Y639429D01*
G01Y632067D02*
Y634429D01*
G01Y627067D02*
Y629429D01*
G01Y622067D02*
Y624429D01*
G01Y617067D02*
Y619429D01*
G01X363957D02*
Y617067D01*
G01Y624429D02*
Y622067D01*
G01Y629429D02*
Y627067D01*
G01Y634429D02*
Y632067D01*
G01Y639429D02*
Y637067D01*
G01Y644429D02*
Y642067D01*
G01Y649429D02*
Y647067D01*
G01X363189Y610886D02*
Y602343D01*
G01X364924Y648932D02*
X364904Y648937D01*
G01X364938Y648918D02*
X364924Y648932D01*
G01X364943Y648898D02*
X364938Y648918D01*
G01X364908Y649035D02*
X364912Y649134D01*
G01X364902Y648963D02*
X364908Y649035D01*
G01X364904Y648937D02*
X364902Y648963D01*
G01X364908Y674035D02*
X364912Y674134D01*
G01X364902Y673963D02*
X364908Y674035D01*
G01X364904Y673937D02*
X364902Y673963D01*
G01X364908Y679035D02*
X364912Y679134D01*
G01X364902Y678963D02*
X364908Y679035D01*
G01X364904Y678937D02*
X364902Y678963D01*
G01X364908Y684035D02*
X364912Y684134D01*
G01X364902Y683963D02*
X364908Y684035D01*
G01X364904Y683937D02*
X364902Y683963D01*
G01X364908Y689035D02*
X364912Y689134D01*
G01X364902Y688963D02*
X364908Y689035D01*
G01X364904Y688937D02*
X364902Y688963D01*
G01X364908Y694035D02*
X364912Y694134D01*
G01X364902Y693963D02*
X364908Y694035D01*
G01X364904Y693937D02*
X364902Y693963D01*
G01X363957Y692557D02*
X363958Y692559D01*
G01X363957Y692552D02*
Y692557D01*
G01Y692543D02*
Y692552D01*
G01Y687557D02*
X363958Y687559D01*
G01X363957Y687552D02*
Y687557D01*
G01Y687543D02*
Y687552D01*
G01Y682557D02*
X363958Y682559D01*
G01X363957Y682552D02*
Y682557D01*
G01Y682543D02*
Y682552D01*
G01Y677557D02*
X363958Y677559D01*
G01X363957Y677552D02*
Y677557D01*
G01Y677543D02*
Y677552D01*
G01Y672557D02*
X363958Y672559D01*
G01X363957Y672552D02*
Y672557D01*
G01Y672543D02*
Y672552D01*
G01X364941Y648904D02*
Y648911D01*
G01X364942Y648900D02*
X364941Y648904D01*
G01X364943Y648898D02*
X364942Y648900D01*
G01X364941Y673904D02*
Y673911D01*
G01X364942Y673900D02*
X364941Y673904D01*
G01X364943Y673898D02*
X364942Y673900D01*
G01X364941Y678904D02*
Y678911D01*
G01X364942Y678900D02*
X364941Y678904D01*
G01X364943Y678898D02*
X364942Y678900D01*
G01X364941Y683904D02*
Y683911D01*
G01X364942Y683900D02*
X364941Y683904D01*
G01X364943Y683898D02*
X364942Y683900D01*
G01X364941Y688904D02*
Y688911D01*
G01X364942Y688900D02*
X364941Y688904D01*
G01X364943Y688898D02*
X364942Y688900D01*
G01X364941Y693904D02*
Y693911D01*
G01X364942Y693900D02*
X364941Y693904D01*
G01X364943Y693898D02*
X364942Y693900D01*
G01X363957Y648944D02*
Y648954D01*
G01Y648939D02*
Y648944D01*
G01X363958Y648937D02*
X363957Y648939D01*
G01Y673944D02*
Y673954D01*
G01Y673939D02*
Y673944D01*
G01X363958Y673937D02*
X363957Y673939D01*
G01Y678944D02*
Y678954D01*
G01Y678939D02*
Y678944D01*
G01X363958Y678937D02*
X363957Y678939D01*
G01Y683944D02*
Y683954D01*
G01Y683939D02*
Y683944D01*
G01X363958Y683937D02*
X363957Y683939D01*
G01Y688944D02*
Y688954D01*
G01Y688939D02*
Y688944D01*
G01X363958Y688937D02*
X363957Y688939D01*
G01Y693944D02*
Y693954D01*
G01Y693939D02*
Y693944D01*
G01X363958Y693937D02*
X363957Y693939D01*
G01X364933Y649081D02*
X364941Y649055D01*
G01X364923Y649107D02*
X364933Y649081D01*
G01X364912Y649134D02*
X364923Y649107D01*
G01X364933Y674081D02*
X364941Y674055D01*
G01X364923Y674107D02*
X364933Y674081D01*
G01X364912Y674134D02*
X364923Y674107D01*
G01X364933Y679081D02*
X364941Y679055D01*
G01X364923Y679107D02*
X364933Y679081D01*
G01X364912Y679134D02*
X364923Y679107D01*
G01X364933Y684081D02*
X364941Y684055D01*
G01X364923Y684107D02*
X364933Y684081D01*
G01X364912Y684134D02*
X364923Y684107D01*
G01X364933Y689081D02*
X364941Y689055D01*
G01X364923Y689107D02*
X364933Y689081D01*
G01X364912Y689134D02*
X364923Y689107D01*
G01X364933Y694081D02*
X364941Y694055D01*
G01X364923Y694107D02*
X364933Y694081D01*
G01X364912Y694134D02*
X364923Y694107D01*
G01X364924Y673932D02*
X364904Y673937D01*
G01X364938Y673918D02*
X364924Y673932D01*
G01X364943Y673898D02*
X364938Y673918D01*
G01X364924Y678932D02*
X364904Y678937D01*
G01X364938Y678918D02*
X364924Y678932D01*
G01X364943Y678898D02*
X364938Y678918D01*
G01X364924Y683932D02*
X364904Y683937D01*
G01X364938Y683918D02*
X364924Y683932D01*
G01X364943Y683898D02*
X364938Y683918D01*
G01X364924Y688932D02*
X364904Y688937D01*
G01X364938Y688918D02*
X364924Y688932D01*
G01X364943Y688898D02*
X364938Y688918D01*
G01X364924Y693932D02*
X364904Y693937D01*
G01X364938Y693918D02*
X364924Y693932D01*
G01X364943Y693898D02*
X364938Y693918D01*
G01X364941Y692552D02*
Y692543D01*
G01X364942Y692557D02*
X364941Y692552D01*
G01X364944Y692559D02*
X364942Y692557D01*
G01X364941Y687552D02*
Y687543D01*
G01X364942Y687557D02*
X364941Y687552D01*
G01X364944Y687559D02*
X364942Y687557D01*
G01X364941Y682552D02*
Y682543D01*
G01X364942Y682557D02*
X364941Y682552D01*
G01X364944Y682559D02*
X364942Y682557D01*
G01X364941Y677552D02*
Y677543D01*
G01X364942Y677557D02*
X364941Y677552D01*
G01X364944Y677559D02*
X364942Y677557D01*
G01X364941Y672552D02*
Y672543D01*
G01X364942Y672557D02*
X364941Y672552D01*
G01X364944Y672559D02*
X364942Y672557D01*
G01X364928Y648929D02*
X364939Y648913D01*
G01X364904Y648937D02*
X364928Y648929D01*
G01Y673929D02*
X364939Y673913D01*
G01X364904Y673937D02*
X364928Y673929D01*
G01Y678929D02*
X364939Y678913D01*
G01X364904Y678937D02*
X364928Y678929D01*
G01Y683929D02*
X364939Y683913D01*
G01X364904Y683937D02*
X364928Y683929D01*
G01Y688929D02*
X364939Y688913D01*
G01X364904Y688937D02*
X364928Y688929D01*
G01Y693929D02*
X364939Y693913D01*
G01X364904Y693937D02*
X364928Y693929D01*
G01X364941Y694429D02*
X363957D01*
G01X363958Y693937D02*
X369291D01*
G01Y693898D02*
X364943D01*
G01X369291Y692559D02*
X363958D01*
G01X363957Y692067D02*
X364941D01*
G01Y689429D02*
X363957D01*
G01X363958Y688937D02*
X369291D01*
G01Y688898D02*
X364943D01*
G01X369291Y687559D02*
X363958D01*
G01X363957Y687067D02*
X364941D01*
G01Y684429D02*
X363957D01*
G01X363958Y683937D02*
X369291D01*
G01Y683898D02*
X364943D01*
G01X369291Y682559D02*
X363958D01*
G01X363957Y682067D02*
X364941D01*
G01Y679429D02*
X363957D01*
G01X363958Y678937D02*
X369291D01*
G01Y678898D02*
X364943D01*
G01X369291Y677559D02*
X363958D01*
G01X363957Y677067D02*
X364941D01*
G01Y674429D02*
X363957D01*
G01X363958Y673937D02*
X369291D01*
G01Y673898D02*
X364943D01*
G01X369291Y672559D02*
X363958D01*
G01X363957Y672067D02*
X364941D01*
G01Y649429D02*
X363957D01*
G01X363958Y648937D02*
X369291D01*
G01Y648898D02*
X364943D01*
G01X363957Y694133D02*
X364912Y694134D01*
G01X364941Y692363D02*
X363957Y692362D01*
G01Y689133D02*
X364912Y689134D01*
G01X364941Y687363D02*
X363957Y687362D01*
G01Y684133D02*
X364912Y684134D01*
G01X364941Y682363D02*
X363957Y682362D01*
G01Y679133D02*
X364912Y679134D01*
G01X364941Y677363D02*
X363957Y677362D01*
G01Y674133D02*
X364912Y674134D01*
G01X364941Y672363D02*
X363957Y672362D01*
G01Y649133D02*
X364912Y649134D01*
G01X364370Y670610D02*
X365551Y671791D01*
G01X364370Y650886D02*
X365551Y649705D01*
G01X364941Y648911D02*
Y648920D01*
G01Y673911D02*
Y673920D01*
G01Y678911D02*
Y678920D01*
G01Y683911D02*
Y683920D01*
G01Y688911D02*
Y688920D01*
G01Y693911D02*
Y693920D01*
G01X369291Y692559D02*
Y693937D01*
G01Y687559D02*
Y688937D01*
G01Y682559D02*
Y683937D01*
G01Y677559D02*
Y678937D01*
G01Y672559D02*
Y673937D01*
G01X366122D02*
Y672559D01*
G01Y678937D02*
Y677559D01*
G01Y683937D02*
Y682559D01*
G01Y688937D02*
Y687559D01*
G01Y693937D02*
Y692559D01*
G01X365551Y671791D02*
Y649705D01*
G01X364941Y692067D02*
Y694429D01*
G01Y687067D02*
Y689429D01*
G01Y682067D02*
Y684429D01*
G01Y677067D02*
Y679429D01*
G01Y672067D02*
Y674429D01*
G01X364370Y670610D02*
Y650886D01*
G01X363957Y674429D02*
Y672067D01*
G01Y679429D02*
Y677067D01*
G01Y684429D02*
Y682067D01*
G01Y689429D02*
Y687067D01*
G01Y694429D02*
Y692067D01*
G01X364908Y699035D02*
X364912Y699134D01*
G01X364902Y698963D02*
X364908Y699035D01*
G01X364904Y698937D02*
X364902Y698963D01*
G01X364908Y704035D02*
X364912Y704134D01*
G01X364902Y703963D02*
X364908Y704035D01*
G01X364904Y703937D02*
X364902Y703963D01*
G01X364908Y709035D02*
X364912Y709134D01*
G01X364902Y708963D02*
X364908Y709035D01*
G01X364904Y708937D02*
X364902Y708963D01*
G01X364908Y714035D02*
X364912Y714134D01*
G01X364902Y713963D02*
X364908Y714035D01*
G01X364904Y713937D02*
X364902Y713963D01*
G01X364908Y719035D02*
X364912Y719134D01*
G01X364902Y718963D02*
X364908Y719035D01*
G01X364904Y718937D02*
X364902Y718963D01*
G01X364908Y724035D02*
X364912Y724134D01*
G01X364902Y723963D02*
X364908Y724035D01*
G01X364904Y723937D02*
X364902Y723963D01*
G01X364908Y729035D02*
X364912Y729134D01*
G01X364902Y728963D02*
X364908Y729035D01*
G01X364904Y728937D02*
X364902Y728963D01*
G01X364908Y734035D02*
X364912Y734134D01*
G01X364902Y733963D02*
X364908Y734035D01*
G01X364904Y733937D02*
X364902Y733963D01*
G01X364908Y739035D02*
X364912Y739134D01*
G01X364902Y738963D02*
X364908Y739035D01*
G01X364904Y738937D02*
X364902Y738963D01*
G01X364908Y744035D02*
X364912Y744134D01*
G01X364902Y743963D02*
X364908Y744035D01*
G01X364904Y743937D02*
X364902Y743963D01*
G01X363957Y742557D02*
X363958Y742559D01*
G01X363957Y742552D02*
Y742557D01*
G01Y742543D02*
Y742552D01*
G01Y737557D02*
X363958Y737559D01*
G01X363957Y737552D02*
Y737557D01*
G01Y737543D02*
Y737552D01*
G01Y732557D02*
X363958Y732559D01*
G01X363957Y732552D02*
Y732557D01*
G01Y732543D02*
Y732552D01*
G01Y727557D02*
X363958Y727559D01*
G01X363957Y727552D02*
Y727557D01*
G01Y727543D02*
Y727552D01*
G01Y722557D02*
X363958Y722559D01*
G01X363957Y722552D02*
Y722557D01*
G01Y722543D02*
Y722552D01*
G01Y717557D02*
X363958Y717559D01*
G01X363957Y717552D02*
Y717557D01*
G01Y717543D02*
Y717552D01*
G01Y712557D02*
X363958Y712559D01*
G01X363957Y712552D02*
Y712557D01*
G01Y712543D02*
Y712552D01*
G01Y707557D02*
X363958Y707559D01*
G01X363957Y707552D02*
Y707557D01*
G01Y707543D02*
Y707552D01*
G01Y702557D02*
X363958Y702559D01*
G01X363957Y702552D02*
Y702557D01*
G01Y702543D02*
Y702552D01*
G01Y697557D02*
X363958Y697559D01*
G01X363957Y697552D02*
Y697557D01*
G01Y697543D02*
Y697552D01*
G01X364941Y698904D02*
Y698911D01*
G01X364942Y698900D02*
X364941Y698904D01*
G01X364943Y698898D02*
X364942Y698900D01*
G01X363957Y698944D02*
Y698954D01*
G01Y698939D02*
Y698944D01*
G01X363958Y698937D02*
X363957Y698939D01*
G01Y703944D02*
Y703954D01*
G01Y703939D02*
Y703944D01*
G01X363958Y703937D02*
X363957Y703939D01*
G01Y708944D02*
Y708954D01*
G01Y708939D02*
Y708944D01*
G01X363958Y708937D02*
X363957Y708939D01*
G01Y713944D02*
Y713954D01*
G01Y713939D02*
Y713944D01*
G01X363958Y713937D02*
X363957Y713939D01*
G01Y718944D02*
Y718954D01*
G01Y718939D02*
Y718944D01*
G01X363958Y718937D02*
X363957Y718939D01*
G01Y723944D02*
Y723954D01*
G01Y723939D02*
Y723944D01*
G01X363958Y723937D02*
X363957Y723939D01*
G01Y728944D02*
Y728954D01*
G01Y728939D02*
Y728944D01*
G01X363958Y728937D02*
X363957Y728939D01*
G01Y733944D02*
Y733954D01*
G01Y733939D02*
Y733944D01*
G01X363958Y733937D02*
X363957Y733939D01*
G01Y738944D02*
Y738954D01*
G01Y738939D02*
Y738944D01*
G01X363958Y738937D02*
X363957Y738939D01*
G01Y743944D02*
Y743954D01*
G01Y743939D02*
Y743944D01*
G01X363958Y743937D02*
X363957Y743939D01*
G01X364933Y699081D02*
X364941Y699055D01*
G01X364923Y699107D02*
X364933Y699081D01*
G01X364912Y699134D02*
X364923Y699107D01*
G01X364933Y704081D02*
X364941Y704055D01*
G01X364923Y704107D02*
X364933Y704081D01*
G01X364912Y704134D02*
X364923Y704107D01*
G01X364933Y709081D02*
X364941Y709055D01*
G01X364923Y709107D02*
X364933Y709081D01*
G01X364912Y709134D02*
X364923Y709107D01*
G01X364933Y714081D02*
X364941Y714055D01*
G01X364923Y714107D02*
X364933Y714081D01*
G01X364912Y714134D02*
X364923Y714107D01*
G01X364933Y719081D02*
X364941Y719055D01*
G01X364923Y719107D02*
X364933Y719081D01*
G01X364912Y719134D02*
X364923Y719107D01*
G01X364933Y724081D02*
X364941Y724055D01*
G01X364923Y724107D02*
X364933Y724081D01*
G01X364912Y724134D02*
X364923Y724107D01*
G01X364933Y729081D02*
X364941Y729055D01*
G01X364923Y729107D02*
X364933Y729081D01*
G01X364912Y729134D02*
X364923Y729107D01*
G01X364933Y734081D02*
X364941Y734055D01*
G01X364923Y734107D02*
X364933Y734081D01*
G01X364912Y734134D02*
X364923Y734107D01*
G01X364933Y739081D02*
X364941Y739055D01*
G01X364923Y739107D02*
X364933Y739081D01*
G01X364912Y739134D02*
X364923Y739107D01*
G01X364933Y744081D02*
X364941Y744055D01*
G01X364923Y744107D02*
X364933Y744081D01*
G01X364912Y744134D02*
X364923Y744107D01*
G01X364924Y698932D02*
X364904Y698937D01*
G01X364938Y698918D02*
X364924Y698932D01*
G01X364943Y698898D02*
X364938Y698918D01*
G01X364924Y703932D02*
X364904Y703937D01*
G01X364938Y703918D02*
X364924Y703932D01*
G01X364943Y703898D02*
X364938Y703918D01*
G01X364924Y708932D02*
X364904Y708937D01*
G01X364938Y708918D02*
X364924Y708932D01*
G01X364943Y708898D02*
X364938Y708918D01*
G01X364924Y713932D02*
X364904Y713937D01*
G01X364938Y713918D02*
X364924Y713932D01*
G01X364943Y713898D02*
X364938Y713918D01*
G01X364924Y718932D02*
X364904Y718937D01*
G01X364938Y718918D02*
X364924Y718932D01*
G01X364943Y718898D02*
X364938Y718918D01*
G01X364924Y723932D02*
X364904Y723937D01*
G01X364938Y723918D02*
X364924Y723932D01*
G01X364943Y723898D02*
X364938Y723918D01*
G01X364924Y728932D02*
X364904Y728937D01*
G01X364938Y728918D02*
X364924Y728932D01*
G01X364943Y728898D02*
X364938Y728918D01*
G01X364924Y733932D02*
X364904Y733937D01*
G01X364938Y733918D02*
X364924Y733932D01*
G01X364943Y733898D02*
X364938Y733918D01*
G01X364924Y738932D02*
X364904Y738937D01*
G01X364938Y738918D02*
X364924Y738932D01*
G01X364943Y738898D02*
X364938Y738918D01*
G01X364924Y743932D02*
X364904Y743937D01*
G01X364938Y743918D02*
X364924Y743932D01*
G01X364943Y743898D02*
X364938Y743918D01*
G01X364941Y742552D02*
Y742543D01*
G01X364942Y742557D02*
X364941Y742552D01*
G01X364944Y742559D02*
X364942Y742557D01*
G01X364941Y737552D02*
Y737543D01*
G01X364942Y737557D02*
X364941Y737552D01*
G01X364944Y737559D02*
X364942Y737557D01*
G01X364941Y732552D02*
Y732543D01*
G01X364942Y732557D02*
X364941Y732552D01*
G01X364944Y732559D02*
X364942Y732557D01*
G01X364941Y703904D02*
Y703911D01*
G01X364942Y703900D02*
X364941Y703904D01*
G01X364943Y703898D02*
X364942Y703900D01*
G01X364941Y708904D02*
Y708911D01*
G01X364942Y708900D02*
X364941Y708904D01*
G01X364943Y708898D02*
X364942Y708900D01*
G01X364941Y713904D02*
Y713911D01*
G01X364942Y713900D02*
X364941Y713904D01*
G01X364943Y713898D02*
X364942Y713900D01*
G01X364941Y718904D02*
Y718911D01*
G01X364942Y718900D02*
X364941Y718904D01*
G01X364943Y718898D02*
X364942Y718900D01*
G01X364941Y723904D02*
Y723911D01*
G01X364942Y723900D02*
X364941Y723904D01*
G01X364943Y723898D02*
X364942Y723900D01*
G01X364941Y728904D02*
Y728911D01*
G01X364942Y728900D02*
X364941Y728904D01*
G01X364943Y728898D02*
X364942Y728900D01*
G01X364941Y733904D02*
Y733911D01*
G01X364942Y733900D02*
X364941Y733904D01*
G01X364943Y733898D02*
X364942Y733900D01*
G01X364941Y738904D02*
Y738911D01*
G01X364942Y738900D02*
X364941Y738904D01*
G01X364943Y738898D02*
X364942Y738900D01*
G01X364941Y743904D02*
Y743911D01*
G01X364942Y743900D02*
X364941Y743904D01*
G01X364943Y743898D02*
X364942Y743900D01*
G01X364941Y727552D02*
Y727543D01*
G01X364942Y727557D02*
X364941Y727552D01*
G01X364944Y727559D02*
X364942Y727557D01*
G01X364941Y722552D02*
Y722543D01*
G01X364942Y722557D02*
X364941Y722552D01*
G01X364944Y722559D02*
X364942Y722557D01*
G01X364941Y717552D02*
Y717543D01*
G01X364942Y717557D02*
X364941Y717552D01*
G01X364944Y717559D02*
X364942Y717557D01*
G01X364941Y712552D02*
Y712543D01*
G01X364942Y712557D02*
X364941Y712552D01*
G01X364944Y712559D02*
X364942Y712557D01*
G01X364941Y707552D02*
Y707543D01*
G01X364942Y707557D02*
X364941Y707552D01*
G01X364944Y707559D02*
X364942Y707557D01*
G01X364941Y702552D02*
Y702543D01*
G01X364942Y702557D02*
X364941Y702552D01*
G01X364944Y702559D02*
X364942Y702557D01*
G01X364941Y697552D02*
Y697543D01*
G01X364942Y697557D02*
X364941Y697552D01*
G01X364944Y697559D02*
X364942Y697557D01*
G01X364928Y698929D02*
X364939Y698913D01*
G01X364904Y698937D02*
X364928Y698929D01*
G01Y703929D02*
X364939Y703913D01*
G01X364904Y703937D02*
X364928Y703929D01*
G01Y708929D02*
X364939Y708913D01*
G01X364904Y708937D02*
X364928Y708929D01*
G01Y713929D02*
X364939Y713913D01*
G01X364904Y713937D02*
X364928Y713929D01*
G01Y718929D02*
X364939Y718913D01*
G01X364904Y718937D02*
X364928Y718929D01*
G01Y723929D02*
X364939Y723913D01*
G01X364904Y723937D02*
X364928Y723929D01*
G01Y728929D02*
X364939Y728913D01*
G01X364904Y728937D02*
X364928Y728929D01*
G01Y733929D02*
X364939Y733913D01*
G01X364904Y733937D02*
X364928Y733929D01*
G01Y738929D02*
X364939Y738913D01*
G01X364904Y738937D02*
X364928Y738929D01*
G01Y743929D02*
X364939Y743913D01*
G01X364904Y743937D02*
X364928Y743929D01*
G01X364941Y744429D02*
X363957D01*
G01X363958Y743937D02*
X369291D01*
G01Y743898D02*
X364943D01*
G01X369291Y742559D02*
X363958D01*
G01X363957Y742067D02*
X364941D01*
G01Y739429D02*
X363957D01*
G01X363958Y738937D02*
X369291D01*
G01Y738898D02*
X364943D01*
G01X369291Y737559D02*
X363958D01*
G01X363957Y737067D02*
X364941D01*
G01Y734429D02*
X363957D01*
G01X363958Y733937D02*
X369291D01*
G01Y733898D02*
X364943D01*
G01X369291Y732559D02*
X363958D01*
G01X363957Y732067D02*
X364941D01*
G01Y729429D02*
X363957D01*
G01X363958Y728937D02*
X369291D01*
G01Y728898D02*
X364943D01*
G01X369291Y727559D02*
X363958D01*
G01X363957Y727067D02*
X364941D01*
G01Y724429D02*
X363957D01*
G01X363958Y723937D02*
X369291D01*
G01Y723898D02*
X364943D01*
G01X369291Y722559D02*
X363958D01*
G01X363957Y722067D02*
X364941D01*
G01Y719429D02*
X363957D01*
G01X363958Y718937D02*
X369291D01*
G01Y718898D02*
X364943D01*
G01X369291Y717559D02*
X363958D01*
G01X363957Y717067D02*
X364941D01*
G01Y714429D02*
X363957D01*
G01X363958Y713937D02*
X369291D01*
G01Y713898D02*
X364943D01*
G01X369291Y712559D02*
X363958D01*
G01X363957Y712067D02*
X364941D01*
G01Y709429D02*
X363957D01*
G01X363958Y708937D02*
X369291D01*
G01Y708898D02*
X364943D01*
G01X369291Y707559D02*
X363958D01*
G01X363957Y707067D02*
X364941D01*
G01X363957Y744133D02*
X364912Y744134D01*
G01X364941Y742363D02*
X363957Y742362D01*
G01Y739133D02*
X364912Y739134D01*
G01X364941Y737363D02*
X363957Y737362D01*
G01Y734133D02*
X364912Y734134D01*
G01X364941Y732363D02*
X363957Y732362D01*
G01Y729133D02*
X364912Y729134D01*
G01X364941Y727363D02*
X363957Y727362D01*
G01Y724133D02*
X364912Y724134D01*
G01X364941Y722363D02*
X363957Y722362D01*
G01Y719133D02*
X364912Y719134D01*
G01X364941Y717363D02*
X363957Y717362D01*
G01Y714133D02*
X364912Y714134D01*
G01X364941Y712363D02*
X363957Y712362D01*
G01Y709133D02*
X364912Y709134D01*
G01X364941Y707363D02*
X363957Y707362D01*
G01X364941Y704429D02*
X363957D01*
G01X363958Y703937D02*
X369291D01*
G01Y703898D02*
X364943D01*
G01X369291Y702559D02*
X363958D01*
G01X363957Y702067D02*
X364941D01*
G01Y699429D02*
X363957D01*
G01X363958Y698937D02*
X369291D01*
G01Y698898D02*
X364943D01*
G01X369291Y697559D02*
X363958D01*
G01X363957Y697067D02*
X364941D01*
G01X363957Y704133D02*
X364912Y704134D01*
G01X364941Y702363D02*
X363957Y702362D01*
G01Y699133D02*
X364912Y699134D01*
G01X364941Y697363D02*
X363957Y697362D01*
G01X364941Y698911D02*
Y698920D01*
G01Y703911D02*
Y703920D01*
G01Y708911D02*
Y708920D01*
G01Y713911D02*
Y713920D01*
G01Y718911D02*
Y718920D01*
G01Y723911D02*
Y723920D01*
G01Y728911D02*
Y728920D01*
G01Y733911D02*
Y733920D01*
G01Y738911D02*
Y738920D01*
G01Y743911D02*
Y743920D01*
G01X369291Y742559D02*
Y743937D01*
G01Y737559D02*
Y738937D01*
G01Y732559D02*
Y733937D01*
G01Y727559D02*
Y728937D01*
G01Y722559D02*
Y723937D01*
G01Y717559D02*
Y718937D01*
G01Y712559D02*
Y713937D01*
G01Y707559D02*
Y708937D01*
G01Y702559D02*
Y703937D01*
G01Y697559D02*
Y698937D01*
G01X366122D02*
Y697559D01*
G01Y703937D02*
Y702559D01*
G01Y708937D02*
Y707559D01*
G01Y713937D02*
Y712559D01*
G01Y718937D02*
Y717559D01*
G01Y723937D02*
Y722559D01*
G01Y728937D02*
Y727559D01*
G01Y733937D02*
Y732559D01*
G01Y738937D02*
Y737559D01*
G01Y743937D02*
Y742559D01*
G01X364941Y742067D02*
Y744429D01*
G01Y737067D02*
Y739429D01*
G01Y732067D02*
Y734429D01*
G01Y727067D02*
Y729429D01*
G01Y722067D02*
Y724429D01*
G01Y717067D02*
Y719429D01*
G01Y712067D02*
Y714429D01*
G01Y707067D02*
Y709429D01*
G01Y702067D02*
Y704429D01*
G01Y697067D02*
Y699429D01*
G01X363957D02*
Y697067D01*
G01Y704429D02*
Y702067D01*
G01Y709429D02*
Y707067D01*
G01Y714429D02*
Y712067D01*
G01Y719429D02*
Y717067D01*
G01Y724429D02*
Y722067D01*
G01Y729429D02*
Y727067D01*
G01Y734429D02*
Y732067D01*
G01Y739429D02*
Y737067D01*
G01Y744429D02*
Y742067D01*
G01X363386Y769429D02*
G03X362795Y770020I-591J0D01*
G01X370276Y768839D02*
G03X368307Y770807I-1969J-1D01*
G01X366339Y750610D02*
X363189D01*
G01X370276Y753091D02*
X366929Y749744D01*
G01X370276Y753091D02*
Y768839D01*
G01X363386Y763327D02*
Y769429D01*
G01X363189Y759154D02*
Y750610D01*
G01X389213Y844772D02*
G03X396138Y831641I37662J11471D01*
G01X389213Y844772D02*
G03X396138Y831641I37662J11471D01*
G01X389213Y844772D02*
G03X369252I-9981J-3039D01*
G01X389213D02*
G03X369252I-9981J-3040D01*
G01X364941Y1080308D02*
Y1080299D01*
G01X364942Y1080313D02*
X364941Y1080308D01*
G01X364944Y1080315D02*
X364942Y1080313D01*
G01X364941Y1075308D02*
Y1075299D01*
G01X364942Y1075313D02*
X364941Y1075308D01*
G01X364944Y1075315D02*
X364942Y1075313D01*
G01X364941Y1070308D02*
Y1070299D01*
G01X364942Y1070313D02*
X364941Y1070308D01*
G01X364944Y1070315D02*
X364942Y1070313D01*
G01X364908Y1071791D02*
X364912Y1071890D01*
G01X364902Y1071719D02*
X364908Y1071791D01*
G01X364904Y1071693D02*
X364902Y1071719D01*
G01X364908Y1076791D02*
X364912Y1076890D01*
G01X364902Y1076719D02*
X364908Y1076791D01*
G01X364904Y1076693D02*
X364902Y1076719D01*
G01X364908Y1081791D02*
X364912Y1081890D01*
G01X364902Y1081719D02*
X364908Y1081791D01*
G01X364904Y1081693D02*
X364902Y1081719D01*
G01X363957Y1080313D02*
X363958Y1080315D01*
G01X363957Y1080308D02*
Y1080313D01*
G01Y1080299D02*
Y1080308D01*
G01Y1075313D02*
X363958Y1075315D01*
G01X363957Y1075308D02*
Y1075313D01*
G01Y1075299D02*
Y1075308D01*
G01Y1070313D02*
X363958Y1070315D01*
G01X363957Y1070308D02*
Y1070313D01*
G01Y1070299D02*
Y1070308D01*
G01X364933Y1071837D02*
X364941Y1071811D01*
G01X364923Y1071863D02*
X364933Y1071837D01*
G01X364912Y1071890D02*
X364923Y1071863D01*
G01X364933Y1076837D02*
X364941Y1076811D01*
G01X364923Y1076863D02*
X364933Y1076837D01*
G01X364912Y1076890D02*
X364923Y1076863D01*
G01X364924Y1071688D02*
X364904Y1071693D01*
G01X364938Y1071674D02*
X364924Y1071688D01*
G01X364943Y1071654D02*
X364938Y1071674D01*
G01X364924Y1076688D02*
X364904Y1076693D01*
G01X364938Y1076674D02*
X364924Y1076688D01*
G01X364943Y1076654D02*
X364938Y1076674D01*
G01X364924Y1081688D02*
X364904Y1081693D01*
G01X364938Y1081674D02*
X364924Y1081688D01*
G01X364943Y1081654D02*
X364938Y1081674D01*
G01X363957Y1071700D02*
Y1071709D01*
G01Y1071695D02*
Y1071700D01*
G01X363958Y1071693D02*
X363957Y1071695D01*
G01Y1076700D02*
Y1076709D01*
G01Y1076695D02*
Y1076700D01*
G01X363958Y1076693D02*
X363957Y1076695D01*
G01Y1081700D02*
Y1081709D01*
G01Y1081695D02*
Y1081700D01*
G01X363958Y1081693D02*
X363957Y1081695D01*
G01X364933Y1081837D02*
X364941Y1081811D01*
G01X364923Y1081863D02*
X364933Y1081837D01*
G01X364912Y1081890D02*
X364923Y1081863D01*
G01X364941Y1071660D02*
Y1071667D01*
G01X364942Y1071656D02*
X364941Y1071660D01*
G01X364943Y1071654D02*
X364942Y1071656D01*
G01X364941Y1076660D02*
Y1076667D01*
G01X364942Y1076656D02*
X364941Y1076660D01*
G01X364943Y1076654D02*
X364942Y1076656D01*
G01X364941Y1081660D02*
Y1081667D01*
G01X364942Y1081656D02*
X364941Y1081660D01*
G01X364943Y1081654D02*
X364942Y1081656D01*
G01X364928Y1071685D02*
X364939Y1071669D01*
G01X364904Y1071693D02*
X364928Y1071685D01*
G01Y1076685D02*
X364939Y1076669D01*
G01X364904Y1076693D02*
X364928Y1076685D01*
G01Y1081685D02*
X364939Y1081669D01*
G01X364904Y1081693D02*
X364928Y1081685D01*
G01X362795Y1044232D02*
G03X363386Y1044823I0J591D01*
G01X368307Y1043445D02*
G03X370276Y1045413I0J1969D01*
G01X364941Y1082185D02*
X363957D01*
G01X363958Y1081693D02*
X369291D01*
G01Y1081654D02*
X364943D01*
G01X369291Y1080315D02*
X363958D01*
G01X363957Y1079823D02*
X364941D01*
G01Y1077185D02*
X363957D01*
G01X363958Y1076693D02*
X369291D01*
G01Y1076654D02*
X364943D01*
G01X369291Y1075315D02*
X363958D01*
G01X363957Y1074823D02*
X364941D01*
G01Y1072185D02*
X363957D01*
G01X363958Y1071693D02*
X369291D01*
G01Y1071654D02*
X364943D01*
G01X369291Y1070315D02*
X363958D01*
G01X363957Y1069823D02*
X364941D01*
G01X363957Y1081889D02*
X364912Y1081890D01*
G01X364941Y1080119D02*
X363957Y1080118D01*
G01Y1076889D02*
X364912Y1076890D01*
G01X364941Y1075119D02*
X363957Y1075118D01*
G01Y1071889D02*
X364912Y1071890D01*
G01X364941Y1070119D02*
X363957Y1070118D01*
G01X363189Y1063642D02*
X366339D01*
G01X366929Y1064508D02*
X370276Y1061161D01*
G01X364941Y1071667D02*
Y1071676D01*
G01Y1076667D02*
Y1076676D01*
G01Y1081667D02*
Y1081676D01*
G01X370276Y1045413D02*
Y1061161D01*
G01X369291Y1080315D02*
Y1081693D01*
G01Y1075315D02*
Y1076693D01*
G01Y1070315D02*
Y1071693D01*
G01X366929Y1202500D02*
Y1064508D01*
G01X366339Y1204744D02*
Y1062264D01*
G01X366122Y1071693D02*
Y1070315D01*
G01Y1076693D02*
Y1075315D01*
G01Y1081693D02*
Y1080315D01*
G01X364941Y1079823D02*
Y1082185D01*
G01Y1074823D02*
Y1077185D01*
G01Y1069823D02*
Y1072185D01*
G01Y1071667D02*
Y1071811D01*
G01Y1081667D02*
Y1081811D01*
G01Y1076667D02*
Y1076811D01*
G01X363957Y1072185D02*
Y1069823D01*
G01Y1077185D02*
Y1074823D01*
G01Y1082185D02*
Y1079823D01*
G01X363386Y1050925D02*
Y1044823D01*
G01X363189Y1063642D02*
Y1055098D01*
G01X364941Y1130308D02*
Y1130299D01*
G01X364942Y1130313D02*
X364941Y1130308D01*
G01X364944Y1130315D02*
X364942Y1130313D01*
G01X364941Y1125308D02*
Y1125299D01*
G01X364942Y1125313D02*
X364941Y1125308D01*
G01X364944Y1125315D02*
X364942Y1125313D01*
G01X364941Y1100308D02*
Y1100299D01*
G01X364942Y1100313D02*
X364941Y1100308D01*
G01X364944Y1100315D02*
X364942Y1100313D01*
G01X364941Y1095308D02*
Y1095299D01*
G01X364942Y1095313D02*
X364941Y1095308D01*
G01X364944Y1095315D02*
X364942Y1095313D01*
G01X364941Y1090308D02*
Y1090299D01*
G01X364942Y1090313D02*
X364941Y1090308D01*
G01X364944Y1090315D02*
X364942Y1090313D01*
G01X364941Y1085308D02*
Y1085299D01*
G01X364942Y1085313D02*
X364941Y1085308D01*
G01X364944Y1085315D02*
X364942Y1085313D01*
G01X364908Y1086791D02*
X364912Y1086890D01*
G01X364902Y1086719D02*
X364908Y1086791D01*
G01X364904Y1086693D02*
X364902Y1086719D01*
G01X364908Y1091791D02*
X364912Y1091890D01*
G01X364902Y1091719D02*
X364908Y1091791D01*
G01X364904Y1091693D02*
X364902Y1091719D01*
G01X364908Y1096791D02*
X364912Y1096890D01*
G01X364902Y1096719D02*
X364908Y1096791D01*
G01X364904Y1096693D02*
X364902Y1096719D01*
G01X364908Y1101791D02*
X364912Y1101890D01*
G01X364902Y1101719D02*
X364908Y1101791D01*
G01X364904Y1101693D02*
X364902Y1101719D01*
G01X364908Y1126791D02*
X364912Y1126890D01*
G01X364902Y1126719D02*
X364908Y1126791D01*
G01X364904Y1126693D02*
X364902Y1126719D01*
G01X363957Y1130313D02*
X363958Y1130315D01*
G01X363957Y1130308D02*
Y1130313D01*
G01Y1130299D02*
Y1130308D01*
G01Y1125313D02*
X363958Y1125315D01*
G01X363957Y1125308D02*
Y1125313D01*
G01Y1125299D02*
Y1125308D01*
G01Y1100313D02*
X363958Y1100315D01*
G01X363957Y1100308D02*
Y1100313D01*
G01Y1100299D02*
Y1100308D01*
G01Y1095313D02*
X363958Y1095315D01*
G01X363957Y1095308D02*
Y1095313D01*
G01Y1095299D02*
Y1095308D01*
G01Y1090313D02*
X363958Y1090315D01*
G01X363957Y1090308D02*
Y1090313D01*
G01Y1090299D02*
Y1090308D01*
G01Y1085313D02*
X363958Y1085315D01*
G01X363957Y1085308D02*
Y1085313D01*
G01Y1085299D02*
Y1085308D01*
G01X364924Y1086688D02*
X364904Y1086693D01*
G01X364938Y1086674D02*
X364924Y1086688D01*
G01X364943Y1086654D02*
X364938Y1086674D01*
G01X364924Y1091688D02*
X364904Y1091693D01*
G01X364938Y1091674D02*
X364924Y1091688D01*
G01X364943Y1091654D02*
X364938Y1091674D01*
G01X364924Y1096688D02*
X364904Y1096693D01*
G01X364938Y1096674D02*
X364924Y1096688D01*
G01X364943Y1096654D02*
X364938Y1096674D01*
G01X364924Y1101688D02*
X364904Y1101693D01*
G01X364938Y1101674D02*
X364924Y1101688D01*
G01X364943Y1101654D02*
X364938Y1101674D01*
G01X364924Y1126688D02*
X364904Y1126693D01*
G01X364938Y1126674D02*
X364924Y1126688D01*
G01X364943Y1126654D02*
X364938Y1126674D01*
G01X363957Y1086700D02*
Y1086709D01*
G01Y1086695D02*
Y1086700D01*
G01X363958Y1086693D02*
X363957Y1086695D01*
G01Y1091700D02*
Y1091709D01*
G01Y1091695D02*
Y1091700D01*
G01X363958Y1091693D02*
X363957Y1091695D01*
G01Y1096700D02*
Y1096709D01*
G01Y1096695D02*
Y1096700D01*
G01X363958Y1096693D02*
X363957Y1096695D01*
G01Y1101700D02*
Y1101709D01*
G01Y1101695D02*
Y1101700D01*
G01X363958Y1101693D02*
X363957Y1101695D01*
G01Y1126700D02*
Y1126709D01*
G01Y1126695D02*
Y1126700D01*
G01X363958Y1126693D02*
X363957Y1126695D01*
G01X364933Y1086837D02*
X364941Y1086811D01*
G01X364923Y1086863D02*
X364933Y1086837D01*
G01X364912Y1086890D02*
X364923Y1086863D01*
G01X364933Y1091837D02*
X364941Y1091811D01*
G01X364923Y1091863D02*
X364933Y1091837D01*
G01X364912Y1091890D02*
X364923Y1091863D01*
G01X364933Y1096837D02*
X364941Y1096811D01*
G01X364923Y1096863D02*
X364933Y1096837D01*
G01X364912Y1096890D02*
X364923Y1096863D01*
G01X364933Y1101837D02*
X364941Y1101811D01*
G01X364923Y1101863D02*
X364933Y1101837D01*
G01X364912Y1101890D02*
X364923Y1101863D01*
G01X364933Y1126837D02*
X364941Y1126811D01*
G01X364923Y1126863D02*
X364933Y1126837D01*
G01X364912Y1126890D02*
X364923Y1126863D01*
G01X364941Y1086660D02*
Y1086667D01*
G01X364942Y1086656D02*
X364941Y1086660D01*
G01X364943Y1086654D02*
X364942Y1086656D01*
G01X364941Y1091660D02*
Y1091667D01*
G01X364942Y1091656D02*
X364941Y1091660D01*
G01X364943Y1091654D02*
X364942Y1091656D01*
G01X364941Y1096660D02*
Y1096667D01*
G01X364942Y1096656D02*
X364941Y1096660D01*
G01X364943Y1096654D02*
X364942Y1096656D01*
G01X364941Y1101660D02*
Y1101667D01*
G01X364942Y1101656D02*
X364941Y1101660D01*
G01X364943Y1101654D02*
X364942Y1101656D01*
G01X364941Y1126660D02*
Y1126667D01*
G01X364942Y1126656D02*
X364941Y1126660D01*
G01X364943Y1126654D02*
X364942Y1126656D01*
G01X364928Y1086685D02*
X364939Y1086669D01*
G01X364904Y1086693D02*
X364928Y1086685D01*
G01Y1091685D02*
X364939Y1091669D01*
G01X364904Y1091693D02*
X364928Y1091685D01*
G01Y1096685D02*
X364939Y1096669D01*
G01X364904Y1096693D02*
X364928Y1096685D01*
G01Y1101685D02*
X364939Y1101669D01*
G01X364904Y1101693D02*
X364928Y1101685D01*
G01Y1126685D02*
X364939Y1126669D01*
G01X364904Y1126693D02*
X364928Y1126685D01*
G01X369291Y1130315D02*
X363958D01*
G01X363957Y1129823D02*
X364941D01*
G01Y1127185D02*
X363957D01*
G01X363958Y1126693D02*
X369291D01*
G01Y1126654D02*
X364943D01*
G01X369291Y1125315D02*
X363958D01*
G01X363957Y1124823D02*
X364941D01*
G01Y1102185D02*
X363957D01*
G01X363958Y1101693D02*
X369291D01*
G01Y1101654D02*
X364943D01*
G01X369291Y1100315D02*
X363958D01*
G01X363957Y1099823D02*
X364941D01*
G01Y1097185D02*
X363957D01*
G01X363958Y1096693D02*
X369291D01*
G01Y1096654D02*
X364943D01*
G01X369291Y1095315D02*
X363958D01*
G01X363957Y1094823D02*
X364941D01*
G01Y1092185D02*
X363957D01*
G01X363958Y1091693D02*
X369291D01*
G01Y1091654D02*
X364943D01*
G01X369291Y1090315D02*
X363958D01*
G01X363957Y1089823D02*
X364941D01*
G01Y1087185D02*
X363957D01*
G01X363958Y1086693D02*
X369291D01*
G01Y1086654D02*
X364943D01*
G01X369291Y1085315D02*
X363958D01*
G01X363957Y1084823D02*
X364941D01*
G01Y1130119D02*
X363957Y1130118D01*
G01Y1126889D02*
X364912Y1126890D01*
G01X364941Y1125119D02*
X363957Y1125118D01*
G01Y1101889D02*
X364912Y1101890D01*
G01X364941Y1100119D02*
X363957Y1100118D01*
G01Y1096889D02*
X364912Y1096890D01*
G01X364941Y1095119D02*
X363957Y1095118D01*
G01Y1091889D02*
X364912Y1091890D01*
G01X364941Y1090119D02*
X363957Y1090118D01*
G01Y1086889D02*
X364912Y1086890D01*
G01X364941Y1085119D02*
X363957Y1085118D01*
G01X364370Y1103642D02*
X365551Y1102461D01*
G01X364941Y1086667D02*
Y1086676D01*
G01Y1091667D02*
Y1091676D01*
G01Y1096667D02*
Y1096676D01*
G01Y1101667D02*
Y1101676D01*
G01Y1126667D02*
Y1126676D01*
G01X369291Y1130315D02*
Y1131693D01*
G01Y1125315D02*
Y1126693D01*
G01Y1100315D02*
Y1101693D01*
G01Y1095315D02*
Y1096693D01*
G01Y1090315D02*
Y1091693D01*
G01Y1085315D02*
Y1086693D01*
G01X366122D02*
Y1085315D01*
G01Y1091693D02*
Y1090315D01*
G01Y1096693D02*
Y1095315D01*
G01Y1101693D02*
Y1100315D01*
G01Y1126693D02*
Y1125315D01*
G01Y1131693D02*
Y1130315D01*
G01X365551Y1124547D02*
Y1102461D01*
G01X364941Y1129823D02*
Y1132185D01*
G01Y1124823D02*
Y1127185D01*
G01Y1099823D02*
Y1102185D01*
G01Y1094823D02*
Y1097185D01*
G01Y1089823D02*
Y1092185D01*
G01Y1084823D02*
Y1087185D01*
G01Y1091667D02*
Y1091811D01*
G01Y1086667D02*
Y1086811D01*
G01Y1101667D02*
Y1101811D01*
G01Y1096667D02*
Y1096811D01*
G01Y1126667D02*
Y1126811D01*
G01X364370Y1123366D02*
Y1103642D01*
G01X363957Y1087185D02*
Y1084823D01*
G01Y1092185D02*
Y1089823D01*
G01Y1097185D02*
Y1094823D01*
G01Y1102185D02*
Y1099823D01*
G01Y1127185D02*
Y1124823D01*
G01Y1132185D02*
Y1129823D01*
G01X364370Y1123366D02*
X365551Y1124547D01*
G01X364941Y1175308D02*
Y1175299D01*
G01X364942Y1175313D02*
X364941Y1175308D01*
G01X364944Y1175315D02*
X364942Y1175313D01*
G01X364941Y1170308D02*
Y1170299D01*
G01X364942Y1170313D02*
X364941Y1170308D01*
G01X364944Y1170315D02*
X364942Y1170313D01*
G01X364941Y1165308D02*
Y1165299D01*
G01X364942Y1165313D02*
X364941Y1165308D01*
G01X364944Y1165315D02*
X364942Y1165313D01*
G01X364941Y1160308D02*
Y1160299D01*
G01X364942Y1160313D02*
X364941Y1160308D01*
G01X364944Y1160315D02*
X364942Y1160313D01*
G01X364941Y1155308D02*
Y1155299D01*
G01X364942Y1155313D02*
X364941Y1155308D01*
G01X364944Y1155315D02*
X364942Y1155313D01*
G01X364941Y1150308D02*
Y1150299D01*
G01X364942Y1150313D02*
X364941Y1150308D01*
G01X364944Y1150315D02*
X364942Y1150313D01*
G01X364941Y1145308D02*
Y1145299D01*
G01X364942Y1145313D02*
X364941Y1145308D01*
G01X364944Y1145315D02*
X364942Y1145313D01*
G01X364941Y1140308D02*
Y1140299D01*
G01X364942Y1140313D02*
X364941Y1140308D01*
G01X364944Y1140315D02*
X364942Y1140313D01*
G01X364941Y1135308D02*
Y1135299D01*
G01X364942Y1135313D02*
X364941Y1135308D01*
G01X364944Y1135315D02*
X364942Y1135313D01*
G01X364908Y1131791D02*
X364912Y1131890D01*
G01X364902Y1131719D02*
X364908Y1131791D01*
G01X364904Y1131693D02*
X364902Y1131719D01*
G01X364908Y1136791D02*
X364912Y1136890D01*
G01X364902Y1136719D02*
X364908Y1136791D01*
G01X364904Y1136693D02*
X364902Y1136719D01*
G01X364908Y1141791D02*
X364912Y1141890D01*
G01X364902Y1141719D02*
X364908Y1141791D01*
G01X364904Y1141693D02*
X364902Y1141719D01*
G01X364908Y1146791D02*
X364912Y1146890D01*
G01X364902Y1146719D02*
X364908Y1146791D01*
G01X364904Y1146693D02*
X364902Y1146719D01*
G01X364908Y1151791D02*
X364912Y1151890D01*
G01X364902Y1151719D02*
X364908Y1151791D01*
G01X364904Y1151693D02*
X364902Y1151719D01*
G01X364908Y1156791D02*
X364912Y1156890D01*
G01X364902Y1156719D02*
X364908Y1156791D01*
G01X364904Y1156693D02*
X364902Y1156719D01*
G01X364908Y1161791D02*
X364912Y1161890D01*
G01X364902Y1161719D02*
X364908Y1161791D01*
G01X364904Y1161693D02*
X364902Y1161719D01*
G01X364908Y1166791D02*
X364912Y1166890D01*
G01X364902Y1166719D02*
X364908Y1166791D01*
G01X364904Y1166693D02*
X364902Y1166719D01*
G01X364908Y1171791D02*
X364912Y1171890D01*
G01X364902Y1171719D02*
X364908Y1171791D01*
G01X364904Y1171693D02*
X364902Y1171719D01*
G01X364908Y1176791D02*
X364912Y1176890D01*
G01X364902Y1176719D02*
X364908Y1176791D01*
G01X364904Y1176693D02*
X364902Y1176719D01*
G01X363957Y1175313D02*
X363958Y1175315D01*
G01X363957Y1175308D02*
Y1175313D01*
G01Y1175299D02*
Y1175308D01*
G01Y1170313D02*
X363958Y1170315D01*
G01X363957Y1170308D02*
Y1170313D01*
G01Y1170299D02*
Y1170308D01*
G01Y1165313D02*
X363958Y1165315D01*
G01X363957Y1165308D02*
Y1165313D01*
G01Y1165299D02*
Y1165308D01*
G01Y1160313D02*
X363958Y1160315D01*
G01X363957Y1160308D02*
Y1160313D01*
G01Y1160299D02*
Y1160308D01*
G01Y1155313D02*
X363958Y1155315D01*
G01X363957Y1155308D02*
Y1155313D01*
G01Y1155299D02*
Y1155308D01*
G01Y1150313D02*
X363958Y1150315D01*
G01X363957Y1150308D02*
Y1150313D01*
G01Y1150299D02*
Y1150308D01*
G01Y1145313D02*
X363958Y1145315D01*
G01X363957Y1145308D02*
Y1145313D01*
G01Y1145299D02*
Y1145308D01*
G01Y1140313D02*
X363958Y1140315D01*
G01X363957Y1140308D02*
Y1140313D01*
G01Y1140299D02*
Y1140308D01*
G01Y1135313D02*
X363958Y1135315D01*
G01X363957Y1135308D02*
Y1135313D01*
G01Y1135299D02*
Y1135308D01*
G01X364924Y1131688D02*
X364904Y1131693D01*
G01X364938Y1131674D02*
X364924Y1131688D01*
G01X364943Y1131654D02*
X364938Y1131674D01*
G01X364924Y1136688D02*
X364904Y1136693D01*
G01X364938Y1136674D02*
X364924Y1136688D01*
G01X364943Y1136654D02*
X364938Y1136674D01*
G01X364924Y1141688D02*
X364904Y1141693D01*
G01X364938Y1141674D02*
X364924Y1141688D01*
G01X364943Y1141654D02*
X364938Y1141674D01*
G01X364924Y1146688D02*
X364904Y1146693D01*
G01X364938Y1146674D02*
X364924Y1146688D01*
G01X364943Y1146654D02*
X364938Y1146674D01*
G01X364924Y1151688D02*
X364904Y1151693D01*
G01X364938Y1151674D02*
X364924Y1151688D01*
G01X364943Y1151654D02*
X364938Y1151674D01*
G01X364924Y1156688D02*
X364904Y1156693D01*
G01X364938Y1156674D02*
X364924Y1156688D01*
G01X364943Y1156654D02*
X364938Y1156674D01*
G01X364924Y1161688D02*
X364904Y1161693D01*
G01X364938Y1161674D02*
X364924Y1161688D01*
G01X364943Y1161654D02*
X364938Y1161674D01*
G01X364924Y1166688D02*
X364904Y1166693D01*
G01X364938Y1166674D02*
X364924Y1166688D01*
G01X364943Y1166654D02*
X364938Y1166674D01*
G01X364924Y1171688D02*
X364904Y1171693D01*
G01X364938Y1171674D02*
X364924Y1171688D01*
G01X364943Y1171654D02*
X364938Y1171674D01*
G01X364924Y1176688D02*
X364904Y1176693D01*
G01X364938Y1176674D02*
X364924Y1176688D01*
G01X364943Y1176654D02*
X364938Y1176674D01*
G01X363957Y1131700D02*
Y1131709D01*
G01Y1131695D02*
Y1131700D01*
G01X363958Y1131693D02*
X363957Y1131695D01*
G01Y1136700D02*
Y1136709D01*
G01Y1136695D02*
Y1136700D01*
G01X363958Y1136693D02*
X363957Y1136695D01*
G01Y1141700D02*
Y1141709D01*
G01Y1141695D02*
Y1141700D01*
G01X363958Y1141693D02*
X363957Y1141695D01*
G01Y1146700D02*
Y1146709D01*
G01Y1146695D02*
Y1146700D01*
G01X363958Y1146693D02*
X363957Y1146695D01*
G01Y1151700D02*
Y1151709D01*
G01Y1151695D02*
Y1151700D01*
G01X363958Y1151693D02*
X363957Y1151695D01*
G01Y1156700D02*
Y1156709D01*
G01Y1156695D02*
Y1156700D01*
G01X363958Y1156693D02*
X363957Y1156695D01*
G01Y1161700D02*
Y1161709D01*
G01Y1161695D02*
Y1161700D01*
G01X363958Y1161693D02*
X363957Y1161695D01*
G01Y1166700D02*
Y1166709D01*
G01Y1166695D02*
Y1166700D01*
G01X363958Y1166693D02*
X363957Y1166695D01*
G01Y1171700D02*
Y1171709D01*
G01Y1171695D02*
Y1171700D01*
G01X363958Y1171693D02*
X363957Y1171695D01*
G01Y1176700D02*
Y1176709D01*
G01Y1176695D02*
Y1176700D01*
G01X363958Y1176693D02*
X363957Y1176695D01*
G01X364933Y1131837D02*
X364941Y1131811D01*
G01X364923Y1131863D02*
X364933Y1131837D01*
G01X364912Y1131890D02*
X364923Y1131863D01*
G01X364933Y1136837D02*
X364941Y1136811D01*
G01X364923Y1136863D02*
X364933Y1136837D01*
G01X364912Y1136890D02*
X364923Y1136863D01*
G01X364933Y1141837D02*
X364941Y1141811D01*
G01X364923Y1141863D02*
X364933Y1141837D01*
G01X364912Y1141890D02*
X364923Y1141863D01*
G01X364933Y1146837D02*
X364941Y1146811D01*
G01X364923Y1146863D02*
X364933Y1146837D01*
G01X364912Y1146890D02*
X364923Y1146863D01*
G01X364933Y1151837D02*
X364941Y1151811D01*
G01X364923Y1151863D02*
X364933Y1151837D01*
G01X364912Y1151890D02*
X364923Y1151863D01*
G01X364933Y1156837D02*
X364941Y1156811D01*
G01X364923Y1156863D02*
X364933Y1156837D01*
G01X364912Y1156890D02*
X364923Y1156863D01*
G01X364933Y1161837D02*
X364941Y1161811D01*
G01X364923Y1161863D02*
X364933Y1161837D01*
G01X364912Y1161890D02*
X364923Y1161863D01*
G01X364933Y1166837D02*
X364941Y1166811D01*
G01X364923Y1166863D02*
X364933Y1166837D01*
G01X364912Y1166890D02*
X364923Y1166863D01*
G01X364933Y1171837D02*
X364941Y1171811D01*
G01X364923Y1171863D02*
X364933Y1171837D01*
G01X364912Y1171890D02*
X364923Y1171863D01*
G01X364933Y1176837D02*
X364941Y1176811D01*
G01X364923Y1176863D02*
X364933Y1176837D01*
G01X364912Y1176890D02*
X364923Y1176863D01*
G01X364941Y1131660D02*
Y1131667D01*
G01X364942Y1131656D02*
X364941Y1131660D01*
G01X364943Y1131654D02*
X364942Y1131656D01*
G01X364941Y1136660D02*
Y1136667D01*
G01X364942Y1136656D02*
X364941Y1136660D01*
G01X364943Y1136654D02*
X364942Y1136656D01*
G01X364941Y1141660D02*
Y1141667D01*
G01X364942Y1141656D02*
X364941Y1141660D01*
G01X364943Y1141654D02*
X364942Y1141656D01*
G01X364941Y1146660D02*
Y1146667D01*
G01X364942Y1146656D02*
X364941Y1146660D01*
G01X364943Y1146654D02*
X364942Y1146656D01*
G01X364941Y1151660D02*
Y1151667D01*
G01X364942Y1151656D02*
X364941Y1151660D01*
G01X364943Y1151654D02*
X364942Y1151656D01*
G01X364941Y1156660D02*
Y1156667D01*
G01X364942Y1156656D02*
X364941Y1156660D01*
G01X364943Y1156654D02*
X364942Y1156656D01*
G01X364941Y1161660D02*
Y1161667D01*
G01X364942Y1161656D02*
X364941Y1161660D01*
G01X364943Y1161654D02*
X364942Y1161656D01*
G01X364941Y1166660D02*
Y1166667D01*
G01X364942Y1166656D02*
X364941Y1166660D01*
G01X364943Y1166654D02*
X364942Y1166656D01*
G01X364941Y1171660D02*
Y1171667D01*
G01X364942Y1171656D02*
X364941Y1171660D01*
G01X364943Y1171654D02*
X364942Y1171656D01*
G01X364941Y1176660D02*
Y1176667D01*
G01X364942Y1176656D02*
X364941Y1176660D01*
G01X364943Y1176654D02*
X364942Y1176656D01*
G01X364928Y1131685D02*
X364939Y1131669D01*
G01X364904Y1131693D02*
X364928Y1131685D01*
G01Y1136685D02*
X364939Y1136669D01*
G01X364904Y1136693D02*
X364928Y1136685D01*
G01Y1141685D02*
X364939Y1141669D01*
G01X364904Y1141693D02*
X364928Y1141685D01*
G01Y1146685D02*
X364939Y1146669D01*
G01X364904Y1146693D02*
X364928Y1146685D01*
G01Y1151685D02*
X364939Y1151669D01*
G01X364904Y1151693D02*
X364928Y1151685D01*
G01Y1156685D02*
X364939Y1156669D01*
G01X364904Y1156693D02*
X364928Y1156685D01*
G01Y1161685D02*
X364939Y1161669D01*
G01X364904Y1161693D02*
X364928Y1161685D01*
G01Y1166685D02*
X364939Y1166669D01*
G01X364904Y1166693D02*
X364928Y1166685D01*
G01Y1171685D02*
X364939Y1171669D01*
G01X364904Y1171693D02*
X364928Y1171685D01*
G01Y1176685D02*
X364939Y1176669D01*
G01X364904Y1176693D02*
X364928Y1176685D01*
G01X364941Y1177185D02*
X363957D01*
G01X363958Y1176693D02*
X369291D01*
G01Y1176654D02*
X364943D01*
G01X369291Y1175315D02*
X363958D01*
G01X363957Y1174823D02*
X364941D01*
G01Y1172185D02*
X363957D01*
G01X363958Y1171693D02*
X369291D01*
G01Y1171654D02*
X364943D01*
G01X369291Y1170315D02*
X363958D01*
G01X363957Y1169823D02*
X364941D01*
G01Y1167185D02*
X363957D01*
G01X363958Y1166693D02*
X369291D01*
G01Y1166654D02*
X364943D01*
G01X369291Y1165315D02*
X363958D01*
G01X363957Y1164823D02*
X364941D01*
G01Y1162185D02*
X363957D01*
G01X363958Y1161693D02*
X369291D01*
G01Y1161654D02*
X364943D01*
G01X369291Y1160315D02*
X363958D01*
G01X363957Y1159823D02*
X364941D01*
G01Y1157185D02*
X363957D01*
G01X363958Y1156693D02*
X369291D01*
G01Y1156654D02*
X364943D01*
G01X369291Y1155315D02*
X363958D01*
G01X363957Y1154823D02*
X364941D01*
G01X363957Y1176889D02*
X364912Y1176890D01*
G01X364941Y1175119D02*
X363957Y1175118D01*
G01Y1171889D02*
X364912Y1171890D01*
G01X364941Y1170119D02*
X363957Y1170118D01*
G01Y1166889D02*
X364912Y1166890D01*
G01X364941Y1165119D02*
X363957Y1165118D01*
G01Y1161889D02*
X364912Y1161890D01*
G01X364941Y1160119D02*
X363957Y1160118D01*
G01Y1156889D02*
X364912Y1156890D01*
G01X364941Y1155119D02*
X363957Y1155118D01*
G01X364941Y1152185D02*
X363957D01*
G01X363958Y1151693D02*
X369291D01*
G01Y1151654D02*
X364943D01*
G01X369291Y1150315D02*
X363958D01*
G01X363957Y1149823D02*
X364941D01*
G01Y1147185D02*
X363957D01*
G01X363958Y1146693D02*
X369291D01*
G01Y1146654D02*
X364943D01*
G01X369291Y1145315D02*
X363958D01*
G01X363957Y1144823D02*
X364941D01*
G01Y1142185D02*
X363957D01*
G01X363958Y1141693D02*
X369291D01*
G01Y1141654D02*
X364943D01*
G01X369291Y1140315D02*
X363958D01*
G01X363957Y1139823D02*
X364941D01*
G01Y1137185D02*
X363957D01*
G01X363958Y1136693D02*
X369291D01*
G01Y1136654D02*
X364943D01*
G01X369291Y1135315D02*
X363958D01*
G01X363957Y1134823D02*
X364941D01*
G01Y1132185D02*
X363957D01*
G01X363958Y1131693D02*
X369291D01*
G01Y1131654D02*
X364943D01*
G01X363957Y1151889D02*
X364912Y1151890D01*
G01X364941Y1150119D02*
X363957Y1150118D01*
G01Y1146889D02*
X364912Y1146890D01*
G01X364941Y1145119D02*
X363957Y1145118D01*
G01Y1141889D02*
X364912Y1141890D01*
G01X364941Y1140119D02*
X363957Y1140118D01*
G01Y1136889D02*
X364912Y1136890D01*
G01X364941Y1135119D02*
X363957Y1135118D01*
G01Y1131889D02*
X364912Y1131890D01*
G01X364941Y1131667D02*
Y1131676D01*
G01Y1136667D02*
Y1136676D01*
G01Y1141667D02*
Y1141676D01*
G01Y1146667D02*
Y1146676D01*
G01Y1151667D02*
Y1151676D01*
G01Y1156667D02*
Y1156676D01*
G01Y1161667D02*
Y1161676D01*
G01Y1166667D02*
Y1166676D01*
G01Y1171667D02*
Y1171676D01*
G01Y1176667D02*
Y1176676D01*
G01X369291Y1175315D02*
Y1176693D01*
G01Y1170315D02*
Y1171693D01*
G01Y1165315D02*
Y1166693D01*
G01Y1160315D02*
Y1161693D01*
G01Y1155315D02*
Y1156693D01*
G01Y1150315D02*
Y1151693D01*
G01Y1145315D02*
Y1146693D01*
G01Y1140315D02*
Y1141693D01*
G01Y1135315D02*
Y1136693D01*
G01X366122D02*
Y1135315D01*
G01Y1141693D02*
Y1140315D01*
G01Y1146693D02*
Y1145315D01*
G01Y1151693D02*
Y1150315D01*
G01Y1156693D02*
Y1155315D01*
G01Y1161693D02*
Y1160315D01*
G01Y1166693D02*
Y1165315D01*
G01Y1171693D02*
Y1170315D01*
G01Y1176693D02*
Y1175315D01*
G01X364941Y1174823D02*
Y1177185D01*
G01Y1169823D02*
Y1172185D01*
G01Y1164823D02*
Y1167185D01*
G01Y1159823D02*
Y1162185D01*
G01Y1154823D02*
Y1157185D01*
G01Y1149823D02*
Y1152185D01*
G01Y1144823D02*
Y1147185D01*
G01Y1139823D02*
Y1142185D01*
G01Y1134823D02*
Y1137185D01*
G01Y1131667D02*
Y1131811D01*
G01Y1141667D02*
Y1141811D01*
G01Y1136667D02*
Y1136811D01*
G01Y1151667D02*
Y1151811D01*
G01Y1146667D02*
Y1146811D01*
G01Y1161667D02*
Y1161811D01*
G01Y1156667D02*
Y1156811D01*
G01Y1171667D02*
Y1171811D01*
G01Y1166667D02*
Y1166811D01*
G01Y1176667D02*
Y1176811D01*
G01X363957Y1137185D02*
Y1134823D01*
G01Y1142185D02*
Y1139823D01*
G01Y1147185D02*
Y1144823D01*
G01Y1152185D02*
Y1149823D01*
G01Y1157185D02*
Y1154823D01*
G01Y1162185D02*
Y1159823D01*
G01Y1167185D02*
Y1164823D01*
G01Y1172185D02*
Y1169823D01*
G01Y1177185D02*
Y1174823D01*
G01X364941Y1195308D02*
Y1195299D01*
G01X364942Y1195313D02*
X364941Y1195308D01*
G01X364944Y1195315D02*
X364942Y1195313D01*
G01X364941Y1190308D02*
Y1190299D01*
G01X364942Y1190313D02*
X364941Y1190308D01*
G01X364944Y1190315D02*
X364942Y1190313D01*
G01X364941Y1185308D02*
Y1185299D01*
G01X364942Y1185313D02*
X364941Y1185308D01*
G01X364944Y1185315D02*
X364942Y1185313D01*
G01X364941Y1180308D02*
Y1180299D01*
G01X364942Y1180313D02*
X364941Y1180308D01*
G01X364944Y1180315D02*
X364942Y1180313D01*
G01X364908Y1181791D02*
X364912Y1181890D01*
G01X364902Y1181719D02*
X364908Y1181791D01*
G01X364904Y1181693D02*
X364902Y1181719D01*
G01X364908Y1186791D02*
X364912Y1186890D01*
G01X364902Y1186719D02*
X364908Y1186791D01*
G01X364904Y1186693D02*
X364902Y1186719D01*
G01X364908Y1191791D02*
X364912Y1191890D01*
G01X364902Y1191719D02*
X364908Y1191791D01*
G01X364904Y1191693D02*
X364902Y1191719D01*
G01X364908Y1196791D02*
X364912Y1196890D01*
G01X364902Y1196719D02*
X364908Y1196791D01*
G01X364904Y1196693D02*
X364902Y1196719D01*
G01X363957Y1195313D02*
X363958Y1195315D01*
G01X363957Y1195308D02*
Y1195313D01*
G01Y1195299D02*
Y1195308D01*
G01Y1190313D02*
X363958Y1190315D01*
G01X363957Y1190308D02*
Y1190313D01*
G01Y1190299D02*
Y1190308D01*
G01Y1185313D02*
X363958Y1185315D01*
G01X363957Y1185308D02*
Y1185313D01*
G01Y1185299D02*
Y1185308D01*
G01Y1180313D02*
X363958Y1180315D01*
G01X363957Y1180308D02*
Y1180313D01*
G01Y1180299D02*
Y1180308D01*
G01X364924Y1181688D02*
X364904Y1181693D01*
G01X364938Y1181674D02*
X364924Y1181688D01*
G01X364943Y1181654D02*
X364938Y1181674D01*
G01X364924Y1186688D02*
X364904Y1186693D01*
G01X364938Y1186674D02*
X364924Y1186688D01*
G01X364943Y1186654D02*
X364938Y1186674D01*
G01X364924Y1191688D02*
X364904Y1191693D01*
G01X364938Y1191674D02*
X364924Y1191688D01*
G01X364943Y1191654D02*
X364938Y1191674D01*
G01X364924Y1196688D02*
X364904Y1196693D01*
G01X364938Y1196674D02*
X364924Y1196688D01*
G01X364943Y1196654D02*
X364938Y1196674D01*
G01X363957Y1181700D02*
Y1181709D01*
G01Y1181695D02*
Y1181700D01*
G01X363958Y1181693D02*
X363957Y1181695D01*
G01Y1186700D02*
Y1186709D01*
G01Y1186695D02*
Y1186700D01*
G01X363958Y1186693D02*
X363957Y1186695D01*
G01Y1191700D02*
Y1191709D01*
G01Y1191695D02*
Y1191700D01*
G01X363958Y1191693D02*
X363957Y1191695D01*
G01Y1196700D02*
Y1196709D01*
G01Y1196695D02*
Y1196700D01*
G01X363958Y1196693D02*
X363957Y1196695D01*
G01X364933Y1181837D02*
X364941Y1181811D01*
G01X364923Y1181863D02*
X364933Y1181837D01*
G01X364912Y1181890D02*
X364923Y1181863D01*
G01X364933Y1186837D02*
X364941Y1186811D01*
G01X364923Y1186863D02*
X364933Y1186837D01*
G01X364912Y1186890D02*
X364923Y1186863D01*
G01X364933Y1191837D02*
X364941Y1191811D01*
G01X364923Y1191863D02*
X364933Y1191837D01*
G01X364912Y1191890D02*
X364923Y1191863D01*
G01X364933Y1196837D02*
X364941Y1196811D01*
G01X364923Y1196863D02*
X364933Y1196837D01*
G01X364912Y1196890D02*
X364923Y1196863D01*
G01X364941Y1181660D02*
Y1181667D01*
G01X364942Y1181656D02*
X364941Y1181660D01*
G01X364943Y1181654D02*
X364942Y1181656D01*
G01X364941Y1186660D02*
Y1186667D01*
G01X364942Y1186656D02*
X364941Y1186660D01*
G01X364943Y1186654D02*
X364942Y1186656D01*
G01X364941Y1191660D02*
Y1191667D01*
G01X364942Y1191656D02*
X364941Y1191660D01*
G01X364943Y1191654D02*
X364942Y1191656D01*
G01X364941Y1196660D02*
Y1196667D01*
G01X364942Y1196656D02*
X364941Y1196660D01*
G01X364943Y1196654D02*
X364942Y1196656D01*
G01X364928Y1181685D02*
X364939Y1181669D01*
G01X364904Y1181693D02*
X364928Y1181685D01*
G01Y1186685D02*
X364939Y1186669D01*
G01X364904Y1186693D02*
X364928Y1186685D01*
G01Y1191685D02*
X364939Y1191669D01*
G01X364904Y1191693D02*
X364928Y1191685D01*
G01Y1196685D02*
X364939Y1196669D01*
G01X364904Y1196693D02*
X364928Y1196685D01*
G01X370276Y1221594D02*
G03X368307Y1223563I-1969J0D01*
G01X363386Y1222185D02*
G03X362795Y1222776I-591J0D01*
G01X366339Y1203366D02*
X363189D01*
G01X364941Y1197185D02*
X363957D01*
G01X363958Y1196693D02*
X369291D01*
G01Y1196654D02*
X364943D01*
G01X369291Y1195315D02*
X363958D01*
G01X363957Y1194823D02*
X364941D01*
G01Y1192185D02*
X363957D01*
G01X363958Y1191693D02*
X369291D01*
G01Y1191654D02*
X364943D01*
G01X369291Y1190315D02*
X363958D01*
G01X363957Y1189823D02*
X364941D01*
G01Y1187185D02*
X363957D01*
G01X363958Y1186693D02*
X369291D01*
G01Y1186654D02*
X364943D01*
G01X369291Y1185315D02*
X363958D01*
G01X363957Y1184823D02*
X364941D01*
G01Y1182185D02*
X363957D01*
G01X363958Y1181693D02*
X369291D01*
G01Y1181654D02*
X364943D01*
G01X369291Y1180315D02*
X363958D01*
G01X363957Y1179823D02*
X364941D01*
G01X363957Y1196889D02*
X364912Y1196890D01*
G01X364941Y1195119D02*
X363957Y1195118D01*
G01Y1191889D02*
X364912Y1191890D01*
G01X364941Y1190119D02*
X363957Y1190118D01*
G01Y1186889D02*
X364912Y1186890D01*
G01X364941Y1185119D02*
X363957Y1185118D01*
G01Y1181889D02*
X364912Y1181890D01*
G01X364941Y1180119D02*
X363957Y1180118D01*
G01X364941Y1181667D02*
Y1181676D01*
G01Y1186667D02*
Y1186676D01*
G01Y1191667D02*
Y1191676D01*
G01Y1196667D02*
Y1196676D01*
G01X370276Y1205846D02*
Y1221594D01*
G01X369291Y1195315D02*
Y1196693D01*
G01Y1190315D02*
Y1191693D01*
G01Y1185315D02*
Y1186693D01*
G01Y1180315D02*
Y1181693D01*
G01X366122D02*
Y1180315D01*
G01Y1186693D02*
Y1185315D01*
G01Y1191693D02*
Y1190315D01*
G01Y1196693D02*
Y1195315D01*
G01X364941Y1194823D02*
Y1197185D01*
G01Y1189823D02*
Y1192185D01*
G01Y1184823D02*
Y1187185D01*
G01Y1179823D02*
Y1182185D01*
G01Y1181667D02*
Y1181811D01*
G01Y1191667D02*
Y1191811D01*
G01Y1186667D02*
Y1186811D01*
G01Y1196667D02*
Y1196811D01*
G01X363957Y1182185D02*
Y1179823D01*
G01Y1187185D02*
Y1184823D01*
G01Y1192185D02*
Y1189823D01*
G01Y1197185D02*
Y1194823D01*
G01X363386Y1216083D02*
Y1222185D01*
G01X363189Y1211909D02*
Y1203366D01*
G01X370276Y1205846D02*
X366929Y1202500D01*
G01X389213Y1297528D02*
G03X396138Y1284397I37662J11471D01*
G01X389213Y1297528D02*
G03X369252I-9981J-3040D01*
G01X389213D02*
G03X396138Y1284397I37662J11471D01*
G01X389213Y1297528D02*
G03X369252I-9981J-3040D01*
G01X393110Y1382677D02*
G03Y1374803I0J-3937D01*
G01Y1382677D02*
X692520D01*
G01X393110D02*
X692520D01*
G01X393110D02*
G03Y1374803I0J-3937D01*
G01X443701Y374803D02*
G03X444882I591J0D01*
G01Y368504D02*
G03X443701I-590J0D01*
G01X441732D02*
G03X440551I-591J0D01*
G01Y374803D02*
G03X441732I590J0D01*
G01X443701D02*
G03X444882I591J0D01*
G01Y368504D02*
G03X443701I-590J0D01*
G01X441732D02*
G03X440551I-591J0D01*
G01Y374803D02*
G03X441732I590J0D01*
G01X443701D02*
X441732D01*
G01X440551D02*
X439764D01*
G01X443701D02*
X441732D01*
G01X440551D02*
X439764D01*
G01X445669D02*
X444882D01*
G01X445669D02*
X444882D01*
G01X445669Y373819D02*
X439764D01*
G01Y373622D02*
X445669D01*
G01X439764Y369685D02*
X445669D01*
G01Y369488D02*
X439764D01*
G01X444882Y368504D02*
X445669D01*
G01X444882D02*
X445669D01*
G01X441732D02*
X443701D01*
G01X439764D02*
X440551D01*
G01X441732D02*
X443701D01*
G01X439764D02*
X440551D01*
G01X445669D02*
Y374803D01*
G01Y368504D02*
Y374803D01*
G01X439764Y368504D02*
Y374803D01*
G01D02*
Y368504D01*
G01X443701Y827559D02*
G03X444882I591J0D01*
G01Y821260D02*
G03X443701I-590J0D01*
G01X441732D02*
G03X440551I-591J0D01*
G01Y827559D02*
G03X441732I590J0D01*
G01X443701D02*
G03X444882I591J0D01*
G01Y821260D02*
G03X443701I-590J0D01*
G01X441732D02*
G03X440551I-591J0D01*
G01Y827559D02*
G03X441732I590J0D01*
G01X443701D02*
X441732D01*
G01X440551D02*
X439764D01*
G01X443701D02*
X441732D01*
G01X440551D02*
X439764D01*
G01X445669D02*
X444882D01*
G01X445669D02*
X444882D01*
G01X445669Y826575D02*
X439764D01*
G01Y826378D02*
X445669D01*
G01X439764Y822441D02*
X445669D01*
G01Y822244D02*
X439764D01*
G01X444882Y821260D02*
X445669D01*
G01X444882D02*
X445669D01*
G01X441732D02*
X443701D01*
G01X439764D02*
X440551D01*
G01X441732D02*
X443701D01*
G01X439764D02*
X440551D01*
G01X445669D02*
Y827559D01*
G01Y821260D02*
Y827559D01*
G01X439764Y821260D02*
Y827559D01*
G01D02*
Y821260D01*
G01X414665Y1141732D02*
G03X428642I6989J0D01*
G01D02*
G03X414665I-6989J0D01*
G01X428642D02*
G03I-6988J0D01*
G01X444882Y1274016D02*
G03X443701I-590J0D01*
G01X441732D02*
G03X440551I-591J0D01*
G01X444882D02*
G03X443701I-590J0D01*
G01X441732D02*
G03X440551I-591J0D01*
G01X439764Y1275197D02*
X445669D01*
G01Y1275000D02*
X439764D01*
G01X444882Y1274016D02*
X445669D01*
G01X444882D02*
X445669D01*
G01X441732D02*
X443701D01*
G01X439764D02*
X440551D01*
G01X441732D02*
X443701D01*
G01X439764D02*
X440551D01*
G01X445669D02*
Y1280315D01*
G01Y1274016D02*
Y1280315D01*
G01X439764Y1274016D02*
Y1280315D01*
G01D02*
Y1274016D01*
G01X443701Y1280315D02*
G03X444882I591J0D01*
G01X440551D02*
G03X441732I590J0D01*
G01X443701D02*
G03X444882I591J0D01*
G01X440551D02*
G03X441732I590J0D01*
G01X443701D02*
X441732D01*
G01X440551D02*
X439764D01*
G01X443701D02*
X441732D01*
G01X440551D02*
X439764D01*
G01X445669D02*
X444882D01*
G01X445669D02*
X444882D01*
G01X445669Y1279331D02*
X439764D01*
G01Y1279134D02*
X445669D01*
G01X491634Y110551D02*
G03X501673I5020J0D01*
G01D02*
G03X491634I-5019J0D01*
G01X491909Y80906D02*
G03X501398I4744J0D01*
G01D02*
G03X491909I-4744J0D01*
G01X501398D02*
G03I-4744J0D01*
G01X501673Y110551D02*
G03I-5019J0D01*
G01X479724Y139311D02*
G03X480315Y138720I591J0D01*
G01X487008D02*
G03X487598Y139311I-1J591D01*
G01X484843Y140492D02*
G03Y142461I0J984D01*
G01X482480D02*
G03Y140492I0J-984D01*
G01X484764Y153681D02*
G03I-1103J0D01*
G01X486220Y148406D02*
G03X487402Y149587I1J1181D01*
G01X479921D02*
G03X481102Y148406I1181J0D01*
G01X485236Y153681D02*
G03I-1575J0D01*
G01X492520Y137933D02*
G03X494488Y139902I-1J1969D01*
G01X472835D02*
G03X474803Y137933I1968J-1D01*
G01X479134Y161673D02*
X477953Y160492D01*
G01X476181Y158996D02*
X472835Y155650D01*
G01X486146Y156752D02*
X484843Y154783D01*
G01X480170Y148861D02*
X482480Y153091D01*
G01X494488Y139902D02*
Y155650D01*
G01X491142Y296988D02*
Y158996D01*
G01X490551Y299232D02*
Y156752D01*
G01X487598Y145413D02*
Y139311D01*
G01X487402Y158130D02*
Y149587D01*
G01X485827Y196949D02*
Y160492D01*
G01X484843Y154783D02*
Y153091D01*
G01X484646Y198130D02*
Y161673D01*
G01X482480Y153091D02*
Y154783D01*
G01X479921Y149587D02*
Y158130D01*
G01X479724Y145413D02*
Y139311D01*
G01X479134Y161673D02*
Y294311D01*
G01X477953Y160492D02*
Y295492D01*
G01X476181Y195787D02*
Y156752D01*
G01X472835Y155650D02*
Y139902D01*
G01X484646Y161673D02*
X479134D01*
G01X485827Y160492D02*
X477953D01*
G01X491142Y158996D02*
X476181D01*
G01X487402Y158130D02*
X490551D01*
G01X479921D02*
X476181D01*
G01Y156752D02*
X490551D01*
G01X484843Y154783D02*
X482480D01*
G01X484843Y153091D02*
X482480D01*
G01X486220Y148406D02*
X481102D01*
G01X494488Y148366D02*
X472835D01*
G01X487598Y145413D02*
X479724D01*
G01Y143839D02*
X487598D01*
G01X484843Y142461D02*
X482480D01*
G01Y140492D02*
X484843D01*
G01X487008Y138720D02*
X480315D01*
G01X492520Y137933D02*
X474803D01*
G01X484843Y153091D02*
X487153Y148861D01*
G01X482480Y154783D02*
X481177Y156752D01*
G01X491142Y158996D02*
X494488Y155650D01*
G01X484646Y161673D02*
X485827Y160492D01*
G01X474744Y197983D02*
Y197979D01*
G01X474746Y197976D02*
X474744Y197983D01*
G01X474757Y197961D02*
X474746Y197976D01*
G01X474781Y197953D02*
X474757Y197961D01*
G01X489141Y166173D02*
X489152Y166157D01*
G01X489117Y166181D02*
X489141Y166173D01*
G01Y171173D02*
X489152Y171157D01*
G01X489117Y171181D02*
X489141Y171173D01*
G01Y176173D02*
X489152Y176157D01*
G01X489117Y176181D02*
X489141Y176173D01*
G01Y181173D02*
X489152Y181157D01*
G01X489117Y181181D02*
X489141Y181173D01*
G01X489152Y186157D02*
X489154Y186152D01*
G01X489141Y186173D02*
X489152Y186157D01*
G01X489117Y186181D02*
X489141Y186173D01*
G01Y191173D02*
X489152Y191157D01*
G01X489117Y191181D02*
X489141Y191173D01*
G01Y196173D02*
X489152Y196157D01*
G01X489117Y196181D02*
X489141Y196173D01*
G01X474744Y207431D02*
Y207428D01*
G01X474745Y207426D02*
X474744Y207431D01*
G01X474756Y207411D02*
X474745Y207426D01*
G01X474779Y207402D02*
X474756Y207411D01*
G01X475697Y205432D02*
X475687Y205433D01*
G01X475706Y205429D02*
X475697Y205432D01*
G01X475713Y205424D02*
X475706Y205429D01*
G01X475697Y199133D02*
X475687Y199134D01*
G01X475706Y199130D02*
X475697Y199133D01*
G01X475713Y199124D02*
X475706Y199130D01*
G01X475697Y202282D02*
X475687Y202283D01*
G01X475706Y202279D02*
X475697Y202282D01*
G01X475713Y202274D02*
X475706Y202279D01*
G01X475697Y208581D02*
X475687Y208583D01*
G01X475706Y208578D02*
X475697Y208581D01*
G01X475713Y208573D02*
X475706Y208578D01*
G01X475697Y211731D02*
X475687Y211732D01*
G01X475706Y211728D02*
X475697Y211731D01*
G01X475713Y211723D02*
X475706Y211728D01*
G01X474783Y197948D02*
Y197942D01*
G01X474782Y197952D02*
X474783Y197948D01*
G01X474781Y197953D02*
X474782Y197952D01*
G01X474783Y201098D02*
Y201091D01*
G01X474782Y201101D02*
X474783Y201098D01*
G01X474781Y201102D02*
X474782Y201101D01*
G01X474783Y204247D02*
Y204241D01*
G01X474782Y204251D02*
X474783Y204247D01*
G01X474781Y204252D02*
X474782Y204251D01*
G01X474783Y207397D02*
Y207391D01*
G01X474782Y207400D02*
X474783Y207397D01*
G01X474781Y207402D02*
X474782Y207400D01*
G01X474783Y210546D02*
Y210540D01*
G01X474782Y210550D02*
X474783Y210546D01*
G01X474781Y210551D02*
X474782Y210550D01*
G01X489154Y166148D02*
Y166156D01*
G01X489155Y166144D02*
X489154Y166148D01*
G01X489156Y166142D02*
X489155Y166144D01*
G01X489154Y171148D02*
Y171156D01*
G01X489155Y171144D02*
X489154Y171148D01*
G01X489156Y171142D02*
X489155Y171144D01*
G01X489154Y176148D02*
Y176156D01*
G01X489155Y176144D02*
X489154Y176148D01*
G01X489156Y176142D02*
X489155Y176144D01*
G01X489154Y181148D02*
Y181156D01*
G01X489155Y181144D02*
X489154Y181148D01*
G01X489156Y181142D02*
X489155Y181144D01*
G01X489154Y186148D02*
Y186156D01*
G01X489155Y186144D02*
X489154Y186148D01*
G01X489156Y186142D02*
X489155Y186144D01*
G01X489154Y191148D02*
Y191156D01*
G01X489155Y191144D02*
X489154Y191148D01*
G01X489156Y191142D02*
X489155Y191144D01*
G01X489154Y196148D02*
Y196156D01*
G01X489155Y196144D02*
X489154Y196148D01*
G01X489156Y196142D02*
X489155Y196144D01*
G01X474767Y201105D02*
X474781Y201102D01*
G01X474756Y201112D02*
X474767Y201105D01*
G01X474743Y201131D02*
X474756Y201112D01*
G01X474767Y210554D02*
X474781Y210551D01*
G01X474755Y210561D02*
X474767Y210554D01*
G01X474743Y210580D02*
X474755Y210561D01*
G01X474767Y204255D02*
X474781Y204252D01*
G01X474754Y204263D02*
X474767Y204255D01*
G01X474743Y204283D02*
X474754Y204263D01*
G01X475728Y197986D02*
Y197979D01*
G01Y197991D02*
Y197986D01*
G01X475727Y197992D02*
X475728Y197991D01*
G01Y201136D02*
Y201128D01*
G01Y201141D02*
Y201136D01*
G01X475727Y201142D02*
X475728Y201141D01*
G01Y204285D02*
Y204278D01*
G01Y204290D02*
Y204285D01*
G01X475727Y204291D02*
X475728Y204290D01*
G01Y207435D02*
Y207428D01*
G01Y207440D02*
Y207435D01*
G01X475727Y207441D02*
X475728Y207440D01*
G01Y210585D02*
Y210577D01*
G01Y210589D02*
Y210585D01*
G01X475727Y210591D02*
X475728Y210589D01*
G01X474766Y197956D02*
X474781Y197953D01*
G01X474753Y197964D02*
X474766Y197956D01*
G01X474743Y197985D02*
X474753Y197964D01*
G01X475719Y199132D02*
X475723Y199127D01*
G01X475714Y199137D02*
X475719Y199132D01*
G01X475708Y199141D02*
X475714Y199137D01*
G01X475702Y199143D02*
X475708Y199141D01*
G01X475696Y199145D02*
X475702Y199143D01*
G01X475689Y199145D02*
X475696D01*
G01X475719Y202282D02*
X475723Y202277D01*
G01X475714Y202286D02*
X475719Y202282D01*
G01X475708Y202290D02*
X475714Y202286D01*
G01X475702Y202293D02*
X475708Y202290D01*
G01X475696Y202294D02*
X475702Y202293D01*
G01X475689Y202295D02*
X475696Y202294D01*
G01X474745Y197971D02*
X474744Y197979D01*
G01X474747Y197965D02*
X474745Y197971D01*
G01X474751Y197958D02*
X474747Y197965D01*
G01X474756Y197952D02*
X474751Y197958D01*
G01X474762Y197948D02*
X474756Y197952D01*
G01X474769Y197944D02*
X474762Y197948D01*
G01X474776Y197943D02*
X474769Y197944D01*
G01X474783Y197942D02*
X474776Y197943D01*
G01X474745Y201121D02*
X474744Y201128D01*
G01X474747Y201114D02*
X474745Y201121D01*
G01X474751Y201108D02*
X474747Y201114D01*
G01X474756Y201102D02*
X474751Y201108D01*
G01X474762Y201097D02*
X474756Y201102D01*
G01X474769Y201094D02*
X474762Y201097D01*
G01X474776Y201092D02*
X474769Y201094D01*
G01X474783Y201091D02*
X474776Y201092D01*
G01X474745Y204270D02*
X474744Y204278D01*
G01X474747Y204264D02*
X474745Y204270D01*
G01X474751Y204257D02*
X474747Y204264D01*
G01X474756Y204252D02*
X474751Y204257D01*
G01X474762Y204247D02*
X474756Y204252D01*
G01X474769Y204244D02*
X474762Y204247D01*
G01X474776Y204242D02*
X474769Y204244D01*
G01X474783Y204241D02*
X474776Y204242D01*
G01X474745Y207420D02*
X474744Y207428D01*
G01X474747Y207413D02*
X474745Y207420D01*
G01X474751Y207407D02*
X474747Y207413D01*
G01X474756Y207401D02*
X474751Y207407D01*
G01X474762Y207396D02*
X474756Y207401D01*
G01X474769Y207393D02*
X474762Y207396D01*
G01X474776Y207391D02*
X474769Y207393D01*
G01X474783Y207391D02*
X474776D01*
G01X475698Y199133D02*
X475707Y199128D01*
G01X475687Y199134D02*
X475698Y199133D01*
G01Y202282D02*
X475707Y202278D01*
G01X475687Y202283D02*
X475698Y202282D01*
G01Y205432D02*
X475707Y205428D01*
G01X475687Y205433D02*
X475698Y205432D01*
G01Y208581D02*
X475707Y208577D01*
G01X475687Y208583D02*
X475698Y208581D01*
G01Y211731D02*
X475707Y211727D01*
G01X475687Y211732D02*
X475698Y211731D01*
G01X474744Y201132D02*
Y201128D01*
G01X474746Y201126D02*
X474744Y201132D01*
G01X474757Y201111D02*
X474746Y201126D01*
G01X474782Y201102D02*
X474757Y201111D01*
G01X474744Y204282D02*
Y204278D01*
G01X474746Y204276D02*
X474744Y204282D01*
G01X474757Y204260D02*
X474746Y204276D01*
G01X474781Y204252D02*
X474757Y204260D01*
G01X474744Y210581D02*
Y210577D01*
G01X474746Y210575D02*
X474744Y210581D01*
G01X474757Y210559D02*
X474746Y210575D01*
G01X474781Y210551D02*
X474757Y210559D01*
G01X475728Y199115D02*
Y199108D01*
G01X475726Y199121D02*
X475728Y199115D01*
G01X475723Y199127D02*
X475726Y199121D01*
G01X475728Y202265D02*
Y202258D01*
G01X475726Y202271D02*
X475728Y202265D01*
G01X475723Y202277D02*
X475726Y202271D01*
G01X475728Y205414D02*
Y205407D01*
G01X475726Y205420D02*
X475728Y205414D01*
G01X475723Y205426D02*
X475726Y205420D01*
G01X475728Y208564D02*
Y208557D01*
G01X475726Y208570D02*
X475728Y208564D01*
G01X475723Y208576D02*
X475726Y208570D01*
G01X475728Y211713D02*
Y211707D01*
G01X475726Y211720D02*
X475728Y211713D01*
G01X475723Y211726D02*
X475726Y211720D01*
G01X475689Y197948D02*
X475690Y197942D01*
G01X475688Y197952D02*
X475689Y197948D01*
G01X475687Y197953D02*
X475688Y197952D01*
G01X475689Y201097D02*
X475690Y201091D01*
G01X475688Y201101D02*
X475689Y201097D01*
G01X475687Y201102D02*
X475688Y201101D01*
G01X475689Y204247D02*
X475690Y204241D01*
G01X475688Y204251D02*
X475689Y204247D01*
G01X475687Y204252D02*
X475688Y204251D01*
G01X475689Y207396D02*
X475690Y207391D01*
G01X475688Y207400D02*
X475689Y207396D01*
G01X475687Y207402D02*
X475688Y207400D01*
G01X475689Y210546D02*
X475690Y210540D01*
G01X475688Y210550D02*
X475689Y210546D01*
G01X475687Y210551D02*
X475688Y210550D01*
G01X488169Y166189D02*
Y166198D01*
G01X488170Y166183D02*
X488169Y166189D01*
G01X488171Y166181D02*
X488170Y166183D01*
G01X488169Y171189D02*
Y171198D01*
G01X488170Y171183D02*
X488169Y171189D01*
G01X488171Y171181D02*
X488170Y171183D01*
G01X488169Y176189D02*
Y176198D01*
G01X488170Y176183D02*
X488169Y176189D01*
G01X488171Y176181D02*
X488170Y176183D01*
G01X488169Y181189D02*
Y181198D01*
G01X488170Y181183D02*
X488169Y181189D01*
G01X488171Y181181D02*
X488170Y181183D01*
G01X488169Y186189D02*
Y186198D01*
G01X488170Y186183D02*
X488169Y186189D01*
G01X488171Y186181D02*
X488170Y186183D01*
G01X488169Y191189D02*
Y191198D01*
G01X488170Y191183D02*
X488169Y191189D01*
G01X488171Y191181D02*
X488170Y191183D01*
G01X488169Y196189D02*
Y196198D01*
G01X488170Y196183D02*
X488169Y196189D01*
G01X488171Y196181D02*
X488170Y196183D01*
G01X489146Y166325D02*
X489154Y166299D01*
G01X489136Y166352D02*
X489146Y166325D01*
G01X489124Y166378D02*
X489136Y166352D01*
G01X489146Y171325D02*
X489154Y171299D01*
G01X489136Y171352D02*
X489146Y171325D01*
G01X489124Y171378D02*
X489136Y171352D01*
G01X489146Y176325D02*
X489154Y176299D01*
G01X489136Y176352D02*
X489146Y176325D01*
G01X489124Y176378D02*
X489136Y176352D01*
G01X489146Y181325D02*
X489154Y181299D01*
G01X489136Y181352D02*
X489146Y181325D01*
G01X489124Y181378D02*
X489136Y181352D01*
G01X489146Y186325D02*
X489154Y186299D01*
G01X489136Y186352D02*
X489146Y186325D01*
G01X489124Y186378D02*
X489136Y186352D01*
G01X489146Y191325D02*
X489154Y191299D01*
G01X489136Y191352D02*
X489146Y191325D01*
G01X489124Y191378D02*
X489136Y191352D01*
G01X489146Y196325D02*
X489154Y196299D01*
G01X489136Y196352D02*
X489146Y196325D01*
G01X489124Y196378D02*
X489136Y196352D01*
G01X474762Y207407D02*
X474781Y207402D01*
G01X474748Y207419D02*
X474762Y207407D01*
G01X474742Y207437D02*
X474748Y207419D01*
G01X489136Y166176D02*
X489117Y166181D01*
G01X489151Y166162D02*
X489136Y166176D01*
G01X489156Y166142D02*
X489151Y166162D01*
G01X489136Y171176D02*
X489117Y171181D01*
G01X489151Y171162D02*
X489136Y171176D01*
G01X489156Y171142D02*
X489151Y171162D01*
G01X489136Y176176D02*
X489117Y176181D01*
G01X489151Y176162D02*
X489136Y176176D01*
G01X489156Y176142D02*
X489151Y176162D01*
G01X489136Y181176D02*
X489117Y181181D01*
G01X489151Y181162D02*
X489136Y181176D01*
G01X489156Y181142D02*
X489151Y181162D01*
G01X475706Y197945D02*
X475709Y197947D01*
G01X475703Y197944D02*
X475706Y197945D01*
G01X475700Y197943D02*
X475703Y197944D01*
G01X475696Y197942D02*
X475700Y197943D01*
G01X475693Y197942D02*
X475696D01*
G01X475689D02*
X475693D01*
G01X474767Y199142D02*
X474763Y199140D01*
G01X474770Y199143D02*
X474767Y199142D01*
G01X474773Y199144D02*
X474770Y199143D01*
G01X474776Y199144D02*
X474773D01*
G01X474780Y199145D02*
X474776Y199144D01*
G01X474783Y199145D02*
X474780D01*
G01X475706Y201095D02*
X475709Y201096D01*
G01X475703Y201094D02*
X475706Y201095D01*
G01X475700Y201093D02*
X475703Y201094D01*
G01X475696Y201092D02*
X475700Y201093D01*
G01X475693Y201091D02*
X475696Y201092D01*
G01X475689Y201091D02*
X475693D01*
G01X474767Y202291D02*
X474763Y202290D01*
G01X474770Y202293D02*
X474767Y202291D01*
G01X474773Y202294D02*
X474770Y202293D01*
G01X474776Y202294D02*
X474773D01*
G01X474780Y202295D02*
X474776Y202294D01*
G01X474783Y202295D02*
X474780D01*
G01X475706Y204244D02*
X475709Y204246D01*
G01X475703Y204243D02*
X475706Y204244D01*
G01X475700Y204242D02*
X475703Y204243D01*
G01X475696Y204241D02*
X475700Y204242D01*
G01X475693Y204241D02*
X475696D01*
G01X475689D02*
X475693D01*
G01X474767Y205441D02*
X474763Y205439D01*
G01X474770Y205442D02*
X474767Y205441D01*
G01X474773Y205443D02*
X474770Y205442D01*
G01X474776Y205444D02*
X474773Y205443D01*
G01X474780Y205444D02*
X474776D01*
G01X474783D02*
X474780D01*
G01X475706Y207394D02*
X475709Y207396D01*
G01X475703Y207393D02*
X475706Y207394D01*
G01X475700Y207392D02*
X475703Y207393D01*
G01X475696Y207391D02*
X475700Y207392D01*
G01X475693Y207391D02*
X475696D01*
G01X475689D02*
X475693D01*
G01X474767Y208591D02*
X474763Y208589D01*
G01X474770Y208592D02*
X474767Y208591D01*
G01X474773Y208593D02*
X474770Y208592D01*
G01X474776Y208593D02*
X474773D01*
G01X474780Y208594D02*
X474776Y208593D01*
G01X474783Y208594D02*
X474780D01*
G01X475706Y210544D02*
X475709Y210545D01*
G01X475703Y210543D02*
X475706Y210544D01*
G01X475700Y210541D02*
X475703Y210543D01*
G01X475696Y210541D02*
X475700D01*
G01X475693Y210540D02*
X475696Y210541D01*
G01X475689Y210540D02*
X475693D01*
G01X474767Y211740D02*
X474763Y211739D01*
G01X474770Y211741D02*
X474767Y211740D01*
G01X474773Y211743D02*
X474770Y211741D01*
G01X474776Y211743D02*
X474773D01*
G01X474780Y211744D02*
X474776Y211743D01*
G01X474783Y211744D02*
X474780D01*
G01X473997Y201142D02*
X473563D01*
G01X474370D02*
X473997D01*
G01Y207441D02*
X473563D01*
G01X474370D02*
X473997D01*
G01Y210591D02*
X473563D01*
G01X474370D02*
X473997D01*
G01X475719Y205431D02*
X475723Y205426D01*
G01X475714Y205436D02*
X475719Y205431D01*
G01X475708Y205440D02*
X475714Y205436D01*
G01X475702Y205442D02*
X475708Y205440D01*
G01X475696Y205444D02*
X475702Y205442D01*
G01X475689Y205444D02*
X475696D01*
G01X475719Y208581D02*
X475723Y208576D01*
G01X475714Y208585D02*
X475719Y208581D01*
G01X475708Y208589D02*
X475714Y208585D01*
G01X475702Y208592D02*
X475708Y208589D01*
G01X475696Y208594D02*
X475702Y208592D01*
G01X475689Y208594D02*
X475696D01*
G01X475719Y211731D02*
X475723Y211726D01*
G01X475714Y211735D02*
X475719Y211731D01*
G01X475708Y211739D02*
X475714Y211735D01*
G01X475702Y211741D02*
X475708Y211739D01*
G01X475696Y211743D02*
X475702Y211741D01*
G01X475689Y211744D02*
X475696Y211743D01*
G01X474745Y210570D02*
X474744Y210577D01*
G01X474747Y210563D02*
X474745Y210570D01*
G01X474751Y210557D02*
X474747Y210563D01*
G01X474756Y210551D02*
X474751Y210557D01*
G01X474762Y210546D02*
X474756Y210551D01*
G01X474769Y210543D02*
X474762Y210546D01*
G01X474776Y210541D02*
X474769Y210543D01*
G01X474783Y210540D02*
X474776Y210541D01*
G01X489136Y186176D02*
X489117Y186181D01*
G01X489151Y186162D02*
X489136Y186176D01*
G01X489156Y186142D02*
X489151Y186162D01*
G01X489136Y191176D02*
X489117Y191181D01*
G01X489151Y191162D02*
X489136Y191176D01*
G01X489156Y191142D02*
X489151Y191162D01*
G01X489136Y196176D02*
X489117Y196181D01*
G01X489151Y196162D02*
X489136Y196176D01*
G01X489156Y196142D02*
X489151Y196162D01*
G01X475721Y205415D02*
X475713Y205424D01*
G01X475725Y205405D02*
X475721Y205415D01*
G01X475727Y205394D02*
X475725Y205405D01*
G01X475721Y199116D02*
X475713Y199124D01*
G01X475726Y199106D02*
X475721Y199116D01*
G01X475727Y199094D02*
X475726Y199106D01*
G01X475721Y202265D02*
X475713Y202274D01*
G01X475726Y202255D02*
X475721Y202265D01*
G01X475727Y202244D02*
X475726Y202255D01*
G01X475721Y208565D02*
X475713Y208573D01*
G01X475726Y208554D02*
X475721Y208565D01*
G01X475727Y208543D02*
X475726Y208554D01*
G01X475721Y211714D02*
X475713Y211723D01*
G01X475726Y211704D02*
X475721Y211714D01*
G01X475727Y211693D02*
X475726Y211704D01*
G01X489120Y166279D02*
X489124Y166378D01*
G01X489115Y166207D02*
X489120Y166279D01*
G01X489117Y166181D02*
X489115Y166207D01*
G01X489120Y171279D02*
X489124Y171378D01*
G01X489115Y171207D02*
X489120Y171279D01*
G01X489117Y171181D02*
X489115Y171207D01*
G01X489120Y176279D02*
X489124Y176378D01*
G01X489115Y176207D02*
X489120Y176279D01*
G01X489117Y176181D02*
X489115Y176207D01*
G01X489120Y181279D02*
X489124Y181378D01*
G01X489115Y181207D02*
X489120Y181279D01*
G01X489117Y181181D02*
X489115Y181207D01*
G01X489120Y186279D02*
X489124Y186378D01*
G01X489115Y186207D02*
X489120Y186279D01*
G01X489117Y186181D02*
X489115Y186207D01*
G01X489120Y191279D02*
X489124Y191378D01*
G01X489115Y191207D02*
X489120Y191279D01*
G01X489117Y191181D02*
X489115Y191207D01*
G01X489120Y196279D02*
X489124Y196378D01*
G01X489115Y196207D02*
X489120Y196279D01*
G01X489117Y196181D02*
X489115Y196207D01*
G01X474744Y210585D02*
Y210577D01*
G01X474743Y210589D02*
X474744Y210585D01*
G01X474743Y210580D02*
Y210589D01*
G01X474784Y211917D02*
X474783Y211929D01*
G01X474781Y211904D02*
X474784Y211917D01*
G01X474781Y211890D02*
Y211904D01*
G01X474784Y208767D02*
X474783Y208780D01*
G01X474781Y208754D02*
X474784Y208767D01*
G01X474781Y208741D02*
Y208754D01*
G01X474784Y205618D02*
X474783Y205630D01*
G01X474781Y205605D02*
X474784Y205618D01*
G01X474781Y205591D02*
Y205605D01*
G01X474784Y202468D02*
X474783Y202480D01*
G01X474781Y202455D02*
X474784Y202468D01*
G01X474781Y202441D02*
Y202455D01*
G01X474784Y199319D02*
X474783Y199331D01*
G01X474781Y199306D02*
X474784Y199319D01*
G01X474781Y199292D02*
Y199306D01*
G01X488170Y194802D02*
X488171Y194803D01*
G01X488169Y194796D02*
X488170Y194802D01*
G01X488169Y194787D02*
Y194796D01*
G01X488170Y189802D02*
X488171Y189803D01*
G01X488169Y189796D02*
X488170Y189802D01*
G01X488169Y189787D02*
Y189796D01*
G01X488170Y184802D02*
X488171Y184803D01*
G01X488169Y184796D02*
X488170Y184802D01*
G01X488169Y184787D02*
Y184796D01*
G01X488170Y179802D02*
X488171Y179803D01*
G01X488169Y179796D02*
X488170Y179802D01*
G01X488169Y179787D02*
Y179796D01*
G01X488170Y174802D02*
X488171Y174803D01*
G01X488169Y174796D02*
X488170Y174802D01*
G01X488169Y174787D02*
Y174796D01*
G01X488170Y169802D02*
X488171Y169803D01*
G01X488169Y169796D02*
X488170Y169802D01*
G01X488169Y169787D02*
Y169796D01*
G01X488170Y164802D02*
X488171Y164803D01*
G01X488169Y164796D02*
X488170Y164802D01*
G01X488169Y164787D02*
Y164796D01*
G01X474781Y210380D02*
X474780Y210393D01*
G01X474784Y210367D02*
X474781Y210380D01*
G01X474783Y210354D02*
X474784Y210367D01*
G01X474781Y207230D02*
X474780Y207244D01*
G01X474784Y207217D02*
X474781Y207230D01*
G01X474783Y207205D02*
X474784Y207217D01*
G01X474781Y204081D02*
X474780Y204094D01*
G01X474784Y204068D02*
X474781Y204081D01*
G01X474783Y204055D02*
X474784Y204068D01*
G01X474781Y200931D02*
X474780Y200944D01*
G01X474784Y200918D02*
X474781Y200931D01*
G01X474783Y200906D02*
X474784Y200918D01*
G01X474781Y197781D02*
X474780Y197795D01*
G01X474784Y197769D02*
X474781Y197781D01*
G01X474783Y197756D02*
X474784Y197769D01*
G01X475691Y211904D02*
X475693Y211890D01*
G01X475688Y211917D02*
X475691Y211904D01*
G01X475689Y211929D02*
X475688Y211917D01*
G01X475691Y208754D02*
X475693Y208741D01*
G01X475688Y208767D02*
X475691Y208754D01*
G01X475689Y208780D02*
X475688Y208767D01*
G01X475691Y205604D02*
X475693Y205591D01*
G01X475688Y205617D02*
X475691Y205604D01*
G01X475689Y205630D02*
X475688Y205617D01*
G01X475691Y202455D02*
X475693Y202441D01*
G01X475688Y202468D02*
X475691Y202455D01*
G01X475689Y202480D02*
X475688Y202468D01*
G01X475691Y199305D02*
X475693Y199292D01*
G01X475688Y199318D02*
X475691Y199305D01*
G01X475689Y199331D02*
X475688Y199318D01*
G01X474744Y204285D02*
Y204278D01*
G01X474743Y204290D02*
X474744Y204285D01*
G01X474743Y204283D02*
Y204290D01*
G01X475688Y210367D02*
X475689Y210354D01*
G01X475691Y210380D02*
X475688Y210367D01*
G01X475692Y210393D02*
X475691Y210380D01*
G01X475688Y207217D02*
X475689Y207205D01*
G01X475691Y207230D02*
X475688Y207217D01*
G01X475692Y207244D02*
X475691Y207230D01*
G01X475688Y204068D02*
X475689Y204055D01*
G01X475691Y204081D02*
X475688Y204068D01*
G01X475692Y204094D02*
X475691Y204081D01*
G01X475688Y200918D02*
X475689Y200906D01*
G01X475691Y200931D02*
X475688Y200918D01*
G01X475692Y200944D02*
X475691Y200931D01*
G01X475688Y197769D02*
X475689Y197756D01*
G01X475691Y197781D02*
X475688Y197769D01*
G01X475692Y197795D02*
X475691Y197781D01*
G01X474744Y197987D02*
Y197979D01*
G01X474743Y197991D02*
X474744Y197987D01*
G01X474743Y197985D02*
Y197991D01*
G01X475722Y197972D02*
X475727Y197992D01*
G01X475707Y197958D02*
X475722Y197972D01*
G01X475687Y197953D02*
X475707Y197958D01*
G01X474747Y199114D02*
X474742Y199094D01*
G01X474761Y199129D02*
X474747Y199114D01*
G01X474781Y199134D02*
X474761Y199129D01*
G01X474747Y202264D02*
X474742Y202244D01*
G01X474761Y202278D02*
X474747Y202264D01*
G01X474781Y202283D02*
X474761Y202278D01*
G01X474747Y205413D02*
X474742Y205394D01*
G01X474761Y205428D02*
X474747Y205413D01*
G01X474781Y205433D02*
X474761Y205428D01*
G01X474747Y208563D02*
X474742Y208543D01*
G01X474761Y208578D02*
X474747Y208563D01*
G01X474781Y208583D02*
X474761Y208578D01*
G01X474747Y211713D02*
X474742Y211693D01*
G01X474761Y211727D02*
X474747Y211713D01*
G01X474781Y211732D02*
X474761Y211727D01*
G01X475722Y201122D02*
X475727Y201142D01*
G01X475707Y201108D02*
X475722Y201122D01*
G01X475687Y201102D02*
X475707Y201108D01*
G01X475722Y204272D02*
X475727Y204291D01*
G01X475707Y204257D02*
X475722Y204272D01*
G01X475687Y204252D02*
X475707Y204257D01*
G01X475722Y207421D02*
X475727Y207441D01*
G01X475707Y207407D02*
X475722Y207421D01*
G01X475687Y207402D02*
X475707Y207407D01*
G01X475722Y210571D02*
X475727Y210591D01*
G01X475707Y210557D02*
X475722Y210571D01*
G01X475687Y210551D02*
X475707Y210557D01*
G01X474757Y211724D02*
X474781Y211732D01*
G01X474746Y211709D02*
X474757Y211724D01*
G01X474744Y211703D02*
X474746Y211709D01*
G01X474757Y208574D02*
X474781Y208583D01*
G01X474746Y208560D02*
X474757Y208574D01*
G01X474744Y208553D02*
X474746Y208560D01*
G01X474757Y205425D02*
X474781Y205433D01*
G01X474746Y205410D02*
X474757Y205425D01*
G01X474744Y205404D02*
X474746Y205410D01*
G01X474757Y202275D02*
X474781Y202283D01*
G01X474746Y202261D02*
X474757Y202275D01*
G01X474744Y202254D02*
X474746Y202261D01*
G01X474757Y199126D02*
X474781Y199134D01*
G01X474746Y199111D02*
X474757Y199126D01*
G01X474744Y199104D02*
X474746Y199111D01*
G01X475728Y211699D02*
Y211706D01*
G01Y211695D02*
Y211699D01*
G01X475727Y211693D02*
X475728Y211695D01*
G01Y208550D02*
Y208557D01*
G01Y208545D02*
Y208550D01*
G01X475727Y208543D02*
X475728Y208545D01*
G01Y205400D02*
Y205407D01*
G01Y205396D02*
Y205400D01*
G01X475727Y205394D02*
X475728Y205396D01*
G01Y202250D02*
Y202257D01*
G01Y202246D02*
Y202250D01*
G01X475727Y202244D02*
X475728Y202246D01*
G01Y199101D02*
Y199108D01*
G01Y199096D02*
Y199101D01*
G01X475727Y199094D02*
X475728Y199096D01*
G01X474744Y207435D02*
Y207428D01*
G01X474743Y207440D02*
X474744Y207435D01*
G01X474742Y207437D02*
X474743Y207440D01*
G01X474744Y201136D02*
Y201128D01*
G01X474743Y201141D02*
X474744Y201136D01*
G01X474742Y201138D02*
X474743Y201141D01*
G01X475689Y211737D02*
Y211744D01*
G01X475688Y211734D02*
X475689Y211737D01*
G01X475687Y211732D02*
X475688Y211734D01*
G01X475689Y208588D02*
Y208594D01*
G01X475688Y208584D02*
X475689Y208588D01*
G01X475687Y208583D02*
X475688Y208584D01*
G01X475689Y205438D02*
Y205444D01*
G01X475688Y205435D02*
X475689Y205438D01*
G01X475687Y205433D02*
X475688Y205435D01*
G01X475689Y202289D02*
Y202295D01*
G01X475688Y202285D02*
X475689Y202289D01*
G01X475687Y202283D02*
X475688Y202285D01*
G01X475689Y199139D02*
Y199145D01*
G01X475688Y199135D02*
X475689Y199139D01*
G01X475687Y199134D02*
X475688Y199135D01*
G01X489154Y194796D02*
Y194787D01*
G01X489155Y194802D02*
X489154Y194796D01*
G01X489156Y194803D02*
X489155Y194802D01*
G01X489154Y189796D02*
Y189787D01*
G01X489155Y189802D02*
X489154Y189796D01*
G01X489156Y189803D02*
X489155Y189802D01*
G01X489154Y184796D02*
Y184787D01*
G01X489155Y184802D02*
X489154Y184796D01*
G01X489156Y184803D02*
X489155Y184802D01*
G01X489154Y179796D02*
Y179787D01*
G01X489155Y179802D02*
X489154Y179796D01*
G01X489156Y179803D02*
X489155Y179802D01*
G01X489154Y174796D02*
Y174787D01*
G01X489155Y174802D02*
X489154Y174796D01*
G01X489156Y174803D02*
X489155Y174802D01*
G01X489154Y169796D02*
Y169787D01*
G01X489155Y169802D02*
X489154Y169796D01*
G01X489156Y169803D02*
X489155Y169802D01*
G01X489154Y164796D02*
Y164787D01*
G01X489155Y164802D02*
X489154Y164796D01*
G01X489156Y164803D02*
X489155Y164802D01*
G01X474744Y211699D02*
Y211707D01*
G01X474743Y211694D02*
X474744Y211699D01*
G01X474742Y211693D02*
X474743Y211694D01*
G01X474744Y208550D02*
Y208557D01*
G01X474743Y208545D02*
X474744Y208550D01*
G01X474742Y208543D02*
X474743Y208545D01*
G01X474744Y205400D02*
Y205407D01*
G01X474743Y205395D02*
X474744Y205400D01*
G01X474742Y205394D02*
X474743Y205395D01*
G01X474744Y202250D02*
Y202258D01*
G01X474743Y202246D02*
X474744Y202250D01*
G01X474742Y202244D02*
X474743Y202246D01*
G01X474744Y199101D02*
Y199108D01*
G01X474743Y199096D02*
X474744Y199101D01*
G01X474742Y199094D02*
X474743Y199096D01*
G01X475726Y210565D02*
X475728Y210577D01*
G01X475719Y210554D02*
X475726Y210565D01*
G01X475709Y210545D02*
X475719Y210554D01*
G01X475726Y207415D02*
X475728Y207428D01*
G01X475719Y207404D02*
X475726Y207415D01*
G01X475709Y207396D02*
X475719Y207404D01*
G01X475726Y204265D02*
X475728Y204278D01*
G01X475719Y204254D02*
X475726Y204265D01*
G01X475709Y204246D02*
X475719Y204254D01*
G01X475726Y201116D02*
X475728Y201128D01*
G01X475719Y201105D02*
X475726Y201116D01*
G01X475709Y201096D02*
X475719Y201105D01*
G01X475726Y197966D02*
X475728Y197979D01*
G01X475719Y197955D02*
X475726Y197966D01*
G01X475709Y197947D02*
X475719Y197955D01*
G01X474783Y211737D02*
Y211744D01*
G01Y211733D02*
Y211737D01*
G01X474781Y211732D02*
X474783Y211733D01*
G01Y208588D02*
Y208594D01*
G01Y208584D02*
Y208588D01*
G01X474781Y208583D02*
X474783Y208584D01*
G01Y205438D02*
Y205444D01*
G01Y205434D02*
Y205438D01*
G01X474781Y205433D02*
X474783Y205434D01*
G01Y202289D02*
Y202295D01*
G01Y202285D02*
Y202289D01*
G01X474781Y202283D02*
X474783Y202285D01*
G01Y199139D02*
Y199145D01*
G01Y199135D02*
Y199139D01*
G01X474781Y199134D02*
X474783Y199135D01*
G01X474745Y211713D02*
X474744Y211707D01*
G01X474746Y211719D02*
X474745Y211713D01*
G01X474749Y211725D02*
X474746Y211719D01*
G01X474753Y211730D02*
X474749Y211725D01*
G01X474758Y211735D02*
X474753Y211730D01*
G01X474763Y211739D02*
X474758Y211735D01*
G01X474745Y208563D02*
X474744Y208557D01*
G01X474746Y208570D02*
X474745Y208563D01*
G01X474749Y208575D02*
X474746Y208570D01*
G01X474753Y208581D02*
X474749Y208575D01*
G01X474758Y208585D02*
X474753Y208581D01*
G01X474763Y208589D02*
X474758Y208585D01*
G01X474745Y205414D02*
X474744Y205407D01*
G01X474746Y205420D02*
X474745Y205414D01*
G01X474749Y205426D02*
X474746Y205420D01*
G01X474753Y205431D02*
X474749Y205426D01*
G01X474758Y205435D02*
X474753Y205431D01*
G01X474763Y205439D02*
X474758Y205435D01*
G01X474745Y202264D02*
X474744Y202258D01*
G01X474746Y202270D02*
X474745Y202264D01*
G01X474749Y202276D02*
X474746Y202270D01*
G01X474753Y202281D02*
X474749Y202276D01*
G01X474758Y202286D02*
X474753Y202281D01*
G01X474763Y202290D02*
X474758Y202286D01*
G01X474745Y199115D02*
X474744Y199108D01*
G01X474746Y199121D02*
X474745Y199115D01*
G01X474749Y199126D02*
X474746Y199121D01*
G01X474753Y199132D02*
X474749Y199126D01*
G01X474758Y199136D02*
X474753Y199132D01*
G01X474763Y199140D02*
X474758Y199136D01*
G01X475700Y210553D02*
X475687Y210551D01*
G01X475710Y210558D02*
X475700Y210553D01*
G01Y207404D02*
X475687Y207402D01*
G01X475710Y207409D02*
X475700Y207404D01*
G01Y204254D02*
X475687Y204252D01*
G01X475710Y204259D02*
X475700Y204254D01*
G01Y201104D02*
X475687Y201102D01*
G01X475710Y201109D02*
X475700Y201104D01*
G01Y197955D02*
X475687Y197953D01*
G01X475710Y197960D02*
X475700Y197955D01*
G01X475728Y199097D02*
Y199108D01*
G01Y202246D02*
Y202257D01*
G01Y205396D02*
Y205407D01*
G01Y208546D02*
Y208557D01*
G01Y211695D02*
Y211706D01*
G01X489154Y166155D02*
Y166164D01*
G01Y171155D02*
Y171164D01*
G01Y176155D02*
Y176164D01*
G01Y181155D02*
Y181164D01*
G01Y186155D02*
Y186164D01*
G01Y191155D02*
Y191164D01*
G01Y196155D02*
Y196164D01*
G01X493504Y194803D02*
Y196181D01*
G01Y189803D02*
Y191181D01*
G01Y184803D02*
Y186181D01*
G01Y179803D02*
Y181181D01*
G01Y174803D02*
Y176181D01*
G01Y169803D02*
Y171181D01*
G01Y164803D02*
Y166181D01*
G01X490335D02*
Y164803D01*
G01Y171181D02*
Y169803D01*
G01Y176181D02*
Y174803D01*
G01Y181181D02*
Y179803D01*
G01Y186181D02*
Y184803D01*
G01Y191181D02*
Y189803D01*
G01Y196181D02*
Y194803D01*
G01X489764Y219035D02*
Y196949D01*
G01X489154Y166156D02*
Y166299D01*
G01Y171156D02*
Y171299D01*
G01Y176156D02*
Y176299D01*
G01Y181156D02*
Y181299D01*
G01Y186156D02*
Y186299D01*
G01Y191156D02*
Y191299D01*
G01Y196156D02*
Y196299D01*
G01Y194311D02*
Y196673D01*
G01Y189311D02*
Y191673D01*
G01Y184311D02*
Y186673D01*
G01Y179311D02*
Y181673D01*
G01Y174311D02*
Y176673D01*
G01Y169311D02*
Y171673D01*
G01Y164311D02*
Y166673D01*
G01X488583Y217854D02*
Y198130D01*
G01X488169Y166673D02*
Y164311D01*
G01Y171673D02*
Y169311D01*
G01Y176673D02*
Y174311D01*
G01Y181673D02*
Y179311D01*
G01Y186673D02*
Y184311D01*
G01Y191673D02*
Y189311D01*
G01Y196673D02*
Y194311D01*
G01X475728Y210394D02*
Y211890D01*
G01Y207244D02*
Y208740D01*
G01Y204094D02*
Y205591D01*
G01Y200945D02*
Y202441D01*
G01Y197795D02*
Y199291D01*
G01X475689Y197942D02*
Y197795D01*
G01Y201091D02*
Y200944D01*
G01Y202441D02*
Y202295D01*
G01Y199292D02*
Y199145D01*
G01Y207391D02*
Y207244D01*
G01Y204241D02*
Y204094D01*
G01Y205591D02*
Y205444D01*
G01Y210540D02*
Y210393D01*
G01Y211890D02*
Y211744D01*
G01Y208741D02*
Y208594D01*
G01X474783Y210393D02*
Y210540D01*
G01Y211744D02*
Y211891D01*
G01Y208594D02*
Y208741D01*
G01Y207243D02*
Y207391D01*
G01Y204094D02*
Y204241D01*
G01Y205444D02*
Y205591D01*
G01Y200944D02*
Y201091D01*
G01Y202295D02*
Y202442D01*
G01Y199145D02*
Y199292D01*
G01Y197794D02*
Y197942D01*
G01X474744Y202441D02*
Y200945D01*
G01Y199291D02*
Y197795D01*
G01Y205591D02*
Y204094D01*
G01Y211890D02*
Y210394D01*
G01Y208740D02*
Y207244D01*
G01X473563Y199134D02*
Y197953D01*
G01Y202283D02*
Y201102D01*
G01Y208583D02*
Y207402D01*
G01Y205433D02*
Y204252D01*
G01Y211732D02*
Y210551D01*
G01X473228Y220197D02*
Y195787D01*
G01X472835D02*
Y220197D01*
G01X469803Y210551D02*
Y211732D01*
G01Y207402D02*
Y208583D01*
G01Y204252D02*
Y205433D01*
G01Y201102D02*
Y202283D01*
G01Y197953D02*
Y199134D01*
G01X475728Y210577D02*
Y210588D01*
G01Y207428D02*
Y207439D01*
G01Y204278D02*
Y204289D01*
G01Y201128D02*
Y201139D01*
G01Y197979D02*
Y197990D01*
G01X474742Y207437D02*
X474631Y207441D01*
G01X474742Y201138D02*
X474631Y201142D01*
G01X474742Y210587D02*
X474631Y210591D01*
G01X475689Y211929D02*
X474783D01*
G01X475728Y211890D02*
X474744D01*
G01X475687Y211732D02*
X469803D01*
G01Y211693D02*
X475727D01*
G01Y210591D02*
X469803D01*
G01X475687Y210551D02*
X469803D01*
G01X474744Y210394D02*
X475728D01*
G01X474783Y210354D02*
X475689D01*
G01Y208780D02*
X474783D01*
G01X475728Y208740D02*
X474744D01*
G01X475687Y208583D02*
X469803D01*
G01Y208543D02*
X475727D01*
G01Y207441D02*
X469803D01*
G01X475687Y207402D02*
X469803D01*
G01X474744Y207244D02*
X475728D01*
G01X474783Y207205D02*
X475689D01*
G01Y205630D02*
X474783D01*
G01X475728Y205591D02*
X474744D01*
G01X475687Y205433D02*
X469803D01*
G01Y205394D02*
X475727D01*
G01Y204291D02*
X469803D01*
G01X475687Y204252D02*
X469803D01*
G01X474744Y204094D02*
X475728D01*
G01X474783Y204055D02*
X475689D01*
G01Y202480D02*
X474783D01*
G01X475728Y202441D02*
X474744D01*
G01X475687Y202283D02*
X469803D01*
G01Y202244D02*
X475727D01*
G01Y201142D02*
X469803D01*
G01X475687Y201102D02*
X469803D01*
G01X474744Y200945D02*
X475728D01*
G01X474783Y200906D02*
X475689D01*
G01Y199331D02*
X474783D01*
G01X475728Y199291D02*
X474744D01*
G01X475687Y199134D02*
X469803D01*
G01Y199094D02*
X475727D01*
G01X488583Y198130D02*
X484646D01*
G01X475727Y197992D02*
X469803D01*
G01X475687Y197953D02*
X469803D01*
G01X474744Y197795D02*
X475728D01*
G01X474783Y197756D02*
X475689D01*
G01X489764Y196949D02*
X485827D01*
G01X489154Y196673D02*
X488169D01*
G01X488171Y196181D02*
X493504D01*
G01Y196142D02*
X489156D01*
G01X476181Y195787D02*
X472835D01*
G01X493504Y194803D02*
X488171D01*
G01X488169Y194311D02*
X489154D01*
G01Y191673D02*
X488169D01*
G01X488171Y191181D02*
X493504D01*
G01Y191142D02*
X489156D01*
G01X493504Y189803D02*
X488171D01*
G01X488169Y189311D02*
X489154D01*
G01Y186673D02*
X488169D01*
G01X488171Y186181D02*
X493504D01*
G01Y186142D02*
X489156D01*
G01X493504Y184803D02*
X488171D01*
G01X488169Y184311D02*
X489154D01*
G01Y181673D02*
X488169D01*
G01X488171Y181181D02*
X493504D01*
G01Y181142D02*
X489156D01*
G01X493504Y179803D02*
X488171D01*
G01X488169Y179311D02*
X489154D01*
G01Y176673D02*
X488169D01*
G01X488171Y176181D02*
X493504D01*
G01Y176142D02*
X489156D01*
G01X493504Y174803D02*
X488171D01*
G01X488169Y174311D02*
X489154D01*
G01Y171673D02*
X488169D01*
G01X488171Y171181D02*
X493504D01*
G01Y171142D02*
X489156D01*
G01X493504Y169803D02*
X488171D01*
G01X488169Y169311D02*
X489154D01*
G01X488169Y196377D02*
X489124Y196378D01*
G01X489154Y194607D02*
X488169Y194606D01*
G01Y191377D02*
X489124Y191378D01*
G01X489154Y189607D02*
X488169Y189606D01*
G01Y186377D02*
X489124Y186378D01*
G01X489154Y184607D02*
X488169Y184606D01*
G01Y181377D02*
X489124Y181378D01*
G01X489154Y179607D02*
X488169Y179606D01*
G01Y176377D02*
X489124Y176378D01*
G01X489154Y174607D02*
X488169Y174606D01*
G01Y171377D02*
X489124Y171378D01*
G01X489154Y169607D02*
X488169Y169606D01*
G01Y166377D02*
X489124Y166378D01*
G01X489154Y166673D02*
X488169D01*
G01X488171Y166181D02*
X493504D01*
G01Y166142D02*
X489156D01*
G01X493504Y164803D02*
X488171D01*
G01X488169Y164311D02*
X489154D01*
G01Y164607D02*
X488169Y164606D01*
G01X488583Y198130D02*
X489764Y196949D01*
G01X484646Y198130D02*
X485827Y196949D01*
G01X475697Y214881D02*
X475687Y214882D01*
G01X475706Y214878D02*
X475697Y214881D01*
G01X475713Y214872D02*
X475706Y214878D01*
G01X475697Y218030D02*
X475687Y218031D01*
G01X475706Y218027D02*
X475697Y218030D01*
G01X475713Y218022D02*
X475706Y218027D01*
G01X474783Y213696D02*
Y213690D01*
G01X474782Y213700D02*
X474783Y213696D01*
G01X474781Y213701D02*
X474782Y213700D01*
G01X474783Y216846D02*
Y216839D01*
G01X474782Y216849D02*
X474783Y216846D01*
G01X474781Y216850D02*
X474782Y216849D01*
G01X489154Y221148D02*
Y221156D01*
G01X489155Y221144D02*
X489154Y221148D01*
G01X489156Y221142D02*
X489155Y221144D01*
G01X489154Y226148D02*
Y226156D01*
G01X489155Y226144D02*
X489154Y226148D01*
G01X489156Y226142D02*
X489155Y226144D01*
G01X489154Y231148D02*
Y231156D01*
G01X489155Y231144D02*
X489154Y231148D01*
G01X489156Y231142D02*
X489155Y231144D01*
G01X489154Y236148D02*
Y236156D01*
G01X489155Y236144D02*
X489154Y236148D01*
G01X489156Y236142D02*
X489155Y236144D01*
G01X489154Y241148D02*
Y241156D01*
G01X489155Y241144D02*
X489154Y241148D01*
G01X489156Y241142D02*
X489155Y241144D01*
G01X489154Y246148D02*
Y246156D01*
G01X489155Y246144D02*
X489154Y246148D01*
G01X489156Y246142D02*
X489155Y246144D01*
G01X474767Y213704D02*
X474781Y213701D01*
G01X474754Y213711D02*
X474767Y213704D01*
G01X474743Y213731D02*
X474754Y213711D01*
G01X475728Y213734D02*
Y213727D01*
G01Y213739D02*
Y213734D01*
G01X475727Y213740D02*
X475728Y213739D01*
G01Y216884D02*
Y216876D01*
G01Y216889D02*
Y216884D01*
G01X475727Y216890D02*
X475728Y216889D01*
G01X474767Y216853D02*
X474781Y216850D01*
G01X474754Y216861D02*
X474767Y216853D01*
G01X474743Y216881D02*
X474754Y216861D01*
G01X475698Y214881D02*
X475707Y214876D01*
G01X475687Y214882D02*
X475698Y214881D01*
G01Y218030D02*
X475707Y218026D01*
G01X475687Y218031D02*
X475698Y218030D01*
G01X474744Y213731D02*
Y213727D01*
G01X474746Y213724D02*
X474744Y213731D01*
G01X474757Y213709D02*
X474746Y213724D01*
G01X474781Y213701D02*
X474757Y213709D01*
G01X474744Y216880D02*
Y216876D01*
G01X474746Y216874D02*
X474744Y216880D01*
G01X474757Y216859D02*
X474746Y216874D01*
G01X474781Y216850D02*
X474757Y216859D01*
G01X489141Y221173D02*
X489152Y221157D01*
G01X489117Y221181D02*
X489141Y221173D01*
G01Y226173D02*
X489152Y226157D01*
G01X489117Y226181D02*
X489141Y226173D01*
G01Y231173D02*
X489152Y231157D01*
G01X489117Y231181D02*
X489141Y231173D01*
G01Y236173D02*
X489152Y236157D01*
G01X489117Y236181D02*
X489141Y236173D01*
G01Y241173D02*
X489152Y241157D01*
G01X489117Y241181D02*
X489141Y241173D01*
G01Y246173D02*
X489152Y246157D01*
G01X489117Y246181D02*
X489141Y246173D01*
G01Y251173D02*
X489152Y251157D01*
G01X489117Y251181D02*
X489141Y251173D01*
G01Y256173D02*
X489152Y256157D01*
G01X489117Y256181D02*
X489141Y256173D01*
G01X489154Y251148D02*
Y251156D01*
G01X489155Y251144D02*
X489154Y251148D01*
G01X489156Y251142D02*
X489155Y251144D01*
G01X489154Y256148D02*
Y256156D01*
G01X489155Y256144D02*
X489154Y256148D01*
G01X489156Y256142D02*
X489155Y256144D01*
G01X475728Y214863D02*
Y214856D01*
G01X475726Y214869D02*
X475728Y214863D01*
G01X475723Y214875D02*
X475726Y214869D01*
G01X475728Y218013D02*
Y218006D01*
G01X475726Y218019D02*
X475728Y218013D01*
G01X475723Y218025D02*
X475726Y218019D01*
G01X475689Y216845D02*
X475690Y216839D01*
G01X475688Y216849D02*
X475689Y216845D01*
G01X475687Y216850D02*
X475688Y216849D01*
G01X488169Y221189D02*
Y221198D01*
G01X488170Y221183D02*
X488169Y221189D01*
G01X488171Y221181D02*
X488170Y221183D01*
G01X488169Y226189D02*
Y226198D01*
G01X488170Y226183D02*
X488169Y226189D01*
G01X488171Y226181D02*
X488170Y226183D01*
G01X488169Y231189D02*
Y231198D01*
G01X488170Y231183D02*
X488169Y231189D01*
G01X488171Y231181D02*
X488170Y231183D01*
G01X488169Y236189D02*
Y236198D01*
G01X488170Y236183D02*
X488169Y236189D01*
G01X488171Y236181D02*
X488170Y236183D01*
G01X488169Y241189D02*
Y241198D01*
G01X488170Y241183D02*
X488169Y241189D01*
G01X488171Y241181D02*
X488170Y241183D01*
G01X488169Y246189D02*
Y246198D01*
G01X488170Y246183D02*
X488169Y246189D01*
G01X488171Y246181D02*
X488170Y246183D01*
G01X488169Y251189D02*
Y251198D01*
G01X488170Y251183D02*
X488169Y251189D01*
G01X488171Y251181D02*
X488170Y251183D01*
G01X488169Y256189D02*
Y256198D01*
G01X488170Y256183D02*
X488169Y256189D01*
G01X488171Y256181D02*
X488170Y256183D01*
G01X489146Y221325D02*
X489154Y221299D01*
G01X489136Y221352D02*
X489146Y221325D01*
G01X489124Y221378D02*
X489136Y221352D01*
G01X489146Y226325D02*
X489154Y226299D01*
G01X489136Y226352D02*
X489146Y226325D01*
G01X489124Y226378D02*
X489136Y226352D01*
G01X489146Y231325D02*
X489154Y231299D01*
G01X489136Y231352D02*
X489146Y231325D01*
G01X489124Y231378D02*
X489136Y231352D01*
G01X489146Y236325D02*
X489154Y236299D01*
G01X489136Y236352D02*
X489146Y236325D01*
G01X489124Y236378D02*
X489136Y236352D01*
G01X489146Y241325D02*
X489154Y241299D01*
G01X489136Y241352D02*
X489146Y241325D01*
G01X489124Y241378D02*
X489136Y241352D01*
G01X489146Y246325D02*
X489154Y246299D01*
G01X489136Y246352D02*
X489146Y246325D01*
G01X489124Y246378D02*
X489136Y246352D01*
G01X489146Y251325D02*
X489154Y251299D01*
G01X489136Y251352D02*
X489146Y251325D01*
G01X489124Y251378D02*
X489136Y251352D01*
G01X489146Y256325D02*
X489154Y256299D01*
G01X489136Y256352D02*
X489146Y256325D01*
G01X489124Y256378D02*
X489136Y256352D01*
G01X474767Y214890D02*
X474763Y214888D01*
G01X474770Y214891D02*
X474767Y214890D01*
G01X474773Y214892D02*
X474770Y214891D01*
G01X474776Y214893D02*
X474773Y214892D01*
G01X474780Y214893D02*
X474776D01*
G01X474783D02*
X474780D01*
G01X475706Y216843D02*
X475709Y216844D01*
G01X475703Y216842D02*
X475706Y216843D01*
G01X475700Y216841D02*
X475703Y216842D01*
G01X475696Y216840D02*
X475700Y216841D01*
G01X475693Y216839D02*
X475696Y216840D01*
G01X475689Y216839D02*
X475693D01*
G01X474767Y218039D02*
X474763Y218038D01*
G01X474770Y218041D02*
X474767Y218039D01*
G01X474773Y218042D02*
X474770Y218041D01*
G01X474776Y218042D02*
X474773D01*
G01X474780Y218043D02*
X474776Y218042D01*
G01X474783Y218043D02*
X474780D01*
G01X475719Y214880D02*
X475723Y214875D01*
G01X475714Y214885D02*
X475719Y214880D01*
G01X475708Y214889D02*
X475714Y214885D01*
G01X475702Y214891D02*
X475708Y214889D01*
G01X475696Y214893D02*
X475702Y214891D01*
G01X475689Y214893D02*
X475696D01*
G01X475719Y218030D02*
X475723Y218025D01*
G01X475714Y218034D02*
X475719Y218030D01*
G01X475708Y218038D02*
X475714Y218034D01*
G01X475702Y218041D02*
X475708Y218038D01*
G01X475696Y218043D02*
X475702Y218041D01*
G01X475689Y218043D02*
X475696D01*
G01X474745Y213719D02*
X474744Y213727D01*
G01X474747Y213713D02*
X474745Y213719D01*
G01X474751Y213706D02*
X474747Y213713D01*
G01X474756Y213700D02*
X474751Y213706D01*
G01X474762Y213696D02*
X474756Y213700D01*
G01X474769Y213693D02*
X474762Y213696D01*
G01X474776Y213691D02*
X474769Y213693D01*
G01X474783Y213690D02*
X474776Y213691D01*
G01X474745Y216869D02*
X474744Y216876D01*
G01X474747Y216862D02*
X474745Y216869D01*
G01X474751Y216856D02*
X474747Y216862D01*
G01X474756Y216850D02*
X474751Y216856D01*
G01X474762Y216845D02*
X474756Y216850D01*
G01X474769Y216842D02*
X474762Y216845D01*
G01X474776Y216840D02*
X474769Y216842D01*
G01X474783Y216839D02*
X474776Y216840D01*
G01X489136Y221176D02*
X489117Y221181D01*
G01X489151Y221162D02*
X489136Y221176D01*
G01X489156Y221142D02*
X489151Y221162D01*
G01X489136Y226176D02*
X489117Y226181D01*
G01X489151Y226162D02*
X489136Y226176D01*
G01X489156Y226142D02*
X489151Y226162D01*
G01X489136Y231176D02*
X489117Y231181D01*
G01X489151Y231162D02*
X489136Y231176D01*
G01X489156Y231142D02*
X489151Y231162D01*
G01X489136Y236176D02*
X489117Y236181D01*
G01X489151Y236162D02*
X489136Y236176D01*
G01X489156Y236142D02*
X489151Y236162D01*
G01X489136Y241176D02*
X489117Y241181D01*
G01X489151Y241162D02*
X489136Y241176D01*
G01X489156Y241142D02*
X489151Y241162D01*
G01X489136Y246176D02*
X489117Y246181D01*
G01X489151Y246162D02*
X489136Y246176D01*
G01X489156Y246142D02*
X489151Y246162D01*
G01X489136Y251176D02*
X489117Y251181D01*
G01X489151Y251162D02*
X489136Y251176D01*
G01X489156Y251142D02*
X489151Y251162D01*
G01X489136Y256176D02*
X489117Y256181D01*
G01X489151Y256162D02*
X489136Y256176D01*
G01X489156Y256142D02*
X489151Y256162D01*
G01X475721Y214864D02*
X475713Y214872D01*
G01X475726Y214854D02*
X475721Y214864D01*
G01X475727Y214843D02*
X475726Y214854D01*
G01X475721Y218013D02*
X475713Y218022D01*
G01X475726Y218003D02*
X475721Y218013D01*
G01X475727Y217992D02*
X475726Y218003D01*
G01X489120Y221279D02*
X489124Y221378D01*
G01X489115Y221207D02*
X489120Y221279D01*
G01X489117Y221181D02*
X489115Y221207D01*
G01X489120Y226279D02*
X489124Y226378D01*
G01X489115Y226207D02*
X489120Y226279D01*
G01X489117Y226181D02*
X489115Y226207D01*
G01X489120Y231279D02*
X489124Y231378D01*
G01X489115Y231207D02*
X489120Y231279D01*
G01X489117Y231181D02*
X489115Y231207D01*
G01X489120Y236279D02*
X489124Y236378D01*
G01X489115Y236207D02*
X489120Y236279D01*
G01X489117Y236181D02*
X489115Y236207D01*
G01X489120Y241279D02*
X489124Y241378D01*
G01X489115Y241207D02*
X489120Y241279D01*
G01X489117Y241181D02*
X489115Y241207D01*
G01X489120Y246279D02*
X489124Y246378D01*
G01X489115Y246207D02*
X489120Y246279D01*
G01X489117Y246181D02*
X489115Y246207D01*
G01X489120Y251279D02*
X489124Y251378D01*
G01X489115Y251207D02*
X489120Y251279D01*
G01X489117Y251181D02*
X489115Y251207D01*
G01X489120Y256279D02*
X489124Y256378D01*
G01X489115Y256207D02*
X489120Y256279D01*
G01X489117Y256181D02*
X489115Y256207D01*
G01X474784Y218216D02*
X474783Y218228D01*
G01X474781Y218203D02*
X474784Y218216D01*
G01X474781Y218189D02*
Y218203D01*
G01X474784Y215067D02*
X474783Y215079D01*
G01X474781Y215054D02*
X474784Y215067D01*
G01X474781Y215040D02*
Y215054D01*
G01X488170Y259802D02*
X488171Y259803D01*
G01X488169Y259796D02*
X488170Y259802D01*
G01X488169Y259787D02*
Y259796D01*
G01X488170Y254802D02*
X488171Y254803D01*
G01X488169Y254796D02*
X488170Y254802D01*
G01X488169Y254787D02*
Y254796D01*
G01X488170Y249802D02*
X488171Y249803D01*
G01X488169Y249796D02*
X488170Y249802D01*
G01X488169Y249787D02*
Y249796D01*
G01X488170Y244802D02*
X488171Y244803D01*
G01X488169Y244796D02*
X488170Y244802D01*
G01X488169Y244787D02*
Y244796D01*
G01X488170Y239802D02*
X488171Y239803D01*
G01X488169Y239796D02*
X488170Y239802D01*
G01X488169Y239787D02*
Y239796D01*
G01X488170Y234802D02*
X488171Y234803D01*
G01X488169Y234796D02*
X488170Y234802D01*
G01X488169Y234787D02*
Y234796D01*
G01X488170Y229802D02*
X488171Y229803D01*
G01X488169Y229796D02*
X488170Y229802D01*
G01X488169Y229787D02*
Y229796D01*
G01X488170Y224802D02*
X488171Y224803D01*
G01X488169Y224796D02*
X488170Y224802D01*
G01X488169Y224787D02*
Y224796D01*
G01X488170Y219802D02*
X488171Y219803D01*
G01X488169Y219796D02*
X488170Y219802D01*
G01X488169Y219787D02*
Y219796D01*
G01X474744Y216884D02*
Y216876D01*
G01X474743Y216889D02*
X474744Y216884D01*
G01X474743Y216881D02*
Y216889D01*
G01X474781Y216679D02*
X474780Y216693D01*
G01X474784Y216666D02*
X474781Y216679D01*
G01X474783Y216654D02*
X474784Y216666D01*
G01X474781Y213530D02*
X474780Y213543D01*
G01X474784Y213517D02*
X474781Y213530D01*
G01X474783Y213504D02*
X474784Y213517D01*
G01X475691Y218203D02*
X475693Y218189D01*
G01X475688Y218216D02*
X475691Y218203D01*
G01X475689Y218228D02*
X475688Y218216D01*
G01X475691Y215053D02*
X475693Y215040D01*
G01X475688Y215066D02*
X475691Y215053D01*
G01X475689Y215079D02*
X475688Y215066D01*
G01X474744Y213734D02*
Y213727D01*
G01X474743Y213739D02*
X474744Y213734D01*
G01X474743Y213732D02*
Y213739D01*
G01X475688Y216666D02*
X475689Y216654D01*
G01X475691Y216679D02*
X475688Y216666D01*
G01X475692Y216693D02*
X475691Y216679D01*
G01X475688Y213517D02*
X475689Y213504D01*
G01X475691Y213530D02*
X475688Y213517D01*
G01X475692Y213543D02*
X475691Y213530D01*
G01X475728Y213719D02*
Y213727D01*
G01X475725Y213713D02*
X475728Y213719D01*
G01X475722Y213706D02*
X475725Y213713D01*
G01X475717Y213700D02*
X475722Y213706D01*
G01X475711Y213696D02*
X475717Y213700D01*
G01X475704Y213693D02*
X475711Y213696D01*
G01X475696Y213691D02*
X475704Y213693D01*
G01X475689Y213690D02*
X475696Y213691D01*
G01X474747Y214862D02*
X474742Y214843D01*
G01X474761Y214877D02*
X474747Y214862D01*
G01X474781Y214882D02*
X474761Y214877D01*
G01X474747Y218012D02*
X474742Y217992D01*
G01X474761Y218026D02*
X474747Y218012D01*
G01X474781Y218031D02*
X474761Y218026D01*
G01X475722Y213720D02*
X475727Y213740D01*
G01X475707Y213706D02*
X475722Y213720D01*
G01X475687Y213701D02*
X475707Y213706D01*
G01X475722Y216870D02*
X475727Y216890D01*
G01X475707Y216856D02*
X475722Y216870D01*
G01X475687Y216850D02*
X475707Y216856D01*
G01X474757Y218023D02*
X474781Y218031D01*
G01X474746Y218009D02*
X474757Y218023D01*
G01X474744Y218002D02*
X474746Y218009D01*
G01X474757Y214874D02*
X474781Y214882D01*
G01X474746Y214859D02*
X474757Y214874D01*
G01X474744Y214852D02*
X474746Y214859D01*
G01X475728Y217998D02*
Y218006D01*
G01Y217994D02*
Y217998D01*
G01X475727Y217992D02*
X475728Y217994D01*
G01Y214849D02*
Y214856D01*
G01Y214844D02*
Y214849D01*
G01X475727Y214843D02*
X475728Y214844D01*
G01X475689Y218037D02*
Y218043D01*
G01X475688Y218033D02*
X475689Y218037D01*
G01X475687Y218031D02*
X475688Y218033D01*
G01X475689Y214887D02*
Y214893D01*
G01X475688Y214883D02*
X475689Y214887D01*
G01X475687Y214882D02*
X475688Y214883D01*
G01X489154Y259796D02*
Y259787D01*
G01X489155Y259802D02*
X489154Y259796D01*
G01X489156Y259803D02*
X489155Y259802D01*
G01X489154Y254796D02*
Y254787D01*
G01X489155Y254802D02*
X489154Y254796D01*
G01X489156Y254803D02*
X489155Y254802D01*
G01X489154Y249796D02*
Y249787D01*
G01X489155Y249802D02*
X489154Y249796D01*
G01X489156Y249803D02*
X489155Y249802D01*
G01X489154Y244796D02*
Y244787D01*
G01X489155Y244802D02*
X489154Y244796D01*
G01X489156Y244803D02*
X489155Y244802D01*
G01X489154Y239796D02*
Y239787D01*
G01X489155Y239802D02*
X489154Y239796D01*
G01X489156Y239803D02*
X489155Y239802D01*
G01X489154Y234796D02*
Y234787D01*
G01X489155Y234802D02*
X489154Y234796D01*
G01X489156Y234803D02*
X489155Y234802D01*
G01X489154Y229796D02*
Y229787D01*
G01X489155Y229802D02*
X489154Y229796D01*
G01X489156Y229803D02*
X489155Y229802D01*
G01X489154Y224796D02*
Y224787D01*
G01X489155Y224802D02*
X489154Y224796D01*
G01X489156Y224803D02*
X489155Y224802D01*
G01X489154Y219796D02*
Y219787D01*
G01X489155Y219802D02*
X489154Y219796D01*
G01X489156Y219803D02*
X489155Y219802D01*
G01X474744Y217998D02*
Y218006D01*
G01X474743Y217994D02*
X474744Y217998D01*
G01X474742Y217992D02*
X474743Y217994D01*
G01X474744Y214849D02*
Y214856D01*
G01X474743Y214844D02*
X474744Y214849D01*
G01X474742Y214843D02*
X474743Y214844D01*
G01X475726Y216864D02*
X475728Y216876D01*
G01X475719Y216853D02*
X475726Y216864D01*
G01X475709Y216844D02*
X475719Y216853D01*
G01X474783Y218037D02*
Y218043D01*
G01Y218033D02*
Y218037D01*
G01X474781Y218031D02*
X474783Y218033D01*
G01Y214887D02*
Y214893D01*
G01Y214883D02*
Y214887D01*
G01X474781Y214882D02*
X474783Y214883D01*
G01X474745Y218012D02*
X474744Y218006D01*
G01X474746Y218019D02*
X474745Y218012D01*
G01X474749Y218024D02*
X474746Y218019D01*
G01X474753Y218030D02*
X474749Y218024D01*
G01X474758Y218034D02*
X474753Y218030D01*
G01X474763Y218038D02*
X474758Y218034D01*
G01X474745Y214863D02*
X474744Y214856D01*
G01X474746Y214869D02*
X474745Y214863D01*
G01X474749Y214874D02*
X474746Y214869D01*
G01X474753Y214880D02*
X474749Y214874D01*
G01X474758Y214884D02*
X474753Y214880D01*
G01X474763Y214888D02*
X474758Y214884D01*
G01X475700Y216852D02*
X475687Y216850D01*
G01X475710Y216857D02*
X475700Y216852D01*
G01Y213703D02*
X475687Y213701D01*
G01X475710Y213708D02*
X475700Y213703D01*
G01X488583Y217854D02*
X489764Y219035D01*
G01X484646Y217854D02*
X485827Y219035D01*
G01X493504Y259803D02*
X488171D01*
G01X488169Y259311D02*
X489154D01*
G01Y256673D02*
X488169D01*
G01X489154Y259607D02*
X488169Y259606D01*
G01Y256377D02*
X489124Y256378D01*
G01X475728Y214845D02*
Y214856D01*
G01Y217994D02*
Y218006D01*
G01X489154Y221155D02*
Y221164D01*
G01Y226155D02*
Y226164D01*
G01Y231155D02*
Y231164D01*
G01Y236155D02*
Y236164D01*
G01Y241155D02*
Y241164D01*
G01Y246155D02*
Y246164D01*
G01Y251155D02*
Y251164D01*
G01Y256155D02*
Y256164D01*
G01X493504Y259803D02*
Y261181D01*
G01Y254803D02*
Y256181D01*
G01Y249803D02*
Y251181D01*
G01Y244803D02*
Y246181D01*
G01Y239803D02*
Y241181D01*
G01Y234803D02*
Y236181D01*
G01Y229803D02*
Y231181D01*
G01Y224803D02*
Y226181D01*
G01Y219803D02*
Y221181D01*
G01X490335D02*
Y219803D01*
G01Y226181D02*
Y224803D01*
G01Y231181D02*
Y229803D01*
G01Y236181D02*
Y234803D01*
G01Y241181D02*
Y239803D01*
G01Y246181D02*
Y244803D01*
G01Y251181D02*
Y249803D01*
G01Y256181D02*
Y254803D01*
G01Y261181D02*
Y259803D01*
G01X489154Y221156D02*
Y221299D01*
G01Y226156D02*
Y226299D01*
G01Y231156D02*
Y231299D01*
G01Y236156D02*
Y236299D01*
G01Y241156D02*
Y241299D01*
G01Y246156D02*
Y246299D01*
G01Y251156D02*
Y251299D01*
G01Y256156D02*
Y256299D01*
G01Y259311D02*
Y261673D01*
G01Y254311D02*
Y256673D01*
G01Y249311D02*
Y251673D01*
G01Y244311D02*
Y246673D01*
G01Y239311D02*
Y241673D01*
G01Y234311D02*
Y236673D01*
G01Y229311D02*
Y231673D01*
G01Y224311D02*
Y226673D01*
G01Y219311D02*
Y221673D01*
G01X488169D02*
Y219311D01*
G01Y226673D02*
Y224311D01*
G01Y231673D02*
Y229311D01*
G01Y236673D02*
Y234311D01*
G01Y241673D02*
Y239311D01*
G01Y246673D02*
Y244311D01*
G01Y251673D02*
Y249311D01*
G01Y256673D02*
Y254311D01*
G01Y261673D02*
Y259311D01*
G01X485827Y295492D02*
Y219035D01*
G01X484646Y294311D02*
Y217854D01*
G01X476181Y299232D02*
Y220197D01*
G01X475728Y216693D02*
Y218189D01*
G01Y213543D02*
Y215039D01*
G01X475689Y216839D02*
Y216693D01*
G01Y213690D02*
Y213543D01*
G01Y215040D02*
Y214893D01*
G01Y218189D02*
Y218043D01*
G01X474783D02*
Y218190D01*
G01Y216692D02*
Y216839D01*
G01Y213543D02*
Y213690D01*
G01Y214893D02*
Y215040D01*
G01X474744Y215039D02*
Y213543D01*
G01Y218189D02*
Y216693D01*
G01X473563Y218031D02*
Y216850D01*
G01Y214882D02*
Y213701D01*
G01X469803Y216850D02*
Y218031D01*
G01Y213701D02*
Y214882D01*
G01X475728Y216876D02*
Y216887D01*
G01Y213727D02*
Y213738D01*
G01X474631Y216890D02*
X474743Y216881D01*
G01X488171Y256181D02*
X493504D01*
G01Y256142D02*
X489156D01*
G01X493504Y254803D02*
X488171D01*
G01X488169Y254311D02*
X489154D01*
G01Y251673D02*
X488169D01*
G01X488171Y251181D02*
X493504D01*
G01Y251142D02*
X489156D01*
G01X493504Y249803D02*
X488171D01*
G01X488169Y249311D02*
X489154D01*
G01Y246673D02*
X488169D01*
G01X488171Y246181D02*
X493504D01*
G01Y246142D02*
X489156D01*
G01X493504Y244803D02*
X488171D01*
G01X488169Y244311D02*
X489154D01*
G01Y241673D02*
X488169D01*
G01X488171Y241181D02*
X493504D01*
G01Y241142D02*
X489156D01*
G01X493504Y239803D02*
X488171D01*
G01X488169Y239311D02*
X489154D01*
G01Y236673D02*
X488169D01*
G01X488171Y236181D02*
X493504D01*
G01Y236142D02*
X489156D01*
G01X493504Y234803D02*
X488171D01*
G01X488169Y234311D02*
X489154D01*
G01Y231673D02*
X488169D01*
G01X488171Y231181D02*
X493504D01*
G01Y231142D02*
X489156D01*
G01X493504Y229803D02*
X488171D01*
G01X488169Y229311D02*
X489154D01*
G01Y226673D02*
X488169D01*
G01X488171Y226181D02*
X493504D01*
G01Y226142D02*
X489156D01*
G01X493504Y224803D02*
X488171D01*
G01X488169Y224311D02*
X489154D01*
G01Y221673D02*
X488169D01*
G01X488171Y221181D02*
X493504D01*
G01Y221142D02*
X489156D01*
G01X476181Y220197D02*
X472835D01*
G01X493504Y219803D02*
X488171D01*
G01X488169Y219311D02*
X489154D01*
G01X485827Y219035D02*
X489764D01*
G01X475689Y218228D02*
X474783D01*
G01X475728Y218189D02*
X474744D01*
G01X475687Y218031D02*
X469803D01*
G01Y217992D02*
X475727D01*
G01X484646Y217854D02*
X488583D01*
G01X475727Y216890D02*
X469803D01*
G01X475687Y216850D02*
X469803D01*
G01X474744Y216693D02*
X475728D01*
G01X474783Y216654D02*
X475689D01*
G01Y215079D02*
X474783D01*
G01X475728Y215039D02*
X474744D01*
G01X475687Y214882D02*
X469803D01*
G01Y214843D02*
X475727D01*
G01Y213740D02*
X469803D01*
G01X475687Y213701D02*
X469803D01*
G01X474744Y213543D02*
X475728D01*
G01X474783Y213504D02*
X475689D01*
G01X489154Y254607D02*
X488169Y254606D01*
G01Y251377D02*
X489124Y251378D01*
G01X489154Y249607D02*
X488169Y249606D01*
G01Y246377D02*
X489124Y246378D01*
G01X489154Y244607D02*
X488169Y244606D01*
G01Y241377D02*
X489124Y241378D01*
G01X489154Y239607D02*
X488169Y239606D01*
G01Y236377D02*
X489124Y236378D01*
G01X489154Y234607D02*
X488169Y234606D01*
G01Y231377D02*
X489124Y231378D01*
G01X489154Y229607D02*
X488169Y229606D01*
G01Y226377D02*
X489124Y226378D01*
G01X489154Y224607D02*
X488169Y224606D01*
G01Y221377D02*
X489124Y221378D01*
G01X489154Y219607D02*
X488169Y219606D01*
G01X475687Y213701D02*
X475691Y213690D01*
G01X489141Y261173D02*
X489152Y261157D01*
G01X489117Y261181D02*
X489141Y261173D01*
G01Y266173D02*
X489152Y266157D01*
G01X489117Y266181D02*
X489141Y266173D01*
G01Y271173D02*
X489152Y271157D01*
G01X489117Y271181D02*
X489141Y271173D01*
G01Y276173D02*
X489152Y276157D01*
G01X489117Y276181D02*
X489141Y276173D01*
G01Y281173D02*
X489152Y281157D01*
G01X489117Y281181D02*
X489141Y281173D01*
G01Y286173D02*
X489152Y286157D01*
G01X489117Y286181D02*
X489141Y286173D01*
G01Y291173D02*
X489152Y291157D01*
G01X489117Y291181D02*
X489141Y291173D01*
G01X489154Y261148D02*
Y261156D01*
G01X489155Y261144D02*
X489154Y261148D01*
G01X489156Y261142D02*
X489155Y261144D01*
G01X489154Y266148D02*
Y266156D01*
G01X489155Y266144D02*
X489154Y266148D01*
G01X489156Y266142D02*
X489155Y266144D01*
G01X489154Y271148D02*
Y271156D01*
G01X489155Y271144D02*
X489154Y271148D01*
G01X489156Y271142D02*
X489155Y271144D01*
G01X489154Y276148D02*
Y276156D01*
G01X489155Y276144D02*
X489154Y276148D01*
G01X489156Y276142D02*
X489155Y276144D01*
G01X489154Y281148D02*
Y281156D01*
G01X489155Y281144D02*
X489154Y281148D01*
G01X489156Y281142D02*
X489155Y281144D01*
G01X489154Y286148D02*
Y286156D01*
G01X489155Y286144D02*
X489154Y286148D01*
G01X489156Y286142D02*
X489155Y286144D01*
G01X489154Y291148D02*
Y291156D01*
G01X489155Y291144D02*
X489154Y291148D01*
G01X489156Y291142D02*
X489155Y291144D01*
G01X488169Y261189D02*
Y261198D01*
G01X488170Y261183D02*
X488169Y261189D01*
G01X488171Y261181D02*
X488170Y261183D01*
G01X488169Y266189D02*
Y266198D01*
G01X488170Y266183D02*
X488169Y266189D01*
G01X488171Y266181D02*
X488170Y266183D01*
G01X488169Y271189D02*
Y271198D01*
G01X488170Y271183D02*
X488169Y271189D01*
G01X488171Y271181D02*
X488170Y271183D01*
G01X488169Y276189D02*
Y276198D01*
G01X488170Y276183D02*
X488169Y276189D01*
G01X488171Y276181D02*
X488170Y276183D01*
G01X488169Y281189D02*
Y281198D01*
G01X488170Y281183D02*
X488169Y281189D01*
G01X488171Y281181D02*
X488170Y281183D01*
G01X488169Y286189D02*
Y286198D01*
G01X488170Y286183D02*
X488169Y286189D01*
G01X488171Y286181D02*
X488170Y286183D01*
G01X488169Y291189D02*
Y291198D01*
G01X488170Y291183D02*
X488169Y291189D01*
G01X488171Y291181D02*
X488170Y291183D01*
G01X489146Y261325D02*
X489154Y261299D01*
G01X489136Y261352D02*
X489146Y261325D01*
G01X489124Y261378D02*
X489136Y261352D01*
G01X489146Y266325D02*
X489154Y266299D01*
G01X489136Y266352D02*
X489146Y266325D01*
G01X489124Y266378D02*
X489136Y266352D01*
G01X489146Y271325D02*
X489154Y271299D01*
G01X489136Y271352D02*
X489146Y271325D01*
G01X489124Y271378D02*
X489136Y271352D01*
G01X489146Y276325D02*
X489154Y276299D01*
G01X489136Y276352D02*
X489146Y276325D01*
G01X489124Y276378D02*
X489136Y276352D01*
G01X489146Y281325D02*
X489154Y281299D01*
G01X489136Y281352D02*
X489146Y281325D01*
G01X489124Y281378D02*
X489136Y281352D01*
G01X489146Y286325D02*
X489154Y286299D01*
G01X489136Y286352D02*
X489146Y286325D01*
G01X489124Y286378D02*
X489136Y286352D01*
G01X489146Y291325D02*
X489154Y291299D01*
G01X489136Y291352D02*
X489146Y291325D01*
G01X489124Y291378D02*
X489136Y291352D01*
G01Y261176D02*
X489117Y261181D01*
G01X489151Y261162D02*
X489136Y261176D01*
G01X489156Y261142D02*
X489151Y261162D01*
G01X489136Y266176D02*
X489117Y266181D01*
G01X489151Y266162D02*
X489136Y266176D01*
G01X489156Y266142D02*
X489151Y266162D01*
G01X489136Y271176D02*
X489117Y271181D01*
G01X489151Y271162D02*
X489136Y271176D01*
G01X489156Y271142D02*
X489151Y271162D01*
G01X489136Y276176D02*
X489117Y276181D01*
G01X489151Y276162D02*
X489136Y276176D01*
G01X489156Y276142D02*
X489151Y276162D01*
G01X489136Y281176D02*
X489117Y281181D01*
G01X489151Y281162D02*
X489136Y281176D01*
G01X489156Y281142D02*
X489151Y281162D01*
G01X489136Y286176D02*
X489117Y286181D01*
G01X489151Y286162D02*
X489136Y286176D01*
G01X489156Y286142D02*
X489151Y286162D01*
G01X489136Y291176D02*
X489117Y291181D01*
G01X489151Y291162D02*
X489136Y291176D01*
G01X489156Y291142D02*
X489151Y291162D01*
G01X489120Y261279D02*
X489124Y261378D01*
G01X489115Y261207D02*
X489120Y261279D01*
G01X489117Y261181D02*
X489115Y261207D01*
G01X489120Y266279D02*
X489124Y266378D01*
G01X489115Y266207D02*
X489120Y266279D01*
G01X489117Y266181D02*
X489115Y266207D01*
G01X489120Y271279D02*
X489124Y271378D01*
G01X489115Y271207D02*
X489120Y271279D01*
G01X489117Y271181D02*
X489115Y271207D01*
G01X489120Y276279D02*
X489124Y276378D01*
G01X489115Y276207D02*
X489120Y276279D01*
G01X489117Y276181D02*
X489115Y276207D01*
G01X489120Y281279D02*
X489124Y281378D01*
G01X489115Y281207D02*
X489120Y281279D01*
G01X489117Y281181D02*
X489115Y281207D01*
G01X489120Y286279D02*
X489124Y286378D01*
G01X489115Y286207D02*
X489120Y286279D01*
G01X489117Y286181D02*
X489115Y286207D01*
G01X489120Y291279D02*
X489124Y291378D01*
G01X489115Y291207D02*
X489120Y291279D01*
G01X489117Y291181D02*
X489115Y291207D01*
G01X488170Y289802D02*
X488171Y289803D01*
G01X488169Y289796D02*
X488170Y289802D01*
G01X488169Y289787D02*
Y289796D01*
G01X488170Y284802D02*
X488171Y284803D01*
G01X488169Y284796D02*
X488170Y284802D01*
G01X488169Y284787D02*
Y284796D01*
G01X488170Y279802D02*
X488171Y279803D01*
G01X488169Y279796D02*
X488170Y279802D01*
G01X488169Y279787D02*
Y279796D01*
G01X488170Y274802D02*
X488171Y274803D01*
G01X488169Y274796D02*
X488170Y274802D01*
G01X488169Y274787D02*
Y274796D01*
G01X488170Y269802D02*
X488171Y269803D01*
G01X488169Y269796D02*
X488170Y269802D01*
G01X488169Y269787D02*
Y269796D01*
G01X488170Y264802D02*
X488171Y264803D01*
G01X488169Y264796D02*
X488170Y264802D01*
G01X488169Y264787D02*
Y264796D01*
G01X489154Y289796D02*
Y289787D01*
G01X489155Y289802D02*
X489154Y289796D01*
G01X489156Y289803D02*
X489155Y289802D01*
G01X489154Y284796D02*
Y284787D01*
G01X489155Y284802D02*
X489154Y284796D01*
G01X489156Y284803D02*
X489155Y284802D01*
G01X489154Y279796D02*
Y279787D01*
G01X489155Y279802D02*
X489154Y279796D01*
G01X489156Y279803D02*
X489155Y279802D01*
G01X489154Y274796D02*
Y274787D01*
G01X489155Y274802D02*
X489154Y274796D01*
G01X489156Y274803D02*
X489155Y274802D01*
G01X489154Y269796D02*
Y269787D01*
G01X489155Y269802D02*
X489154Y269796D01*
G01X489156Y269803D02*
X489155Y269802D01*
G01X489154Y264796D02*
Y264787D01*
G01X489155Y264802D02*
X489154Y264796D01*
G01X489156Y264803D02*
X489155Y264802D01*
G01X481102Y307579D02*
G03X479921Y306398I0J-1181D01*
G01X487402D02*
G03X486220Y307579I-1181J0D01*
G01X485551Y302303D02*
G03I-1890J0D01*
G01X486024D02*
G03I-2363J0D01*
G01X494488Y300335D02*
X491142Y296988D01*
G01X484646Y294311D02*
X485827Y295492D01*
G01X481177Y299232D02*
X482480Y301201D01*
G01X487153Y307123D02*
X484843Y302894D01*
G01X494488Y307618D02*
X472835D01*
G01X481102Y307579D02*
X486220D01*
G01X482480Y302894D02*
X484843D01*
G01X482480Y301201D02*
X484843D01*
G01X476181Y299232D02*
X490551D01*
G01X476181Y297854D02*
X479921D01*
G01X490551D02*
X487402D01*
G01X476181Y296988D02*
X491142D01*
G01X477953Y295492D02*
X485827D01*
G01X479134Y294311D02*
X484646D01*
G01X489154Y291673D02*
X488169D01*
G01X488171Y291181D02*
X493504D01*
G01Y291142D02*
X489156D01*
G01X493504Y289803D02*
X488171D01*
G01X488169Y289311D02*
X489154D01*
G01Y286673D02*
X488169D01*
G01X488171Y286181D02*
X493504D01*
G01Y286142D02*
X489156D01*
G01X493504Y284803D02*
X488171D01*
G01X488169Y284311D02*
X489154D01*
G01Y281673D02*
X488169D01*
G01X488171Y281181D02*
X493504D01*
G01Y281142D02*
X489156D01*
G01X493504Y279803D02*
X488171D01*
G01X488169Y279311D02*
X489154D01*
G01Y276673D02*
X488169D01*
G01X488171Y276181D02*
X493504D01*
G01Y276142D02*
X489156D01*
G01X493504Y274803D02*
X488171D01*
G01X488169Y274311D02*
X489154D01*
G01Y271673D02*
X488169D01*
G01X488171Y271181D02*
X493504D01*
G01Y271142D02*
X489156D01*
G01X493504Y269803D02*
X488171D01*
G01X488169Y269311D02*
X489154D01*
G01Y266673D02*
X488169D01*
G01X488171Y266181D02*
X493504D01*
G01Y266142D02*
X489156D01*
G01X493504Y264803D02*
X488171D01*
G01X488169Y264311D02*
X489154D01*
G01Y261673D02*
X488169D01*
G01X488171Y261181D02*
X493504D01*
G01Y261142D02*
X489156D01*
G01X488169Y291377D02*
X489124Y291378D01*
G01X489154Y289607D02*
X488169Y289606D01*
G01Y286377D02*
X489124Y286378D01*
G01X489154Y284607D02*
X488169Y284606D01*
G01Y281377D02*
X489124Y281378D01*
G01X489154Y279607D02*
X488169Y279606D01*
G01Y276377D02*
X489124Y276378D01*
G01X489154Y274607D02*
X488169Y274606D01*
G01Y271377D02*
X489124Y271378D01*
G01X489154Y269607D02*
X488169Y269606D01*
G01Y266377D02*
X489124Y266378D01*
G01X489154Y264607D02*
X488169Y264606D01*
G01Y261377D02*
X489124Y261378D01*
G01X489154Y261155D02*
Y261164D01*
G01Y266155D02*
Y266164D01*
G01Y271155D02*
Y271164D01*
G01Y276155D02*
Y276164D01*
G01Y281155D02*
Y281164D01*
G01Y286155D02*
Y286164D01*
G01Y291155D02*
Y291164D01*
G01X494488Y300335D02*
Y316083D01*
G01X493504Y289803D02*
Y291181D01*
G01Y284803D02*
Y286181D01*
G01Y279803D02*
Y281181D01*
G01Y274803D02*
Y276181D01*
G01Y269803D02*
Y271181D01*
G01Y264803D02*
Y266181D01*
G01X490335D02*
Y264803D01*
G01Y271181D02*
Y269803D01*
G01Y276181D02*
Y274803D01*
G01Y281181D02*
Y279803D01*
G01Y286181D02*
Y284803D01*
G01Y291181D02*
Y289803D01*
G01X489154Y261156D02*
Y261299D01*
G01Y266156D02*
Y266299D01*
G01Y271156D02*
Y271299D01*
G01Y276156D02*
Y276299D01*
G01Y281156D02*
Y281299D01*
G01Y286156D02*
Y286299D01*
G01Y291156D02*
Y291299D01*
G01Y289311D02*
Y291673D01*
G01Y284311D02*
Y286673D01*
G01Y279311D02*
Y281673D01*
G01Y274311D02*
Y276673D01*
G01Y269311D02*
Y271673D01*
G01Y264311D02*
Y266673D01*
G01X488169D02*
Y264311D01*
G01Y271673D02*
Y269311D01*
G01Y276673D02*
Y274311D01*
G01Y281673D02*
Y279311D01*
G01Y286673D02*
Y284311D01*
G01Y291673D02*
Y289311D01*
G01X487402Y306398D02*
Y297854D01*
G01X484843Y302894D02*
Y301201D01*
G01X482480D02*
Y302894D01*
G01X479921Y297854D02*
Y306398D01*
G01X472835Y316083D02*
Y300335D01*
G01X482480Y302894D02*
X480170Y307123D01*
G01X484843Y301201D02*
X486146Y299232D01*
G01X477953Y295492D02*
X479134Y294311D01*
G01X472835Y300335D02*
X476181Y296988D01*
G01X487598Y316673D02*
G03X487008Y317264I-590J1D01*
G01X480315D02*
G03X479724Y316673I0J-591D01*
G01X482480Y315492D02*
G03Y313524I0J-984D01*
G01X484843D02*
G03Y315492I0J984D01*
G01X494488Y316083D02*
G03X492520Y318051I-1968J0D01*
G01X474803D02*
G03X472835Y316083I0J-1968D01*
G01X492520Y318051D02*
X474803D01*
G01X487008Y317264D02*
X480315D01*
G01X484843Y315492D02*
X482480D01*
G01Y313524D02*
X484843D01*
G01X487598Y312146D02*
X479724D01*
G01Y310571D02*
X487598D01*
G01D02*
Y316673D01*
G01X479724Y310571D02*
Y316673D01*
G01Y592067D02*
G03X480315Y591476I591J0D01*
G01X487008D02*
G03X487598Y592067I-1J591D01*
G01X484843Y593248D02*
G03Y595217I0J985D01*
G01X482480D02*
G03Y593248I0J-985D01*
G01X492520Y590689D02*
G03X494488Y592657I0J1968D01*
G01X472835D02*
G03X474803Y590689I1968J0D01*
G01X487598Y598169D02*
X479724D01*
G01Y596594D02*
X487598D01*
G01X484843Y595217D02*
X482480D01*
G01Y593248D02*
X484843D01*
G01X487008Y591476D02*
X480315D01*
G01X492520Y590689D02*
X474803D01*
G01X494488Y592657D02*
Y608406D01*
G01X487598Y598169D02*
Y592067D01*
G01X479724Y598169D02*
Y592067D01*
G01X472835Y608406D02*
Y592657D01*
G01X489120Y619035D02*
X489124Y619134D01*
G01X489115Y618963D02*
X489120Y619035D01*
G01X489117Y618937D02*
X489115Y618963D01*
G01X489120Y624035D02*
X489124Y624134D01*
G01X489115Y623963D02*
X489120Y624035D01*
G01X489117Y623937D02*
X489115Y623963D01*
G01X489120Y629035D02*
X489124Y629134D01*
G01X489115Y628963D02*
X489120Y629035D01*
G01X489117Y628937D02*
X489115Y628963D01*
G01X489120Y634035D02*
X489124Y634134D01*
G01X489115Y633963D02*
X489120Y634035D01*
G01X489117Y633937D02*
X489115Y633963D01*
G01X489120Y639035D02*
X489124Y639134D01*
G01X489115Y638963D02*
X489120Y639035D01*
G01X489117Y638937D02*
X489115Y638963D01*
G01X489120Y644035D02*
X489124Y644134D01*
G01X489115Y643963D02*
X489120Y644035D01*
G01X489117Y643937D02*
X489115Y643963D01*
G01X488170Y647557D02*
X488171Y647559D01*
G01X488169Y647552D02*
X488170Y647557D01*
G01X488169Y647543D02*
Y647552D01*
G01X488170Y642557D02*
X488171Y642559D01*
G01X488169Y642552D02*
X488170Y642557D01*
G01X488169Y642543D02*
Y642552D01*
G01X488170Y637557D02*
X488171Y637559D01*
G01X488169Y637552D02*
X488170Y637557D01*
G01X488169Y637543D02*
Y637552D01*
G01X488170Y632557D02*
X488171Y632559D01*
G01X488169Y632552D02*
X488170Y632557D01*
G01X488169Y632543D02*
Y632552D01*
G01X488170Y627557D02*
X488171Y627559D01*
G01X488169Y627552D02*
X488170Y627557D01*
G01X488169Y627543D02*
Y627552D01*
G01X488170Y622557D02*
X488171Y622559D01*
G01X488169Y622552D02*
X488170Y622557D01*
G01X488169Y622543D02*
Y622552D01*
G01X488170Y617557D02*
X488171Y617559D01*
G01X488169Y617552D02*
X488170Y617557D01*
G01X488169Y617543D02*
Y617552D01*
G01X489154Y618904D02*
Y618911D01*
G01X489155Y618900D02*
X489154Y618904D01*
G01X489156Y618898D02*
X489155Y618900D01*
G01X489154Y623904D02*
Y623911D01*
G01X489155Y623900D02*
X489154Y623904D01*
G01X489156Y623898D02*
X489155Y623900D01*
G01X489154Y628904D02*
Y628911D01*
G01X489155Y628900D02*
X489154Y628904D01*
G01X489156Y628898D02*
X489155Y628900D01*
G01X489154Y633904D02*
Y633911D01*
G01X489155Y633900D02*
X489154Y633904D01*
G01X489156Y633898D02*
X489155Y633900D01*
G01X489154Y638904D02*
Y638911D01*
G01X489155Y638900D02*
X489154Y638904D01*
G01X489156Y638898D02*
X489155Y638900D01*
G01X489154Y643904D02*
Y643911D01*
G01X489155Y643900D02*
X489154Y643904D01*
G01X489156Y643898D02*
X489155Y643900D01*
G01X488169Y618944D02*
Y618954D01*
G01X488170Y618939D02*
X488169Y618944D01*
G01X488171Y618937D02*
X488170Y618939D01*
G01X488169Y623944D02*
Y623954D01*
G01X488170Y623939D02*
X488169Y623944D01*
G01X488171Y623937D02*
X488170Y623939D01*
G01X488169Y628944D02*
Y628954D01*
G01X488170Y628939D02*
X488169Y628944D01*
G01X488171Y628937D02*
X488170Y628939D01*
G01X488169Y633944D02*
Y633954D01*
G01X488170Y633939D02*
X488169Y633944D01*
G01X488171Y633937D02*
X488170Y633939D01*
G01X488169Y638944D02*
Y638954D01*
G01X488170Y638939D02*
X488169Y638944D01*
G01X488171Y638937D02*
X488170Y638939D01*
G01X488169Y643944D02*
Y643954D01*
G01X488170Y643939D02*
X488169Y643944D01*
G01X488171Y643937D02*
X488170Y643939D01*
G01X489146Y619081D02*
X489154Y619055D01*
G01X489136Y619107D02*
X489146Y619081D01*
G01X489124Y619134D02*
X489136Y619107D01*
G01X489146Y624081D02*
X489154Y624055D01*
G01X489136Y624107D02*
X489146Y624081D01*
G01X489124Y624134D02*
X489136Y624107D01*
G01X489146Y629081D02*
X489154Y629055D01*
G01X489136Y629107D02*
X489146Y629081D01*
G01X489124Y629134D02*
X489136Y629107D01*
G01X489146Y634081D02*
X489154Y634055D01*
G01X489136Y634107D02*
X489146Y634081D01*
G01X489124Y634134D02*
X489136Y634107D01*
G01X489146Y639081D02*
X489154Y639055D01*
G01X489136Y639107D02*
X489146Y639081D01*
G01X489124Y639134D02*
X489136Y639107D01*
G01X489146Y644081D02*
X489154Y644055D01*
G01X489136Y644107D02*
X489146Y644081D01*
G01X489124Y644134D02*
X489136Y644107D01*
G01Y618932D02*
X489117Y618937D01*
G01X489151Y618918D02*
X489136Y618932D01*
G01X489156Y618898D02*
X489151Y618918D01*
G01X489136Y623932D02*
X489117Y623937D01*
G01X489151Y623918D02*
X489136Y623932D01*
G01X489156Y623898D02*
X489151Y623918D01*
G01X489136Y628932D02*
X489117Y628937D01*
G01X489151Y628918D02*
X489136Y628932D01*
G01X489156Y628898D02*
X489151Y628918D01*
G01X489136Y633932D02*
X489117Y633937D01*
G01X489151Y633918D02*
X489136Y633932D01*
G01X489156Y633898D02*
X489151Y633918D01*
G01X489136Y638932D02*
X489117Y638937D01*
G01X489151Y638918D02*
X489136Y638932D01*
G01X489156Y638898D02*
X489151Y638918D01*
G01X489136Y643932D02*
X489117Y643937D01*
G01X489151Y643918D02*
X489136Y643932D01*
G01X489156Y643898D02*
X489151Y643918D01*
G01X489154Y647552D02*
Y647543D01*
G01X489155Y647557D02*
X489154Y647552D01*
G01X489156Y647559D02*
X489155Y647557D01*
G01X489154Y642552D02*
Y642543D01*
G01X489155Y642557D02*
X489154Y642552D01*
G01X489156Y642559D02*
X489155Y642557D01*
G01X489154Y637552D02*
Y637543D01*
G01X489155Y637557D02*
X489154Y637552D01*
G01X489156Y637559D02*
X489155Y637557D01*
G01X489154Y632552D02*
Y632543D01*
G01X489155Y632557D02*
X489154Y632552D01*
G01X489156Y632559D02*
X489155Y632557D01*
G01X489154Y627552D02*
Y627543D01*
G01X489155Y627557D02*
X489154Y627552D01*
G01X489156Y627559D02*
X489155Y627557D01*
G01X489154Y622552D02*
Y622543D01*
G01X489155Y622557D02*
X489154Y622552D01*
G01X489156Y622559D02*
X489155Y622557D01*
G01X489154Y617552D02*
Y617543D01*
G01X489155Y617557D02*
X489154Y617552D01*
G01X489156Y617559D02*
X489155Y617557D01*
G01X489141Y618929D02*
X489152Y618913D01*
G01X489117Y618937D02*
X489141Y618929D01*
G01Y623929D02*
X489152Y623913D01*
G01X489117Y623937D02*
X489141Y623929D01*
G01Y628929D02*
X489152Y628913D01*
G01X489117Y628937D02*
X489141Y628929D01*
G01Y633929D02*
X489152Y633913D01*
G01X489117Y633937D02*
X489141Y633929D01*
G01Y638929D02*
X489152Y638913D01*
G01X489117Y638937D02*
X489141Y638929D01*
G01Y643929D02*
X489152Y643913D01*
G01X489117Y643937D02*
X489141Y643929D01*
G01X484764Y606437D02*
G03I-1103J0D01*
G01X486220Y601161D02*
G03X487402Y602343I1J1181D01*
G01X479921D02*
G03X481102Y601161I1181J-1D01*
G01X485236Y606437D02*
G03I-1575J0D01*
G01X493504Y647559D02*
X488171D01*
G01X488169Y647067D02*
X489154D01*
G01Y644429D02*
X488169D01*
G01X488171Y643937D02*
X493504D01*
G01Y643898D02*
X489156D01*
G01X493504Y642559D02*
X488171D01*
G01X488169Y642067D02*
X489154D01*
G01Y639429D02*
X488169D01*
G01X488171Y638937D02*
X493504D01*
G01Y638898D02*
X489156D01*
G01X493504Y637559D02*
X488171D01*
G01X488169Y637067D02*
X489154D01*
G01Y634429D02*
X488169D01*
G01X488171Y633937D02*
X493504D01*
G01Y633898D02*
X489156D01*
G01X493504Y632559D02*
X488171D01*
G01X488169Y632067D02*
X489154D01*
G01Y629429D02*
X488169D01*
G01X488171Y628937D02*
X493504D01*
G01Y628898D02*
X489156D01*
G01X493504Y627559D02*
X488171D01*
G01X488169Y627067D02*
X489154D01*
G01Y624429D02*
X488169D01*
G01X488171Y623937D02*
X493504D01*
G01Y623898D02*
X489156D01*
G01X493504Y622559D02*
X488171D01*
G01X488169Y622067D02*
X489154D01*
G01Y619429D02*
X488169D01*
G01X488171Y618937D02*
X493504D01*
G01Y618898D02*
X489156D01*
G01X493504Y617559D02*
X488171D01*
G01X488169Y617067D02*
X489154D01*
G01Y647363D02*
X488169Y647362D01*
G01Y644133D02*
X489124Y644134D01*
G01X489154Y642363D02*
X488169Y642362D01*
G01Y639133D02*
X489124Y639134D01*
G01X489154Y637363D02*
X488169Y637362D01*
G01Y634133D02*
X489124Y634134D01*
G01X489154Y632363D02*
X488169Y632362D01*
G01Y629133D02*
X489124Y629134D01*
G01X489154Y627363D02*
X488169Y627362D01*
G01Y624133D02*
X489124Y624134D01*
G01X489154Y622363D02*
X488169Y622362D01*
G01Y619133D02*
X489124Y619134D01*
G01X489154Y617363D02*
X488169Y617362D01*
G01X484646Y614429D02*
X479134D01*
G01X485827Y613248D02*
X477953D01*
G01X491142Y611752D02*
X476181D01*
G01X487402Y610886D02*
X490551D01*
G01X479921D02*
X476181D01*
G01Y609508D02*
X490551D01*
G01X484843Y607539D02*
X482480D01*
G01X484843Y605846D02*
X482480D01*
G01X486220Y601161D02*
X481102D01*
G01X494488Y601122D02*
X472835D01*
G01X479134Y614429D02*
X477953Y613248D01*
G01X476181Y611752D02*
X472835Y608406D01*
G01X486146Y609508D02*
X484843Y607539D01*
G01X480170Y601617D02*
X482480Y605846D01*
G01X484843D02*
X487153Y601617D01*
G01X482480Y607539D02*
X481177Y609508D01*
G01X491142Y611752D02*
X494488Y608406D01*
G01X484646Y614429D02*
X485827Y613248D01*
G01X489154Y618911D02*
Y618920D01*
G01Y623911D02*
Y623920D01*
G01Y628911D02*
Y628920D01*
G01Y633911D02*
Y633920D01*
G01Y638911D02*
Y638920D01*
G01Y643911D02*
Y643920D01*
G01X493504Y647559D02*
Y648937D01*
G01Y642559D02*
Y643937D01*
G01Y637559D02*
Y638937D01*
G01Y632559D02*
Y633937D01*
G01Y627559D02*
Y628937D01*
G01Y622559D02*
Y623937D01*
G01Y617559D02*
Y618937D01*
G01X491142Y749744D02*
Y611752D01*
G01X490551Y751988D02*
Y609508D01*
G01X490335Y618937D02*
Y617559D01*
G01Y623937D02*
Y622559D01*
G01Y628937D02*
Y627559D01*
G01Y633937D02*
Y632559D01*
G01Y638937D02*
Y637559D01*
G01Y643937D02*
Y642559D01*
G01Y648937D02*
Y647559D01*
G01X489154Y647067D02*
Y649429D01*
G01Y642067D02*
Y644429D01*
G01Y637067D02*
Y639429D01*
G01Y632067D02*
Y634429D01*
G01Y627067D02*
Y629429D01*
G01Y622067D02*
Y624429D01*
G01Y617067D02*
Y619429D01*
G01X488169D02*
Y617067D01*
G01Y624429D02*
Y622067D01*
G01Y629429D02*
Y627067D01*
G01Y634429D02*
Y632067D01*
G01Y639429D02*
Y637067D01*
G01Y644429D02*
Y642067D01*
G01Y649429D02*
Y647067D01*
G01X487402Y610886D02*
Y602343D01*
G01X485827Y649705D02*
Y613248D01*
G01X484843Y607539D02*
Y605846D01*
G01X484646Y650886D02*
Y614429D01*
G01X482480Y605846D02*
Y607539D01*
G01X479921Y602343D02*
Y610886D01*
G01X479134Y614429D02*
Y747067D01*
G01X477953Y613248D02*
Y748248D01*
G01X476181Y648543D02*
Y609508D01*
G01X489120Y649035D02*
X489124Y649134D01*
G01X489115Y648963D02*
X489120Y649035D01*
G01X489117Y648937D02*
X489115Y648963D01*
G01X489120Y674035D02*
X489124Y674134D01*
G01X489115Y673963D02*
X489120Y674035D01*
G01X489117Y673937D02*
X489115Y673963D01*
G01X489120Y679035D02*
X489124Y679134D01*
G01X489115Y678963D02*
X489120Y679035D01*
G01X489117Y678937D02*
X489115Y678963D01*
G01X489120Y684035D02*
X489124Y684134D01*
G01X489115Y683963D02*
X489120Y684035D01*
G01X489117Y683937D02*
X489115Y683963D01*
G01X489120Y689035D02*
X489124Y689134D01*
G01X489115Y688963D02*
X489120Y689035D01*
G01X489117Y688937D02*
X489115Y688963D01*
G01X489120Y694035D02*
X489124Y694134D01*
G01X489115Y693963D02*
X489120Y694035D01*
G01X489117Y693937D02*
X489115Y693963D01*
G01X474744Y663341D02*
Y663333D01*
G01X474743Y663345D02*
X474744Y663341D01*
G01X474743Y663336D02*
Y663345D01*
G01X474784Y670972D02*
X474783Y670984D01*
G01X474781Y670959D02*
X474784Y670972D01*
G01X474781Y670945D02*
Y670959D01*
G01X474784Y667822D02*
X474783Y667835D01*
G01X474781Y667809D02*
X474784Y667822D01*
G01X474781Y667796D02*
Y667809D01*
G01X474784Y664673D02*
X474783Y664685D01*
G01X474781Y664660D02*
X474784Y664673D01*
G01X474781Y664646D02*
Y664660D01*
G01X474784Y661523D02*
X474783Y661535D01*
G01X474781Y661510D02*
X474784Y661523D01*
G01X474781Y661496D02*
Y661510D01*
G01X474784Y658374D02*
X474783Y658386D01*
G01X474781Y658361D02*
X474784Y658374D01*
G01X474781Y658347D02*
Y658361D01*
G01X474784Y655224D02*
X474783Y655236D01*
G01X474781Y655211D02*
X474784Y655224D01*
G01X474781Y655197D02*
Y655211D01*
G01X474784Y652074D02*
X474783Y652087D01*
G01X474781Y652061D02*
X474784Y652074D01*
G01X474781Y652048D02*
Y652061D01*
G01X488170Y692557D02*
X488171Y692559D01*
G01X488169Y692552D02*
X488170Y692557D01*
G01X488169Y692543D02*
Y692552D01*
G01X488170Y687557D02*
X488171Y687559D01*
G01X488169Y687552D02*
X488170Y687557D01*
G01X488169Y687543D02*
Y687552D01*
G01X488170Y682557D02*
X488171Y682559D01*
G01X488169Y682552D02*
X488170Y682557D01*
G01X488169Y682543D02*
Y682552D01*
G01X488170Y677557D02*
X488171Y677559D01*
G01X488169Y677552D02*
X488170Y677557D01*
G01X488169Y677543D02*
Y677552D01*
G01X488170Y672557D02*
X488171Y672559D01*
G01X488169Y672552D02*
X488170Y672557D01*
G01X488169Y672543D02*
Y672552D01*
G01X474744Y669640D02*
Y669632D01*
G01X474743Y669644D02*
X474744Y669640D01*
G01X474743Y669637D02*
Y669644D01*
G01X474781Y669435D02*
X474780Y669448D01*
G01X474784Y669422D02*
X474781Y669435D01*
G01X474783Y669409D02*
X474784Y669422D01*
G01X474781Y666285D02*
X474780Y666299D01*
G01X474784Y666272D02*
X474781Y666285D01*
G01X474783Y666260D02*
X474784Y666272D01*
G01X474781Y663136D02*
X474780Y663149D01*
G01X474784Y663123D02*
X474781Y663136D01*
G01X474783Y663110D02*
X474784Y663123D01*
G01X474781Y659986D02*
X474780Y660000D01*
G01X474784Y659973D02*
X474781Y659986D01*
G01X474783Y659961D02*
X474784Y659973D01*
G01X474781Y656837D02*
X474780Y656850D01*
G01X474784Y656824D02*
X474781Y656837D01*
G01X474783Y656811D02*
X474784Y656824D01*
G01X474781Y653687D02*
X474780Y653700D01*
G01X474784Y653674D02*
X474781Y653687D01*
G01X474783Y653661D02*
X474784Y653674D01*
G01X474781Y650537D02*
X474780Y650551D01*
G01X474784Y650524D02*
X474781Y650537D01*
G01X474783Y650512D02*
X474784Y650524D01*
G01X475691Y670959D02*
X475693Y670945D01*
G01X475688Y670972D02*
X475691Y670959D01*
G01X475689Y670984D02*
X475688Y670972D01*
G01X475691Y667809D02*
X475693Y667796D01*
G01X475688Y667822D02*
X475691Y667809D01*
G01X475689Y667835D02*
X475688Y667822D01*
G01X475691Y664659D02*
X475693Y664646D01*
G01X475688Y664672D02*
X475691Y664659D01*
G01X475689Y664685D02*
X475688Y664672D01*
G01X475691Y661510D02*
X475693Y661496D01*
G01X475688Y661523D02*
X475691Y661510D01*
G01X475689Y661535D02*
X475688Y661523D01*
G01X475691Y658360D02*
X475693Y658347D01*
G01X475688Y658373D02*
X475691Y658360D01*
G01X475689Y658386D02*
X475688Y658373D01*
G01X475691Y655211D02*
X475693Y655197D01*
G01X475688Y655224D02*
X475691Y655211D01*
G01X475689Y655236D02*
X475688Y655224D01*
G01X475691Y652061D02*
X475693Y652048D01*
G01X475688Y652074D02*
X475691Y652061D01*
G01X475689Y652087D02*
X475688Y652074D01*
G01X474744Y657041D02*
Y657034D01*
G01X474743Y657046D02*
X474744Y657041D01*
G01X474743Y657039D02*
Y657046D01*
G01X474744Y666490D02*
Y666483D01*
G01X474743Y666495D02*
X474744Y666490D01*
G01X474743Y666488D02*
Y666495D01*
G01X475688Y669422D02*
X475689Y669409D01*
G01X475691Y669435D02*
X475688Y669422D01*
G01X475692Y669448D02*
X475691Y669435D01*
G01X475688Y666272D02*
X475689Y666260D01*
G01X475691Y666285D02*
X475688Y666272D01*
G01X475692Y666299D02*
X475691Y666285D01*
G01X475688Y663123D02*
X475689Y663110D01*
G01X475691Y663136D02*
X475688Y663123D01*
G01X475692Y663149D02*
X475691Y663136D01*
G01X475688Y659973D02*
X475689Y659961D01*
G01X475691Y659986D02*
X475688Y659973D01*
G01X475692Y660000D02*
X475691Y659986D01*
G01X475688Y656824D02*
X475689Y656811D01*
G01X475691Y656837D02*
X475688Y656824D01*
G01X475692Y656850D02*
X475691Y656837D01*
G01X475688Y653674D02*
X475689Y653661D01*
G01X475691Y653687D02*
X475688Y653674D01*
G01X475692Y653700D02*
X475691Y653687D01*
G01X475688Y650524D02*
X475689Y650512D01*
G01X475691Y650537D02*
X475688Y650524D01*
G01X475692Y650551D02*
X475691Y650537D01*
G01X474744Y650743D02*
Y650735D01*
G01X474743Y650747D02*
X474744Y650743D01*
G01X474743Y650741D02*
Y650747D01*
G01X474757Y670779D02*
X474781Y670787D01*
G01X474746Y670765D02*
X474757Y670779D01*
G01X474744Y670758D02*
X474746Y670765D01*
G01X474757Y667630D02*
X474781Y667638D01*
G01X474746Y667615D02*
X474757Y667630D01*
G01X474744Y667608D02*
X474746Y667615D01*
G01X474757Y664480D02*
X474781Y664488D01*
G01X474746Y664465D02*
X474757Y664480D01*
G01X474744Y664459D02*
X474746Y664465D01*
G01X474757Y661330D02*
X474781Y661339D01*
G01X474746Y661316D02*
X474757Y661330D01*
G01X474744Y661309D02*
X474746Y661316D01*
G01X474757Y658181D02*
X474781Y658189D01*
G01X474746Y658166D02*
X474757Y658181D01*
G01X474744Y658159D02*
X474746Y658166D01*
G01X474757Y655031D02*
X474781Y655039D01*
G01X474746Y655017D02*
X474757Y655031D01*
G01X474744Y655010D02*
X474746Y655017D01*
G01X474757Y651881D02*
X474781Y651890D01*
G01X474746Y651867D02*
X474757Y651881D01*
G01X474744Y651860D02*
X474746Y651867D01*
G01X489154Y648904D02*
Y648911D01*
G01X489155Y648900D02*
X489154Y648904D01*
G01X489156Y648898D02*
X489155Y648900D01*
G01X489154Y673904D02*
Y673911D01*
G01X489155Y673900D02*
X489154Y673904D01*
G01X489156Y673898D02*
X489155Y673900D01*
G01X489154Y678904D02*
Y678911D01*
G01X489155Y678900D02*
X489154Y678904D01*
G01X489156Y678898D02*
X489155Y678900D01*
G01X489154Y683904D02*
Y683911D01*
G01X489155Y683900D02*
X489154Y683904D01*
G01X489156Y683898D02*
X489155Y683900D01*
G01X489154Y688904D02*
Y688911D01*
G01X489155Y688900D02*
X489154Y688904D01*
G01X489156Y688898D02*
X489155Y688900D01*
G01X474767Y653861D02*
X474781Y653858D01*
G01X474756Y653868D02*
X474767Y653861D01*
G01X474743Y653887D02*
X474756Y653868D01*
G01X474767Y663310D02*
X474781Y663307D01*
G01X474755Y663317D02*
X474767Y663310D01*
G01X474743Y663335D02*
X474755Y663317D01*
G01X474767Y657011D02*
X474781Y657008D01*
G01X474754Y657019D02*
X474767Y657011D01*
G01X474743Y657039D02*
X474754Y657019D01*
G01X474767Y666459D02*
X474781Y666457D01*
G01X474754Y666467D02*
X474767Y666459D01*
G01X474743Y666487D02*
X474754Y666467D01*
G01X475728Y650742D02*
Y650735D01*
G01Y650747D02*
Y650742D01*
G01X475727Y650748D02*
X475728Y650747D01*
G01Y653892D02*
Y653884D01*
G01Y653896D02*
Y653892D01*
G01X475727Y653898D02*
X475728Y653896D01*
G01Y657041D02*
Y657034D01*
G01Y657046D02*
Y657041D01*
G01X475727Y657047D02*
X475728Y657046D01*
G01Y660191D02*
Y660183D01*
G01Y660196D02*
Y660191D01*
G01X475727Y660197D02*
X475728Y660196D01*
G01Y663341D02*
Y663333D01*
G01Y663345D02*
Y663341D01*
G01X475727Y663346D02*
X475728Y663345D01*
G01Y666490D02*
Y666483D01*
G01Y666495D02*
Y666490D01*
G01X475727Y666496D02*
X475728Y666495D01*
G01Y669640D02*
Y669632D01*
G01Y669644D02*
Y669640D01*
G01X475727Y669646D02*
X475728Y669644D01*
G01X474767Y669609D02*
X474781Y669606D01*
G01X474754Y669617D02*
X474767Y669609D01*
G01X474743Y669637D02*
X474754Y669617D01*
G01X474766Y650712D02*
X474781Y650709D01*
G01X474753Y650720D02*
X474766Y650712D01*
G01X474743Y650741D02*
X474753Y650720D01*
G01X475728Y651871D02*
Y651864D01*
G01X475726Y651877D02*
X475728Y651871D01*
G01X475723Y651883D02*
X475726Y651877D01*
G01X475728Y655020D02*
Y655014D01*
G01X475726Y655027D02*
X475728Y655020D01*
G01X475723Y655033D02*
X475726Y655027D01*
G01X475728Y658170D02*
Y658163D01*
G01X475726Y658176D02*
X475728Y658170D01*
G01X475723Y658182D02*
X475726Y658176D01*
G01X475728Y661320D02*
Y661313D01*
G01X475726Y661326D02*
X475728Y661320D01*
G01X475723Y661332D02*
X475726Y661326D01*
G01X475728Y664469D02*
Y664463D01*
G01X475726Y664476D02*
X475728Y664469D01*
G01X475723Y664481D02*
X475726Y664476D01*
G01X475728Y667619D02*
Y667612D01*
G01X475726Y667625D02*
X475728Y667619D01*
G01X475723Y667631D02*
X475726Y667625D01*
G01X475728Y670769D02*
Y670762D01*
G01X475726Y670775D02*
X475728Y670769D01*
G01X475723Y670781D02*
X475726Y670775D01*
G01X475689Y650704D02*
X475690Y650698D01*
G01X475688Y650707D02*
X475689Y650704D01*
G01X475687Y650709D02*
X475688Y650707D01*
G01X475689Y653853D02*
X475690Y653847D01*
G01X475688Y653857D02*
X475689Y653853D01*
G01X475687Y653858D02*
X475688Y653857D01*
G01X475689Y657003D02*
X475690Y656997D01*
G01X475688Y657007D02*
X475689Y657003D01*
G01X475687Y657008D02*
X475688Y657007D01*
G01X475689Y660152D02*
X475690Y660146D01*
G01X475688Y660156D02*
X475689Y660152D01*
G01X475687Y660157D02*
X475688Y660156D01*
G01X475689Y663302D02*
X475690Y663296D01*
G01X475688Y663306D02*
X475689Y663302D01*
G01X475687Y663307D02*
X475688Y663306D01*
G01X475689Y669601D02*
X475690Y669595D01*
G01X475688Y669605D02*
X475689Y669601D01*
G01X475687Y669606D02*
X475688Y669605D01*
G01X488169Y648944D02*
Y648954D01*
G01X488170Y648939D02*
X488169Y648944D01*
G01X488171Y648937D02*
X488170Y648939D01*
G01X488169Y673944D02*
Y673954D01*
G01X488170Y673939D02*
X488169Y673944D01*
G01X488171Y673937D02*
X488170Y673939D01*
G01X488169Y678944D02*
Y678954D01*
G01X488170Y678939D02*
X488169Y678944D01*
G01X488171Y678937D02*
X488170Y678939D01*
G01X488169Y683944D02*
Y683954D01*
G01X488170Y683939D02*
X488169Y683944D01*
G01X488171Y683937D02*
X488170Y683939D01*
G01X488169Y688944D02*
Y688954D01*
G01X488170Y688939D02*
X488169Y688944D01*
G01X488171Y688937D02*
X488170Y688939D01*
G01X488169Y693944D02*
Y693954D01*
G01X488170Y693939D02*
X488169Y693944D01*
G01X488171Y693937D02*
X488170Y693939D01*
G01X489146Y649081D02*
X489154Y649055D01*
G01X489136Y649107D02*
X489146Y649081D01*
G01X489124Y649134D02*
X489136Y649107D01*
G01X489146Y674081D02*
X489154Y674055D01*
G01X489136Y674107D02*
X489146Y674081D01*
G01X489124Y674134D02*
X489136Y674107D01*
G01X489146Y679081D02*
X489154Y679055D01*
G01X489136Y679107D02*
X489146Y679081D01*
G01X489124Y679134D02*
X489136Y679107D01*
G01X489146Y684081D02*
X489154Y684055D01*
G01X489136Y684107D02*
X489146Y684081D01*
G01X489124Y684134D02*
X489136Y684107D01*
G01X489146Y689081D02*
X489154Y689055D01*
G01X489136Y689107D02*
X489146Y689081D01*
G01X489124Y689134D02*
X489136Y689107D01*
G01X489146Y694081D02*
X489154Y694055D01*
G01X489136Y694107D02*
X489146Y694081D01*
G01X489124Y694134D02*
X489136Y694107D01*
G01X474762Y660163D02*
X474781Y660157D01*
G01X474748Y660175D02*
X474762Y660163D01*
G01X474742Y660193D02*
X474748Y660175D01*
G01X489136Y648932D02*
X489117Y648937D01*
G01X489151Y648918D02*
X489136Y648932D01*
G01X489156Y648898D02*
X489151Y648918D01*
G01X489136Y673932D02*
X489117Y673937D01*
G01X489151Y673918D02*
X489136Y673932D01*
G01X489156Y673898D02*
X489151Y673918D01*
G01X489136Y678932D02*
X489117Y678937D01*
G01X489151Y678918D02*
X489136Y678932D01*
G01X489156Y678898D02*
X489151Y678918D01*
G01X489136Y683932D02*
X489117Y683937D01*
G01X489151Y683918D02*
X489136Y683932D01*
G01X489156Y683898D02*
X489151Y683918D01*
G01X489136Y688932D02*
X489117Y688937D01*
G01X489151Y688918D02*
X489136Y688932D01*
G01X489156Y688898D02*
X489151Y688918D01*
G01X489136Y693932D02*
X489117Y693937D01*
G01X489151Y693918D02*
X489136Y693932D01*
G01X489156Y693898D02*
X489151Y693918D01*
G01X475721Y658171D02*
X475713Y658180D01*
G01X475725Y658161D02*
X475721Y658171D01*
G01X475727Y658150D02*
X475725Y658161D01*
G01X475721Y651872D02*
X475713Y651880D01*
G01X475726Y651861D02*
X475721Y651872D01*
G01X475727Y651850D02*
X475726Y651861D01*
G01X475721Y655021D02*
X475713Y655030D01*
G01X475726Y655011D02*
X475721Y655021D01*
G01X475727Y655000D02*
X475726Y655011D01*
G01X475721Y661320D02*
X475713Y661329D01*
G01X475726Y661310D02*
X475721Y661320D01*
G01X475727Y661299D02*
X475726Y661310D01*
G01X475721Y664470D02*
X475713Y664479D01*
G01X475726Y664460D02*
X475721Y664470D01*
G01X475727Y664449D02*
X475726Y664460D01*
G01X475721Y667620D02*
X475713Y667628D01*
G01X475726Y667609D02*
X475721Y667620D01*
G01X475727Y667598D02*
X475726Y667609D01*
G01X475721Y670769D02*
X475713Y670778D01*
G01X475726Y670759D02*
X475721Y670769D01*
G01X475727Y670748D02*
X475726Y670759D01*
G01X475728Y670754D02*
Y670761D01*
G01Y670750D02*
Y670754D01*
G01X475727Y670748D02*
X475728Y670750D01*
G01Y667605D02*
Y667612D01*
G01Y667600D02*
Y667605D01*
G01X475727Y667598D02*
X475728Y667600D01*
G01Y664455D02*
Y664462D01*
G01Y664451D02*
Y664455D01*
G01X475727Y664449D02*
X475728Y664451D01*
G01Y661306D02*
Y661313D01*
G01Y661301D02*
Y661306D01*
G01X475727Y661299D02*
X475728Y661301D01*
G01Y658156D02*
Y658163D01*
G01Y658152D02*
Y658156D01*
G01X475727Y658150D02*
X475728Y658152D01*
G01Y655006D02*
Y655013D01*
G01Y655002D02*
Y655006D01*
G01X475727Y655000D02*
X475728Y655002D01*
G01Y651857D02*
Y651864D01*
G01Y651852D02*
Y651857D01*
G01X475727Y651850D02*
X475728Y651852D01*
G01X474744Y660191D02*
Y660183D01*
G01X474743Y660196D02*
X474744Y660191D01*
G01X474742Y660193D02*
X474743Y660196D01*
G01X474744Y653892D02*
Y653884D01*
G01X474743Y653896D02*
X474744Y653892D01*
G01X474742Y653894D02*
X474743Y653896D01*
G01X475689Y670793D02*
Y670799D01*
G01X475688Y670789D02*
X475689Y670793D01*
G01X475687Y670787D02*
X475688Y670789D01*
G01X475689Y667643D02*
Y667649D01*
G01X475688Y667639D02*
X475689Y667643D01*
G01X475687Y667638D02*
X475688Y667639D01*
G01X475689Y664493D02*
Y664500D01*
G01X475688Y664490D02*
X475689Y664493D01*
G01X475687Y664488D02*
X475688Y664490D01*
G01X475697Y658188D02*
X475687Y658189D01*
G01X475706Y658185D02*
X475697Y658188D01*
G01X475713Y658180D02*
X475706Y658185D01*
G01X475697Y651889D02*
X475687Y651890D01*
G01X475706Y651885D02*
X475697Y651889D01*
G01X475713Y651880D02*
X475706Y651885D01*
G01X475697Y655038D02*
X475687Y655039D01*
G01X475706Y655035D02*
X475697Y655038D01*
G01X475713Y655030D02*
X475706Y655035D01*
G01X475697Y661337D02*
X475687Y661339D01*
G01X475706Y661334D02*
X475697Y661337D01*
G01X475713Y661329D02*
X475706Y661334D01*
G01X475697Y664487D02*
X475687Y664488D01*
G01X475706Y664484D02*
X475697Y664487D01*
G01X475713Y664479D02*
X475706Y664484D01*
G01X475697Y667637D02*
X475687Y667638D01*
G01X475706Y667633D02*
X475697Y667637D01*
G01X475713Y667628D02*
X475706Y667633D01*
G01X475697Y670786D02*
X475687Y670787D01*
G01X475706Y670783D02*
X475697Y670786D01*
G01X475713Y670778D02*
X475706Y670783D01*
G01X474783Y650704D02*
Y650698D01*
G01X474782Y650707D02*
X474783Y650704D01*
G01X474781Y650709D02*
X474782Y650707D01*
G01X474783Y653854D02*
Y653847D01*
G01X474782Y653857D02*
X474783Y653854D01*
G01X474781Y653858D02*
X474782Y653857D01*
G01X474783Y657003D02*
Y656997D01*
G01X474782Y657007D02*
X474783Y657003D01*
G01X474781Y657008D02*
X474782Y657007D01*
G01X474783Y660153D02*
Y660146D01*
G01X474782Y660156D02*
X474783Y660153D01*
G01X474781Y660157D02*
X474782Y660156D01*
G01X474783Y663302D02*
Y663296D01*
G01X474782Y663306D02*
X474783Y663302D01*
G01X474781Y663307D02*
X474782Y663306D01*
G01X474783Y666452D02*
Y666446D01*
G01X474782Y666456D02*
X474783Y666452D01*
G01X474781Y666457D02*
X474782Y666456D01*
G01X474783Y669602D02*
Y669595D01*
G01X474782Y669605D02*
X474783Y669602D01*
G01X474781Y669606D02*
X474782Y669605D01*
G01X489154Y693904D02*
Y693911D01*
G01X489155Y693900D02*
X489154Y693904D01*
G01X489156Y693898D02*
X489155Y693900D01*
G01X475689Y661344D02*
Y661350D01*
G01X475688Y661340D02*
X475689Y661344D01*
G01X475687Y661339D02*
X475688Y661340D01*
G01X475689Y658194D02*
Y658200D01*
G01X475688Y658191D02*
X475689Y658194D01*
G01X475687Y658189D02*
X475688Y658191D01*
G01X475689Y655044D02*
Y655051D01*
G01X475688Y655041D02*
X475689Y655044D01*
G01X475687Y655039D02*
X475688Y655041D01*
G01X475689Y651895D02*
Y651901D01*
G01X475688Y651891D02*
X475689Y651895D01*
G01X475687Y651890D02*
X475688Y651891D01*
G01X489154Y692552D02*
Y692543D01*
G01X489155Y692557D02*
X489154Y692552D01*
G01X489156Y692559D02*
X489155Y692557D01*
G01X489154Y687552D02*
Y687543D01*
G01X489155Y687557D02*
X489154Y687552D01*
G01X489156Y687559D02*
X489155Y687557D01*
G01X489154Y682552D02*
Y682543D01*
G01X489155Y682557D02*
X489154Y682552D01*
G01X489156Y682559D02*
X489155Y682557D01*
G01X489154Y677552D02*
Y677543D01*
G01X489155Y677557D02*
X489154Y677552D01*
G01X489156Y677559D02*
X489155Y677557D01*
G01X489154Y672552D02*
Y672543D01*
G01X489155Y672557D02*
X489154Y672552D01*
G01X489156Y672559D02*
X489155Y672557D01*
G01X474744Y670754D02*
Y670762D01*
G01X474743Y670750D02*
X474744Y670754D01*
G01X474742Y670748D02*
X474743Y670750D01*
G01X474744Y667605D02*
Y667612D01*
G01X474743Y667600D02*
X474744Y667605D01*
G01X474742Y667598D02*
X474743Y667600D01*
G01X474744Y664455D02*
Y664463D01*
G01X474743Y664450D02*
X474744Y664455D01*
G01X474742Y664449D02*
X474743Y664450D01*
G01X474744Y661306D02*
Y661313D01*
G01X474743Y661301D02*
X474744Y661306D01*
G01X474742Y661299D02*
X474743Y661301D01*
G01X474744Y658156D02*
Y658163D01*
G01X474743Y658151D02*
X474744Y658156D01*
G01X474742Y658150D02*
X474743Y658151D01*
G01X474744Y655006D02*
Y655014D01*
G01X474743Y655002D02*
X474744Y655006D01*
G01X474742Y655000D02*
X474743Y655002D01*
G01X474744Y651857D02*
Y651864D01*
G01X474743Y651852D02*
X474744Y651857D01*
G01X474742Y651850D02*
X474743Y651852D01*
G01X474744Y653888D02*
Y653884D01*
G01X474746Y653882D02*
X474744Y653888D01*
G01X474757Y653867D02*
X474746Y653882D01*
G01X474782Y653858D02*
X474757Y653867D01*
G01X474744Y657038D02*
Y657034D01*
G01X474746Y657031D02*
X474744Y657038D01*
G01X474757Y657016D02*
X474746Y657031D01*
G01X474781Y657008D02*
X474757Y657016D01*
G01X474744Y663337D02*
Y663333D01*
G01X474746Y663331D02*
X474744Y663337D01*
G01X474757Y663315D02*
X474746Y663331D01*
G01X474781Y663307D02*
X474757Y663315D01*
G01X474744Y666487D02*
Y666483D01*
G01X474746Y666480D02*
X474744Y666487D01*
G01X474757Y666465D02*
X474746Y666480D01*
G01X474781Y666457D02*
X474757Y666465D01*
G01X474744Y650739D02*
Y650735D01*
G01X474746Y650732D02*
X474744Y650739D01*
G01X474757Y650717D02*
X474746Y650732D01*
G01X474781Y650709D02*
X474757Y650717D01*
G01X474744Y669636D02*
Y669632D01*
G01X474746Y669630D02*
X474744Y669636D01*
G01X474757Y669615D02*
X474746Y669630D01*
G01X474781Y669606D02*
X474757Y669615D01*
G01X489141Y648929D02*
X489152Y648913D01*
G01X489117Y648937D02*
X489141Y648929D01*
G01Y673929D02*
X489152Y673913D01*
G01X489117Y673937D02*
X489141Y673929D01*
G01X474744Y660187D02*
Y660183D01*
G01X474745Y660182D02*
X474744Y660187D01*
G01X474756Y660167D02*
X474745Y660182D01*
G01X474779Y660158D02*
X474756Y660167D01*
G01X475726Y669620D02*
X475728Y669632D01*
G01X475719Y669609D02*
X475726Y669620D01*
G01X475709Y669600D02*
X475719Y669609D01*
G01X475726Y663320D02*
X475728Y663333D01*
G01X475719Y663309D02*
X475726Y663320D01*
G01X475709Y663301D02*
X475719Y663309D01*
G01X475726Y660171D02*
X475728Y660183D01*
G01X475719Y660160D02*
X475726Y660171D01*
G01X475709Y660152D02*
X475719Y660160D01*
G01X475726Y657021D02*
X475728Y657034D01*
G01X475719Y657010D02*
X475726Y657021D01*
G01X475709Y657002D02*
X475719Y657010D01*
G01X475726Y653872D02*
X475728Y653884D01*
G01X475719Y653861D02*
X475726Y653872D01*
G01X475709Y653852D02*
X475719Y653861D01*
G01X475726Y650722D02*
X475728Y650735D01*
G01X475719Y650711D02*
X475726Y650722D01*
G01X475709Y650703D02*
X475719Y650711D01*
G01X474783Y670793D02*
Y670799D01*
G01Y670789D02*
Y670793D01*
G01X474781Y670787D02*
X474783Y670789D01*
G01Y667643D02*
Y667649D01*
G01Y667639D02*
Y667643D01*
G01X474781Y667638D02*
X474783Y667639D01*
G01Y664493D02*
Y664500D01*
G01Y664489D02*
Y664493D01*
G01X474781Y664488D02*
X474783Y664489D01*
G01Y661344D02*
Y661350D01*
G01Y661340D02*
Y661344D01*
G01X474781Y661339D02*
X474783Y661340D01*
G01Y658194D02*
Y658200D01*
G01Y658190D02*
Y658194D01*
G01X474781Y658189D02*
X474783Y658190D01*
G01Y655044D02*
Y655051D01*
G01Y655041D02*
Y655044D01*
G01X474781Y655039D02*
X474783Y655041D01*
G01Y651895D02*
Y651901D01*
G01Y651891D02*
Y651895D01*
G01X474781Y651890D02*
X474783Y651891D01*
G01X474745Y670768D02*
X474744Y670762D01*
G01X474746Y670774D02*
X474745Y670768D01*
G01X474749Y670780D02*
X474746Y670774D01*
G01X474753Y670785D02*
X474749Y670780D01*
G01X474758Y670790D02*
X474753Y670785D01*
G01X474763Y670794D02*
X474758Y670790D01*
G01X474745Y667619D02*
X474744Y667612D01*
G01X474746Y667625D02*
X474745Y667619D01*
G01X474749Y667630D02*
X474746Y667625D01*
G01X474753Y667636D02*
X474749Y667630D01*
G01X474758Y667640D02*
X474753Y667636D01*
G01X474763Y667644D02*
X474758Y667640D01*
G01X474745Y664469D02*
X474744Y664463D01*
G01X474746Y664475D02*
X474745Y664469D01*
G01X474749Y664481D02*
X474746Y664475D01*
G01X474753Y664486D02*
X474749Y664481D01*
G01X474758Y664491D02*
X474753Y664486D01*
G01X474763Y664494D02*
X474758Y664491D01*
G01X474745Y661319D02*
X474744Y661313D01*
G01X474746Y661326D02*
X474745Y661319D01*
G01X474749Y661331D02*
X474746Y661326D01*
G01X474753Y661337D02*
X474749Y661331D01*
G01X474758Y661341D02*
X474753Y661337D01*
G01X474763Y661345D02*
X474758Y661341D01*
G01X474745Y658170D02*
X474744Y658163D01*
G01X474746Y658176D02*
X474745Y658170D01*
G01X474749Y658181D02*
X474746Y658176D01*
G01X474753Y658187D02*
X474749Y658181D01*
G01X474758Y658191D02*
X474753Y658187D01*
G01X474763Y658195D02*
X474758Y658191D01*
G01X474745Y655020D02*
X474744Y655014D01*
G01X474746Y655026D02*
X474745Y655020D01*
G01X474749Y655032D02*
X474746Y655026D01*
G01X474753Y655037D02*
X474749Y655032D01*
G01X474758Y655042D02*
X474753Y655037D01*
G01X474763Y655046D02*
X474758Y655042D01*
G01X474745Y651870D02*
X474744Y651864D01*
G01X474746Y651877D02*
X474745Y651870D01*
G01X474749Y651882D02*
X474746Y651877D01*
G01X474753Y651888D02*
X474749Y651882D01*
G01X474758Y651892D02*
X474753Y651888D01*
G01X474763Y651896D02*
X474758Y651892D01*
G01X475719Y651888D02*
X475723Y651883D01*
G01X475714Y651893D02*
X475719Y651888D01*
G01X475708Y651896D02*
X475714Y651893D01*
G01X475702Y651899D02*
X475708Y651896D01*
G01X475696Y651901D02*
X475702Y651899D01*
G01X475689Y651901D02*
X475696D01*
G01X474745Y650727D02*
X474744Y650735D01*
G01X474747Y650720D02*
X474745Y650727D01*
G01X474751Y650714D02*
X474747Y650720D01*
G01X474756Y650708D02*
X474751Y650714D01*
G01X474762Y650704D02*
X474756Y650708D01*
G01X474769Y650700D02*
X474762Y650704D01*
G01X474776Y650698D02*
X474769Y650700D01*
G01X474783Y650698D02*
X474776D01*
G01X474745Y653877D02*
X474744Y653884D01*
G01X474747Y653870D02*
X474745Y653877D01*
G01X474751Y653864D02*
X474747Y653870D01*
G01X474756Y653858D02*
X474751Y653864D01*
G01X474762Y653853D02*
X474756Y653858D01*
G01X474769Y653850D02*
X474762Y653853D01*
G01X474776Y653848D02*
X474769Y653850D01*
G01X474783Y653847D02*
X474776Y653848D01*
G01X474745Y657026D02*
X474744Y657034D01*
G01X474747Y657020D02*
X474745Y657026D01*
G01X474751Y657013D02*
X474747Y657020D01*
G01X474756Y657007D02*
X474751Y657013D01*
G01X474762Y657003D02*
X474756Y657007D01*
G01X474769Y657000D02*
X474762Y657003D01*
G01X474776Y656998D02*
X474769Y657000D01*
G01X474783Y656997D02*
X474776Y656998D01*
G01X474745Y660176D02*
X474744Y660183D01*
G01X474747Y660169D02*
X474745Y660176D01*
G01X474751Y660163D02*
X474747Y660169D01*
G01X474756Y660157D02*
X474751Y660163D01*
G01X474762Y660152D02*
X474756Y660157D01*
G01X474769Y660149D02*
X474762Y660152D01*
G01X474776Y660147D02*
X474769Y660149D01*
G01X474783Y660146D02*
X474776Y660147D01*
G01X475698Y651889D02*
X475707Y651884D01*
G01X475687Y651890D02*
X475698Y651889D01*
G01Y655038D02*
X475707Y655034D01*
G01X475687Y655039D02*
X475698Y655038D01*
G01Y658188D02*
X475707Y658183D01*
G01X475687Y658189D02*
X475698Y658188D01*
G01Y661337D02*
X475707Y661333D01*
G01X475687Y661339D02*
X475698Y661337D01*
G01Y664487D02*
X475707Y664483D01*
G01X475687Y664488D02*
X475698Y664487D01*
G01Y667637D02*
X475707Y667632D01*
G01X475687Y667638D02*
X475698Y667637D01*
G01Y670786D02*
X475707Y670782D01*
G01X475687Y670787D02*
X475698Y670786D01*
G01X489141Y678929D02*
X489152Y678913D01*
G01X489117Y678937D02*
X489141Y678929D01*
G01Y683929D02*
X489152Y683913D01*
G01X489117Y683937D02*
X489141Y683929D01*
G01Y688929D02*
X489152Y688913D01*
G01X489117Y688937D02*
X489141Y688929D01*
G01Y693929D02*
X489152Y693913D01*
G01X489117Y693937D02*
X489141Y693929D01*
G01X475700Y669608D02*
X475687Y669606D01*
G01X475710Y669613D02*
X475700Y669608D01*
G01Y666459D02*
X475687Y666457D01*
G01X475710Y666464D02*
X475700Y666459D01*
G01Y663309D02*
X475687Y663307D01*
G01X475710Y663314D02*
X475700Y663309D01*
G01Y660159D02*
X475687Y660157D01*
G01X475710Y660165D02*
X475700Y660159D01*
G01Y657010D02*
X475687Y657008D01*
G01X475710Y657015D02*
X475700Y657010D01*
G01Y653860D02*
X475687Y653858D01*
G01X475710Y653865D02*
X475700Y653860D01*
G01Y650711D02*
X475687Y650709D01*
G01X475710Y650716D02*
X475700Y650711D01*
G01X475706Y650701D02*
X475709Y650703D01*
G01X475703Y650700D02*
X475706Y650701D01*
G01X475700Y650699D02*
X475703Y650700D01*
G01X475696Y650698D02*
X475700Y650699D01*
G01X475693Y650698D02*
X475696D01*
G01X475689D02*
X475693D01*
G01X474767Y651898D02*
X474763Y651896D01*
G01X474770Y651899D02*
X474767Y651898D01*
G01X474773Y651900D02*
X474770Y651899D01*
G01X474776Y651900D02*
X474773D01*
G01X474780Y651901D02*
X474776Y651900D01*
G01X474783Y651901D02*
X474780D01*
G01X475706Y653851D02*
X475709Y653852D01*
G01X475703Y653850D02*
X475706Y653851D01*
G01X475700Y653848D02*
X475703Y653850D01*
G01X475696Y653848D02*
X475700D01*
G01X475693Y653847D02*
X475696Y653848D01*
G01X475689Y653847D02*
X475693D01*
G01X474767Y655047D02*
X474763Y655046D01*
G01X474770Y655048D02*
X474767Y655047D01*
G01X474773Y655050D02*
X474770Y655048D01*
G01X474776Y655050D02*
X474773D01*
G01X474780Y655051D02*
X474776Y655050D01*
G01X474783Y655051D02*
X474780D01*
G01X475706Y657000D02*
X475709Y657002D01*
G01X475703Y656999D02*
X475706Y657000D01*
G01X475700Y656998D02*
X475703Y656999D01*
G01X475696Y656997D02*
X475700Y656998D01*
G01X475693Y656997D02*
X475696D01*
G01X475689D02*
X475693D01*
G01X474767Y658197D02*
X474763Y658195D01*
G01X474770Y658198D02*
X474767Y658197D01*
G01X474773Y658199D02*
X474770Y658198D01*
G01X474776Y658200D02*
X474773Y658199D01*
G01X474780Y658200D02*
X474776D01*
G01X474783D02*
X474780D01*
G01X475706Y660150D02*
X475709Y660152D01*
G01X475703Y660149D02*
X475706Y660150D01*
G01X475700Y660148D02*
X475703Y660149D01*
G01X475696Y660147D02*
X475700Y660148D01*
G01X475693Y660146D02*
X475696Y660147D01*
G01X475689Y660146D02*
X475693D01*
G01X474767Y661346D02*
X474763Y661345D01*
G01X474770Y661348D02*
X474767Y661346D01*
G01X474773Y661349D02*
X474770Y661348D01*
G01X474776Y661349D02*
X474773D01*
G01X474780Y661350D02*
X474776Y661349D01*
G01X474783Y661350D02*
X474780D01*
G01X475706Y663300D02*
X475709Y663301D01*
G01X475703Y663298D02*
X475706Y663300D01*
G01X475700Y663297D02*
X475703Y663298D01*
G01X475696Y663296D02*
X475700Y663297D01*
G01X475693Y663296D02*
X475696D01*
G01X475689D02*
X475693D01*
G01X474767Y664496D02*
X474763Y664494D01*
G01X474770Y664497D02*
X474767Y664496D01*
G01X474773Y664498D02*
X474770Y664497D01*
G01X474776Y664499D02*
X474773Y664498D01*
G01X474780Y664500D02*
X474776Y664499D01*
G01X474783Y664500D02*
X474780D01*
G01X474767Y667646D02*
X474763Y667644D01*
G01X474770Y667647D02*
X474767Y667646D01*
G01X474773Y667648D02*
X474770Y667647D01*
G01X474776Y667648D02*
X474773D01*
G01X474780Y667649D02*
X474776Y667648D01*
G01X474783Y667649D02*
X474780D01*
G01X475706Y669599D02*
X475709Y669600D01*
G01X475703Y669598D02*
X475706Y669599D01*
G01X475700Y669596D02*
X475703Y669598D01*
G01X475696Y669596D02*
X475700D01*
G01X475693Y669595D02*
X475696Y669596D01*
G01X475689Y669595D02*
X475693D01*
G01X474767Y670795D02*
X474763Y670794D01*
G01X474770Y670796D02*
X474767Y670795D01*
G01X474773Y670798D02*
X474770Y670796D01*
G01X474776Y670798D02*
X474773D01*
G01X474780Y670799D02*
X474776Y670798D01*
G01X474783Y670799D02*
X474780D01*
G01X473997Y653898D02*
X473563D01*
G01X474370D02*
X473997D01*
G01Y660197D02*
X473563D01*
G01X474370D02*
X473997D01*
G01Y663346D02*
X473563D01*
G01X474370D02*
X473997D01*
G01X475719Y655038D02*
X475723Y655033D01*
G01X475714Y655042D02*
X475719Y655038D01*
G01X475708Y655046D02*
X475714Y655042D01*
G01X475702Y655048D02*
X475708Y655046D01*
G01X475696Y655050D02*
X475702Y655048D01*
G01X475689Y655051D02*
X475696Y655050D01*
G01X475719Y658187D02*
X475723Y658182D01*
G01X475714Y658192D02*
X475719Y658187D01*
G01X475708Y658196D02*
X475714Y658192D01*
G01X475702Y658198D02*
X475708Y658196D01*
G01X475696Y658200D02*
X475702Y658198D01*
G01X475689Y658200D02*
X475696D01*
G01X475719Y661337D02*
X475723Y661332D01*
G01X475714Y661341D02*
X475719Y661337D01*
G01X475708Y661345D02*
X475714Y661341D01*
G01X475702Y661348D02*
X475708Y661345D01*
G01X475696Y661350D02*
X475702Y661348D01*
G01X475689Y661350D02*
X475696D01*
G01X475719Y664487D02*
X475723Y664481D01*
G01X475714Y664491D02*
X475719Y664487D01*
G01X475708Y664495D02*
X475714Y664491D01*
G01X475702Y664497D02*
X475708Y664495D01*
G01X475696Y664499D02*
X475702Y664497D01*
G01X475689Y664500D02*
X475696Y664499D01*
G01X475719Y667636D02*
X475723Y667631D01*
G01X475714Y667641D02*
X475719Y667636D01*
G01X475708Y667644D02*
X475714Y667641D01*
G01X475702Y667647D02*
X475708Y667644D01*
G01X475696Y667649D02*
X475702Y667647D01*
G01X475689Y667649D02*
X475696D01*
G01X475719Y670786D02*
X475723Y670781D01*
G01X475714Y670790D02*
X475719Y670786D01*
G01X475708Y670794D02*
X475714Y670790D01*
G01X475702Y670796D02*
X475708Y670794D01*
G01X475696Y670798D02*
X475702Y670796D01*
G01X475689Y670799D02*
X475696Y670798D01*
G01X474745Y663326D02*
X474744Y663333D01*
G01X474747Y663319D02*
X474745Y663326D01*
G01X474751Y663313D02*
X474747Y663319D01*
G01X474756Y663307D02*
X474751Y663313D01*
G01X474762Y663302D02*
X474756Y663307D01*
G01X474769Y663299D02*
X474762Y663302D01*
G01X474776Y663297D02*
X474769Y663299D01*
G01X474783Y663296D02*
X474776Y663297D01*
G01X474745Y666475D02*
X474744Y666483D01*
G01X474747Y666469D02*
X474745Y666475D01*
G01X474751Y666462D02*
X474747Y666469D01*
G01X474756Y666456D02*
X474751Y666462D01*
G01X474762Y666452D02*
X474756Y666456D01*
G01X474769Y666448D02*
X474762Y666452D01*
G01X474776Y666446D02*
X474769Y666448D01*
G01X474783Y666446D02*
X474776D01*
G01X474745Y669625D02*
X474744Y669632D01*
G01X474747Y669618D02*
X474745Y669625D01*
G01X474751Y669612D02*
X474747Y669618D01*
G01X474756Y669606D02*
X474751Y669612D01*
G01X474762Y669601D02*
X474756Y669606D01*
G01X474769Y669598D02*
X474762Y669601D01*
G01X474776Y669596D02*
X474769Y669598D01*
G01X474783Y669595D02*
X474776Y669596D01*
G01X474747Y651870D02*
X474742Y651850D01*
G01X474761Y651885D02*
X474747Y651870D01*
G01X474781Y651890D02*
X474761Y651885D01*
G01X474747Y655020D02*
X474742Y655000D01*
G01X474761Y655034D02*
X474747Y655020D01*
G01X474781Y655039D02*
X474761Y655034D01*
G01X474747Y658169D02*
X474742Y658150D01*
G01X474761Y658184D02*
X474747Y658169D01*
G01X474781Y658189D02*
X474761Y658184D01*
G01X474747Y661319D02*
X474742Y661299D01*
G01X474761Y661333D02*
X474747Y661319D01*
G01X474781Y661339D02*
X474761Y661333D01*
G01X475722Y650728D02*
X475727Y650748D01*
G01X475707Y650714D02*
X475722Y650728D01*
G01X475687Y650709D02*
X475707Y650714D01*
G01X475722Y653878D02*
X475727Y653898D01*
G01X475707Y653864D02*
X475722Y653878D01*
G01X475687Y653858D02*
X475707Y653864D01*
G01X475722Y657028D02*
X475727Y657047D01*
G01X475707Y657013D02*
X475722Y657028D01*
G01X475687Y657008D02*
X475707Y657013D01*
G01X475722Y660177D02*
X475727Y660197D01*
G01X475707Y660163D02*
X475722Y660177D01*
G01X475687Y660157D02*
X475707Y660163D01*
G01X475722Y663327D02*
X475727Y663346D01*
G01X475707Y663313D02*
X475722Y663327D01*
G01X475687Y663307D02*
X475707Y663313D01*
G01X475728Y666475D02*
Y666483D01*
G01X475725Y666469D02*
X475728Y666475D01*
G01X475722Y666462D02*
X475725Y666469D01*
G01X475717Y666456D02*
X475722Y666462D01*
G01X475711Y666452D02*
X475717Y666456D01*
G01X475704Y666448D02*
X475711Y666452D01*
G01X475696Y666446D02*
X475704Y666448D01*
G01X475689Y666446D02*
X475696D01*
G01X474747Y664469D02*
X474742Y664449D01*
G01X474761Y664483D02*
X474747Y664469D01*
G01X474781Y664488D02*
X474761Y664483D01*
G01X474747Y667618D02*
X474742Y667598D01*
G01X474761Y667633D02*
X474747Y667618D01*
G01X474781Y667638D02*
X474761Y667633D01*
G01X474747Y670768D02*
X474742Y670748D01*
G01X474761Y670782D02*
X474747Y670768D01*
G01X474781Y670787D02*
X474761Y670782D01*
G01X475722Y666476D02*
X475727Y666496D01*
G01X475707Y666462D02*
X475722Y666476D01*
G01X475687Y666457D02*
X475707Y666462D01*
G01X475722Y669626D02*
X475727Y669646D01*
G01X475707Y669612D02*
X475722Y669626D01*
G01X475687Y669606D02*
X475707Y669612D01*
G01X474631Y669646D02*
X474743Y669637D01*
G01X474742Y660193D02*
X474631Y660197D01*
G01X474742Y653894D02*
X474631Y653898D01*
G01X474742Y663343D02*
X474631Y663346D01*
G01X489154Y694429D02*
X488169D01*
G01X488171Y693937D02*
X493504D01*
G01Y693898D02*
X489156D01*
G01X493504Y692559D02*
X488171D01*
G01X488169Y692067D02*
X489154D01*
G01Y689429D02*
X488169D01*
G01X488171Y688937D02*
X493504D01*
G01Y688898D02*
X489156D01*
G01X493504Y687559D02*
X488171D01*
G01X488169Y687067D02*
X489154D01*
G01Y684429D02*
X488169D01*
G01X488171Y683937D02*
X493504D01*
G01Y683898D02*
X489156D01*
G01X493504Y682559D02*
X488171D01*
G01X488169Y682067D02*
X489154D01*
G01Y679429D02*
X488169D01*
G01X488171Y678937D02*
X493504D01*
G01Y678898D02*
X489156D01*
G01X493504Y677559D02*
X488171D01*
G01X488169Y677067D02*
X489154D01*
G01Y674429D02*
X488169D01*
G01X488171Y673937D02*
X493504D01*
G01Y673898D02*
X489156D01*
G01X476181Y672953D02*
X472835D01*
G01X493504Y672559D02*
X488171D01*
G01X488169Y672067D02*
X489154D01*
G01X485827Y671791D02*
X489764D01*
G01X475689Y670984D02*
X474783D01*
G01X475728Y670945D02*
X474744D01*
G01X475687Y670787D02*
X469803D01*
G01Y670748D02*
X475727D01*
G01X484646Y670610D02*
X488583D01*
G01X475727Y669646D02*
X469803D01*
G01X475687Y669606D02*
X469803D01*
G01X474744Y669449D02*
X475728D01*
G01X474783Y669409D02*
X475689D01*
G01Y667835D02*
X474783D01*
G01X475728Y667795D02*
X474744D01*
G01X475687Y667638D02*
X469803D01*
G01Y667598D02*
X475727D01*
G01Y666496D02*
X469803D01*
G01X475687Y666457D02*
X469803D01*
G01X474744Y666299D02*
X475728D01*
G01X474783Y666260D02*
X475689D01*
G01Y664685D02*
X474783D01*
G01X475728Y664646D02*
X474744D01*
G01X475687Y664488D02*
X469803D01*
G01Y664449D02*
X475727D01*
G01Y663346D02*
X469803D01*
G01X475687Y663307D02*
X469803D01*
G01X474744Y663150D02*
X475728D01*
G01X474783Y663110D02*
X475689D01*
G01Y661535D02*
X474783D01*
G01X475728Y661496D02*
X474744D01*
G01X475687Y661339D02*
X469803D01*
G01Y661299D02*
X475727D01*
G01Y660197D02*
X469803D01*
G01X475687Y660157D02*
X469803D01*
G01X474744Y660000D02*
X475728D01*
G01X474783Y659961D02*
X475689D01*
G01Y658386D02*
X474783D01*
G01X475728Y658346D02*
X474744D01*
G01X475687Y658189D02*
X469803D01*
G01Y658150D02*
X475727D01*
G01Y657047D02*
X469803D01*
G01X475687Y657008D02*
X469803D01*
G01X474744Y656850D02*
X475728D01*
G01X474783Y656811D02*
X475689D01*
G01Y655236D02*
X474783D01*
G01X475728Y655197D02*
X474744D01*
G01X475687Y655039D02*
X469803D01*
G01Y655000D02*
X475727D01*
G01Y653898D02*
X469803D01*
G01X475687Y653858D02*
X469803D01*
G01X474744Y653701D02*
X475728D01*
G01X474783Y653661D02*
X475689D01*
G01Y652087D02*
X474783D01*
G01X475728Y652047D02*
X474744D01*
G01X475687Y651890D02*
X469803D01*
G01Y651850D02*
X475727D01*
G01X488583Y650886D02*
X484646D01*
G01X475727Y650748D02*
X469803D01*
G01X475687Y650709D02*
X469803D01*
G01X474744Y650551D02*
X475728D01*
G01X474783Y650512D02*
X475689D01*
G01X489764Y649705D02*
X485827D01*
G01X489154Y649429D02*
X488169D01*
G01X488171Y648937D02*
X493504D01*
G01Y648898D02*
X489156D01*
G01X476181Y648543D02*
X472835D01*
G01X488169Y694133D02*
X489124Y694134D01*
G01X489154Y692363D02*
X488169Y692362D01*
G01Y689133D02*
X489124Y689134D01*
G01X489154Y687363D02*
X488169Y687362D01*
G01Y684133D02*
X489124Y684134D01*
G01X489154Y682363D02*
X488169Y682362D01*
G01Y679133D02*
X489124Y679134D01*
G01X489154Y677363D02*
X488169Y677362D01*
G01Y674133D02*
X489124Y674134D01*
G01X489154Y672363D02*
X488169Y672362D01*
G01Y649133D02*
X489124Y649134D01*
G01X488583Y670610D02*
X489764Y671791D01*
G01X484646Y670610D02*
X485827Y671791D01*
G01X488583Y650886D02*
X489764Y649705D01*
G01X484646Y650886D02*
X485827Y649705D01*
G01X475687Y666457D02*
X475691Y666446D01*
G01X475728Y651853D02*
Y651864D01*
G01Y655002D02*
Y655013D01*
G01Y658152D02*
Y658163D01*
G01Y661302D02*
Y661313D01*
G01Y664451D02*
Y664462D01*
G01Y667601D02*
Y667612D01*
G01Y670750D02*
Y670761D01*
G01X489154Y648911D02*
Y648920D01*
G01Y673911D02*
Y673920D01*
G01Y678911D02*
Y678920D01*
G01Y683911D02*
Y683920D01*
G01Y688911D02*
Y688920D01*
G01Y693911D02*
Y693920D01*
G01X493504Y692559D02*
Y693937D01*
G01Y687559D02*
Y688937D01*
G01Y682559D02*
Y683937D01*
G01Y677559D02*
Y678937D01*
G01Y672559D02*
Y673937D01*
G01X490335D02*
Y672559D01*
G01Y678937D02*
Y677559D01*
G01Y683937D02*
Y682559D01*
G01Y688937D02*
Y687559D01*
G01Y693937D02*
Y692559D01*
G01X489764Y671791D02*
Y649705D01*
G01X489154Y692067D02*
Y694429D01*
G01Y687067D02*
Y689429D01*
G01Y682067D02*
Y684429D01*
G01Y677067D02*
Y679429D01*
G01Y672067D02*
Y674429D01*
G01X488583Y670610D02*
Y650886D01*
G01X488169Y674429D02*
Y672067D01*
G01Y679429D02*
Y677067D01*
G01Y684429D02*
Y682067D01*
G01Y689429D02*
Y687067D01*
G01Y694429D02*
Y692067D01*
G01X485827Y748248D02*
Y671791D01*
G01X484646Y747067D02*
Y670610D01*
G01X476181Y751988D02*
Y672953D01*
G01X475728Y669449D02*
Y670945D01*
G01Y666299D02*
Y667795D01*
G01Y663150D02*
Y664646D01*
G01Y660000D02*
Y661496D01*
G01Y656850D02*
Y658346D01*
G01Y653701D02*
Y655197D01*
G01Y650551D02*
Y652047D01*
G01X475689Y650698D02*
Y650551D01*
G01Y652048D02*
Y651901D01*
G01Y656997D02*
Y656850D01*
G01Y653847D02*
Y653700D01*
G01Y655197D02*
Y655051D01*
G01Y660146D02*
Y660000D01*
G01Y661496D02*
Y661350D01*
G01Y658347D02*
Y658200D01*
G01Y666446D02*
Y666299D01*
G01Y663296D02*
Y663149D01*
G01Y664646D02*
Y664500D01*
G01Y669595D02*
Y669448D01*
G01Y670945D02*
Y670799D01*
G01Y667796D02*
Y667649D01*
G01X474783Y669448D02*
Y669595D01*
G01Y670799D02*
Y670946D01*
G01Y667649D02*
Y667796D01*
G01Y666298D02*
Y666446D01*
G01Y663149D02*
Y663296D01*
G01Y664500D02*
Y664646D01*
G01Y659999D02*
Y660146D01*
G01Y661350D02*
Y661497D01*
G01Y658200D02*
Y658347D01*
G01Y656850D02*
Y656997D01*
G01Y653700D02*
Y653847D01*
G01Y655051D02*
Y655198D01*
G01Y650550D02*
Y650698D01*
G01Y651901D02*
Y652048D01*
G01X474744Y652047D02*
Y650551D01*
G01Y655197D02*
Y653701D01*
G01Y661496D02*
Y660000D01*
G01Y658346D02*
Y656850D01*
G01Y664646D02*
Y663150D01*
G01Y670945D02*
Y669449D01*
G01Y667795D02*
Y666299D01*
G01X473563Y651890D02*
Y650709D01*
G01Y658189D02*
Y657008D01*
G01Y655039D02*
Y653858D01*
G01Y661339D02*
Y660157D01*
G01Y667638D02*
Y666457D01*
G01Y664488D02*
Y663307D01*
G01Y670787D02*
Y669606D01*
G01X473228Y672953D02*
Y648543D01*
G01X472835D02*
Y672953D01*
G01X469803Y669606D02*
Y670787D01*
G01Y666457D02*
Y667638D01*
G01Y663307D02*
Y664488D01*
G01Y660157D02*
Y661339D01*
G01Y657008D02*
Y658189D01*
G01Y653858D02*
Y655039D01*
G01Y650709D02*
Y651890D01*
G01X475728Y669632D02*
Y669643D01*
G01Y666483D02*
Y666494D01*
G01Y663333D02*
Y663344D01*
G01Y660183D02*
Y660194D01*
G01Y657034D02*
Y657045D01*
G01Y653884D02*
Y653895D01*
G01Y650735D02*
Y650746D01*
G01X489120Y699035D02*
X489124Y699134D01*
G01X489115Y698963D02*
X489120Y699035D01*
G01X489117Y698937D02*
X489115Y698963D01*
G01X489120Y704035D02*
X489124Y704134D01*
G01X489115Y703963D02*
X489120Y704035D01*
G01X489117Y703937D02*
X489115Y703963D01*
G01X489120Y709035D02*
X489124Y709134D01*
G01X489115Y708963D02*
X489120Y709035D01*
G01X489117Y708937D02*
X489115Y708963D01*
G01X489120Y714035D02*
X489124Y714134D01*
G01X489115Y713963D02*
X489120Y714035D01*
G01X489117Y713937D02*
X489115Y713963D01*
G01X489120Y719035D02*
X489124Y719134D01*
G01X489115Y718963D02*
X489120Y719035D01*
G01X489117Y718937D02*
X489115Y718963D01*
G01X489120Y724035D02*
X489124Y724134D01*
G01X489115Y723963D02*
X489120Y724035D01*
G01X489117Y723937D02*
X489115Y723963D01*
G01X489120Y729035D02*
X489124Y729134D01*
G01X489115Y728963D02*
X489120Y729035D01*
G01X489117Y728937D02*
X489115Y728963D01*
G01X489120Y734035D02*
X489124Y734134D01*
G01X489115Y733963D02*
X489120Y734035D01*
G01X489117Y733937D02*
X489115Y733963D01*
G01X489120Y739035D02*
X489124Y739134D01*
G01X489115Y738963D02*
X489120Y739035D01*
G01X489117Y738937D02*
X489115Y738963D01*
G01X489120Y744035D02*
X489124Y744134D01*
G01X489115Y743963D02*
X489120Y744035D01*
G01X489117Y743937D02*
X489115Y743963D01*
G01X488170Y742557D02*
X488171Y742559D01*
G01X488169Y742552D02*
X488170Y742557D01*
G01X488169Y742543D02*
Y742552D01*
G01X488170Y737557D02*
X488171Y737559D01*
G01X488169Y737552D02*
X488170Y737557D01*
G01X488169Y737543D02*
Y737552D01*
G01X488170Y732557D02*
X488171Y732559D01*
G01X488169Y732552D02*
X488170Y732557D01*
G01X488169Y732543D02*
Y732552D01*
G01X488170Y727557D02*
X488171Y727559D01*
G01X488169Y727552D02*
X488170Y727557D01*
G01X488169Y727543D02*
Y727552D01*
G01X488170Y722557D02*
X488171Y722559D01*
G01X488169Y722552D02*
X488170Y722557D01*
G01X488169Y722543D02*
Y722552D01*
G01X488170Y717557D02*
X488171Y717559D01*
G01X488169Y717552D02*
X488170Y717557D01*
G01X488169Y717543D02*
Y717552D01*
G01X488170Y712557D02*
X488171Y712559D01*
G01X488169Y712552D02*
X488170Y712557D01*
G01X488169Y712543D02*
Y712552D01*
G01X488170Y707557D02*
X488171Y707559D01*
G01X488169Y707552D02*
X488170Y707557D01*
G01X488169Y707543D02*
Y707552D01*
G01X488170Y702557D02*
X488171Y702559D01*
G01X488169Y702552D02*
X488170Y702557D01*
G01X488169Y702543D02*
Y702552D01*
G01X488170Y697557D02*
X488171Y697559D01*
G01X488169Y697552D02*
X488170Y697557D01*
G01X488169Y697543D02*
Y697552D01*
G01Y698944D02*
Y698954D01*
G01X488170Y698939D02*
X488169Y698944D01*
G01X488171Y698937D02*
X488170Y698939D01*
G01X488169Y703944D02*
Y703954D01*
G01X488170Y703939D02*
X488169Y703944D01*
G01X488171Y703937D02*
X488170Y703939D01*
G01X488169Y708944D02*
Y708954D01*
G01X488170Y708939D02*
X488169Y708944D01*
G01X488171Y708937D02*
X488170Y708939D01*
G01X488169Y713944D02*
Y713954D01*
G01X488170Y713939D02*
X488169Y713944D01*
G01X488171Y713937D02*
X488170Y713939D01*
G01X488169Y718944D02*
Y718954D01*
G01X488170Y718939D02*
X488169Y718944D01*
G01X488171Y718937D02*
X488170Y718939D01*
G01X488169Y723944D02*
Y723954D01*
G01X488170Y723939D02*
X488169Y723944D01*
G01X488171Y723937D02*
X488170Y723939D01*
G01X488169Y728944D02*
Y728954D01*
G01X488170Y728939D02*
X488169Y728944D01*
G01X488171Y728937D02*
X488170Y728939D01*
G01X488169Y733944D02*
Y733954D01*
G01X488170Y733939D02*
X488169Y733944D01*
G01X488171Y733937D02*
X488170Y733939D01*
G01X488169Y738944D02*
Y738954D01*
G01X488170Y738939D02*
X488169Y738944D01*
G01X488171Y738937D02*
X488170Y738939D01*
G01X488169Y743944D02*
Y743954D01*
G01X488170Y743939D02*
X488169Y743944D01*
G01X488171Y743937D02*
X488170Y743939D01*
G01X489146Y699081D02*
X489154Y699055D01*
G01X489136Y699107D02*
X489146Y699081D01*
G01X489124Y699134D02*
X489136Y699107D01*
G01X489146Y704081D02*
X489154Y704055D01*
G01X489136Y704107D02*
X489146Y704081D01*
G01X489124Y704134D02*
X489136Y704107D01*
G01X489146Y709081D02*
X489154Y709055D01*
G01X489136Y709107D02*
X489146Y709081D01*
G01X489124Y709134D02*
X489136Y709107D01*
G01X489146Y714081D02*
X489154Y714055D01*
G01X489136Y714107D02*
X489146Y714081D01*
G01X489124Y714134D02*
X489136Y714107D01*
G01X489146Y719081D02*
X489154Y719055D01*
G01X489136Y719107D02*
X489146Y719081D01*
G01X489124Y719134D02*
X489136Y719107D01*
G01X489146Y724081D02*
X489154Y724055D01*
G01X489136Y724107D02*
X489146Y724081D01*
G01X489124Y724134D02*
X489136Y724107D01*
G01X489146Y729081D02*
X489154Y729055D01*
G01X489136Y729107D02*
X489146Y729081D01*
G01X489124Y729134D02*
X489136Y729107D01*
G01X489146Y734081D02*
X489154Y734055D01*
G01X489136Y734107D02*
X489146Y734081D01*
G01X489124Y734134D02*
X489136Y734107D01*
G01X489146Y739081D02*
X489154Y739055D01*
G01X489136Y739107D02*
X489146Y739081D01*
G01X489124Y739134D02*
X489136Y739107D01*
G01X489146Y744081D02*
X489154Y744055D01*
G01X489136Y744107D02*
X489146Y744081D01*
G01X489124Y744134D02*
X489136Y744107D01*
G01Y698932D02*
X489117Y698937D01*
G01X489151Y698918D02*
X489136Y698932D01*
G01X489156Y698898D02*
X489151Y698918D01*
G01X489136Y703932D02*
X489117Y703937D01*
G01X489151Y703918D02*
X489136Y703932D01*
G01X489156Y703898D02*
X489151Y703918D01*
G01X489136Y708932D02*
X489117Y708937D01*
G01X489151Y708918D02*
X489136Y708932D01*
G01X489156Y708898D02*
X489151Y708918D01*
G01X489136Y713932D02*
X489117Y713937D01*
G01X489151Y713918D02*
X489136Y713932D01*
G01X489156Y713898D02*
X489151Y713918D01*
G01X489136Y718932D02*
X489117Y718937D01*
G01X489151Y718918D02*
X489136Y718932D01*
G01X489156Y718898D02*
X489151Y718918D01*
G01X489136Y723932D02*
X489117Y723937D01*
G01X489151Y723918D02*
X489136Y723932D01*
G01X489156Y723898D02*
X489151Y723918D01*
G01X489136Y728932D02*
X489117Y728937D01*
G01X489151Y728918D02*
X489136Y728932D01*
G01X489156Y728898D02*
X489151Y728918D01*
G01X489136Y733932D02*
X489117Y733937D01*
G01X489151Y733918D02*
X489136Y733932D01*
G01X489156Y733898D02*
X489151Y733918D01*
G01X489136Y738932D02*
X489117Y738937D01*
G01X489151Y738918D02*
X489136Y738932D01*
G01X489156Y738898D02*
X489151Y738918D01*
G01X489136Y743932D02*
X489117Y743937D01*
G01X489151Y743918D02*
X489136Y743932D01*
G01X489156Y743898D02*
X489151Y743918D01*
G01X489154Y742552D02*
Y742543D01*
G01X489155Y742557D02*
X489154Y742552D01*
G01X489156Y742559D02*
X489155Y742557D01*
G01X489154Y698904D02*
Y698911D01*
G01X489155Y698900D02*
X489154Y698904D01*
G01X489156Y698898D02*
X489155Y698900D01*
G01X489154Y703904D02*
Y703911D01*
G01X489155Y703900D02*
X489154Y703904D01*
G01X489156Y703898D02*
X489155Y703900D01*
G01X489154Y708904D02*
Y708911D01*
G01X489155Y708900D02*
X489154Y708904D01*
G01X489156Y708898D02*
X489155Y708900D01*
G01X489154Y713904D02*
Y713911D01*
G01X489155Y713900D02*
X489154Y713904D01*
G01X489156Y713898D02*
X489155Y713900D01*
G01X489154Y718904D02*
Y718911D01*
G01X489155Y718900D02*
X489154Y718904D01*
G01X489156Y718898D02*
X489155Y718900D01*
G01X489154Y723904D02*
Y723911D01*
G01X489155Y723900D02*
X489154Y723904D01*
G01X489156Y723898D02*
X489155Y723900D01*
G01X489154Y728904D02*
Y728911D01*
G01X489155Y728900D02*
X489154Y728904D01*
G01X489156Y728898D02*
X489155Y728900D01*
G01X489154Y733904D02*
Y733911D01*
G01X489155Y733900D02*
X489154Y733904D01*
G01X489156Y733898D02*
X489155Y733900D01*
G01X489154Y738904D02*
Y738911D01*
G01X489155Y738900D02*
X489154Y738904D01*
G01X489156Y738898D02*
X489155Y738900D01*
G01X489154Y743904D02*
Y743911D01*
G01X489155Y743900D02*
X489154Y743904D01*
G01X489156Y743898D02*
X489155Y743900D01*
G01X489154Y737552D02*
Y737543D01*
G01X489155Y737557D02*
X489154Y737552D01*
G01X489156Y737559D02*
X489155Y737557D01*
G01X489154Y732552D02*
Y732543D01*
G01X489155Y732557D02*
X489154Y732552D01*
G01X489156Y732559D02*
X489155Y732557D01*
G01X489154Y727552D02*
Y727543D01*
G01X489155Y727557D02*
X489154Y727552D01*
G01X489156Y727559D02*
X489155Y727557D01*
G01X489154Y722552D02*
Y722543D01*
G01X489155Y722557D02*
X489154Y722552D01*
G01X489156Y722559D02*
X489155Y722557D01*
G01X489154Y717552D02*
Y717543D01*
G01X489155Y717557D02*
X489154Y717552D01*
G01X489156Y717559D02*
X489155Y717557D01*
G01X489154Y712552D02*
Y712543D01*
G01X489155Y712557D02*
X489154Y712552D01*
G01X489156Y712559D02*
X489155Y712557D01*
G01X489154Y707552D02*
Y707543D01*
G01X489155Y707557D02*
X489154Y707552D01*
G01X489156Y707559D02*
X489155Y707557D01*
G01X489154Y702552D02*
Y702543D01*
G01X489155Y702557D02*
X489154Y702552D01*
G01X489156Y702559D02*
X489155Y702557D01*
G01X489154Y697552D02*
Y697543D01*
G01X489155Y697557D02*
X489154Y697552D01*
G01X489156Y697559D02*
X489155Y697557D01*
G01X489141Y698929D02*
X489152Y698913D01*
G01X489117Y698937D02*
X489141Y698929D01*
G01Y703929D02*
X489152Y703913D01*
G01X489117Y703937D02*
X489141Y703929D01*
G01Y708929D02*
X489152Y708913D01*
G01X489117Y708937D02*
X489141Y708929D01*
G01Y713929D02*
X489152Y713913D01*
G01X489117Y713937D02*
X489141Y713929D01*
G01Y718929D02*
X489152Y718913D01*
G01X489117Y718937D02*
X489141Y718929D01*
G01Y723929D02*
X489152Y723913D01*
G01X489117Y723937D02*
X489141Y723929D01*
G01Y728929D02*
X489152Y728913D01*
G01X489117Y728937D02*
X489141Y728929D01*
G01Y733929D02*
X489152Y733913D01*
G01X489117Y733937D02*
X489141Y733929D01*
G01Y738929D02*
X489152Y738913D01*
G01X489117Y738937D02*
X489141Y738929D01*
G01Y743929D02*
X489152Y743913D01*
G01X489117Y743937D02*
X489141Y743929D01*
G01X489154Y744429D02*
X488169D01*
G01X488171Y743937D02*
X493504D01*
G01Y743898D02*
X489156D01*
G01X493504Y742559D02*
X488171D01*
G01X488169Y742067D02*
X489154D01*
G01Y739429D02*
X488169D01*
G01X488171Y738937D02*
X493504D01*
G01Y738898D02*
X489156D01*
G01X493504Y737559D02*
X488171D01*
G01X488169Y737067D02*
X489154D01*
G01Y734429D02*
X488169D01*
G01X488171Y733937D02*
X493504D01*
G01Y733898D02*
X489156D01*
G01X493504Y732559D02*
X488171D01*
G01X488169Y732067D02*
X489154D01*
G01Y729429D02*
X488169D01*
G01X488171Y728937D02*
X493504D01*
G01Y728898D02*
X489156D01*
G01X493504Y727559D02*
X488171D01*
G01X488169Y727067D02*
X489154D01*
G01Y724429D02*
X488169D01*
G01X488171Y723937D02*
X493504D01*
G01Y723898D02*
X489156D01*
G01X493504Y722559D02*
X488171D01*
G01X488169Y722067D02*
X489154D01*
G01Y719429D02*
X488169D01*
G01X488171Y718937D02*
X493504D01*
G01Y718898D02*
X489156D01*
G01X493504Y717559D02*
X488171D01*
G01X488169Y717067D02*
X489154D01*
G01Y714429D02*
X488169D01*
G01X488171Y713937D02*
X493504D01*
G01Y713898D02*
X489156D01*
G01X493504Y712559D02*
X488171D01*
G01X488169Y712067D02*
X489154D01*
G01Y709429D02*
X488169D01*
G01X488171Y708937D02*
X493504D01*
G01Y708898D02*
X489156D01*
G01X493504Y707559D02*
X488171D01*
G01X488169Y707067D02*
X489154D01*
G01X488169Y744133D02*
X489124Y744134D01*
G01X489154Y742363D02*
X488169Y742362D01*
G01Y739133D02*
X489124Y739134D01*
G01X489154Y737363D02*
X488169Y737362D01*
G01Y734133D02*
X489124Y734134D01*
G01X489154Y732363D02*
X488169Y732362D01*
G01Y729133D02*
X489124Y729134D01*
G01X489154Y727363D02*
X488169Y727362D01*
G01Y724133D02*
X489124Y724134D01*
G01X489154Y722363D02*
X488169Y722362D01*
G01Y719133D02*
X489124Y719134D01*
G01X489154Y717363D02*
X488169Y717362D01*
G01Y714133D02*
X489124Y714134D01*
G01X489154Y712363D02*
X488169Y712362D01*
G01Y709133D02*
X489124Y709134D01*
G01X489154Y707363D02*
X488169Y707362D01*
G01X489154Y704429D02*
X488169D01*
G01X488171Y703937D02*
X493504D01*
G01Y703898D02*
X489156D01*
G01X493504Y702559D02*
X488171D01*
G01X488169Y702067D02*
X489154D01*
G01Y699429D02*
X488169D01*
G01X488171Y698937D02*
X493504D01*
G01Y698898D02*
X489156D01*
G01X493504Y697559D02*
X488171D01*
G01X488169Y697067D02*
X489154D01*
G01X488169Y704133D02*
X489124Y704134D01*
G01X489154Y702363D02*
X488169Y702362D01*
G01Y699133D02*
X489124Y699134D01*
G01X489154Y697363D02*
X488169Y697362D01*
G01X489154Y698911D02*
Y698920D01*
G01Y703911D02*
Y703920D01*
G01Y708911D02*
Y708920D01*
G01Y713911D02*
Y713920D01*
G01Y718911D02*
Y718920D01*
G01Y723911D02*
Y723920D01*
G01Y728911D02*
Y728920D01*
G01Y733911D02*
Y733920D01*
G01Y738911D02*
Y738920D01*
G01Y743911D02*
Y743920D01*
G01X493504Y742559D02*
Y743937D01*
G01Y737559D02*
Y738937D01*
G01Y732559D02*
Y733937D01*
G01Y727559D02*
Y728937D01*
G01Y722559D02*
Y723937D01*
G01Y717559D02*
Y718937D01*
G01Y712559D02*
Y713937D01*
G01Y707559D02*
Y708937D01*
G01Y702559D02*
Y703937D01*
G01Y697559D02*
Y698937D01*
G01X490335D02*
Y697559D01*
G01Y703937D02*
Y702559D01*
G01Y708937D02*
Y707559D01*
G01Y713937D02*
Y712559D01*
G01Y718937D02*
Y717559D01*
G01Y723937D02*
Y722559D01*
G01Y728937D02*
Y727559D01*
G01Y733937D02*
Y732559D01*
G01Y738937D02*
Y737559D01*
G01Y743937D02*
Y742559D01*
G01X489154Y742067D02*
Y744429D01*
G01Y737067D02*
Y739429D01*
G01Y732067D02*
Y734429D01*
G01Y727067D02*
Y729429D01*
G01Y722067D02*
Y724429D01*
G01Y717067D02*
Y719429D01*
G01Y712067D02*
Y714429D01*
G01Y707067D02*
Y709429D01*
G01Y702067D02*
Y704429D01*
G01Y697067D02*
Y699429D01*
G01X488169D02*
Y697067D01*
G01Y704429D02*
Y702067D01*
G01Y709429D02*
Y707067D01*
G01Y714429D02*
Y712067D01*
G01Y719429D02*
Y717067D01*
G01Y724429D02*
Y722067D01*
G01Y729429D02*
Y727067D01*
G01Y734429D02*
Y732067D01*
G01Y739429D02*
Y737067D01*
G01Y744429D02*
Y742067D01*
G01X487598Y769429D02*
G03X487008Y770020I-590J1D01*
G01X484843Y766280D02*
G03Y768248I0J984D01*
G01X494488Y768839D02*
G03X492520Y770807I-1968J0D01*
G01X480315Y770020D02*
G03X479724Y769429I0J-591D01*
G01X482480Y768248D02*
G03Y766280I0J-984D01*
G01X474803Y770807D02*
G03X472835Y768839I0J-1968D01*
G01X481102Y760335D02*
G03X479921Y759154I0J-1181D01*
G01X487402D02*
G03X486220Y760335I-1181J0D01*
G01X485551Y755059D02*
G03I-1890J0D01*
G01X486024D02*
G03I-2363J0D01*
G01X492520Y770807D02*
X474803D01*
G01X487008Y770020D02*
X480315D01*
G01X484843Y768248D02*
X482480D01*
G01Y766280D02*
X484843D01*
G01X487598Y764902D02*
X479724D01*
G01Y763327D02*
X487598D01*
G01X494488Y760374D02*
X472835D01*
G01X481102Y760335D02*
X486220D01*
G01X482480Y755650D02*
X484843D01*
G01X482480Y753957D02*
X484843D01*
G01X476181Y751988D02*
X490551D01*
G01X476181Y750610D02*
X479921D01*
G01X490551D02*
X487402D01*
G01X476181Y749744D02*
X491142D01*
G01X477953Y748248D02*
X485827D01*
G01X479134Y747067D02*
X484646D01*
G01X494488Y753091D02*
X491142Y749744D01*
G01X484646Y747067D02*
X485827Y748248D01*
G01X484843Y753957D02*
X486146Y751988D01*
G01X477953Y748248D02*
X479134Y747067D01*
G01X472835Y753091D02*
X476181Y749744D01*
G01X481177Y751988D02*
X482480Y753957D01*
G01X487153Y759879D02*
X484843Y755650D01*
G01X482480D02*
X480170Y759879D01*
G01X494488Y753091D02*
Y768839D01*
G01X487598Y763327D02*
Y769429D01*
G01X487402Y759154D02*
Y750610D01*
G01X484843Y755650D02*
Y753957D01*
G01X482480D02*
Y755650D01*
G01X479921Y750610D02*
Y759154D01*
G01X479724Y763327D02*
Y769429D01*
G01X472835Y768839D02*
Y753091D01*
G01X483169Y829921D02*
G03X523327I20079J0D01*
G01D02*
G03X483169I-20079J0D01*
G01X523327D02*
G03I-20079J0D01*
G01X489154Y1080308D02*
Y1080299D01*
G01X489155Y1080313D02*
X489154Y1080308D01*
G01X489156Y1080315D02*
X489155Y1080313D01*
G01X489154Y1075308D02*
Y1075299D01*
G01X489155Y1075313D02*
X489154Y1075308D01*
G01X489156Y1075315D02*
X489155Y1075313D01*
G01X489154Y1070308D02*
Y1070299D01*
G01X489155Y1070313D02*
X489154Y1070308D01*
G01X489156Y1070315D02*
X489155Y1070313D01*
G01X489120Y1071791D02*
X489124Y1071890D01*
G01X489115Y1071719D02*
X489120Y1071791D01*
G01X489117Y1071693D02*
X489115Y1071719D01*
G01X489120Y1076791D02*
X489124Y1076890D01*
G01X489115Y1076719D02*
X489120Y1076791D01*
G01X489117Y1076693D02*
X489115Y1076719D01*
G01X489120Y1081791D02*
X489124Y1081890D01*
G01X489115Y1081719D02*
X489120Y1081791D01*
G01X489117Y1081693D02*
X489115Y1081719D01*
G01X488170Y1080313D02*
X488171Y1080315D01*
G01X488169Y1080308D02*
X488170Y1080313D01*
G01X488169Y1080299D02*
Y1080308D01*
G01X488170Y1075313D02*
X488171Y1075315D01*
G01X488169Y1075308D02*
X488170Y1075313D01*
G01X488169Y1075299D02*
Y1075308D01*
G01X488170Y1070313D02*
X488171Y1070315D01*
G01X488169Y1070308D02*
X488170Y1070313D01*
G01X488169Y1070299D02*
Y1070308D01*
G01X489136Y1071688D02*
X489117Y1071693D01*
G01X489151Y1071674D02*
X489136Y1071688D01*
G01X489156Y1071654D02*
X489151Y1071674D01*
G01X489136Y1076688D02*
X489117Y1076693D01*
G01X489151Y1076674D02*
X489136Y1076688D01*
G01X489156Y1076654D02*
X489151Y1076674D01*
G01X489136Y1081688D02*
X489117Y1081693D01*
G01X489151Y1081674D02*
X489136Y1081688D01*
G01X489156Y1081654D02*
X489151Y1081674D01*
G01X488169Y1071700D02*
Y1071709D01*
G01X488170Y1071695D02*
X488169Y1071700D01*
G01X488171Y1071693D02*
X488170Y1071695D01*
G01X488169Y1076700D02*
Y1076709D01*
G01X488170Y1076695D02*
X488169Y1076700D01*
G01X488171Y1076693D02*
X488170Y1076695D01*
G01X488169Y1081700D02*
Y1081709D01*
G01X488170Y1081695D02*
X488169Y1081700D01*
G01X488171Y1081693D02*
X488170Y1081695D01*
G01X489146Y1071837D02*
X489154Y1071811D01*
G01X489136Y1071863D02*
X489146Y1071837D01*
G01X489124Y1071890D02*
X489136Y1071863D01*
G01X489146Y1076837D02*
X489154Y1076811D01*
G01X489136Y1076863D02*
X489146Y1076837D01*
G01X489124Y1076890D02*
X489136Y1076863D01*
G01X489146Y1081837D02*
X489154Y1081811D01*
G01X489136Y1081863D02*
X489146Y1081837D01*
G01X489124Y1081890D02*
X489136Y1081863D01*
G01X489154Y1071660D02*
Y1071667D01*
G01X489155Y1071656D02*
X489154Y1071660D01*
G01X489156Y1071654D02*
X489155Y1071656D01*
G01X489154Y1076660D02*
Y1076667D01*
G01X489155Y1076656D02*
X489154Y1076660D01*
G01X489156Y1076654D02*
X489155Y1076656D01*
G01X489154Y1081660D02*
Y1081667D01*
G01X489155Y1081656D02*
X489154Y1081660D01*
G01X489156Y1081654D02*
X489155Y1081656D01*
G01X489141Y1071685D02*
X489152Y1071669D01*
G01X489117Y1071693D02*
X489141Y1071685D01*
G01Y1076685D02*
X489152Y1076669D01*
G01X489117Y1076693D02*
X489141Y1076685D01*
G01Y1081685D02*
X489152Y1081669D01*
G01X489117Y1081693D02*
X489141Y1081685D01*
G01X487008Y1044232D02*
G03X487598Y1044823I-1J591D01*
G01X484843Y1046004D02*
G03Y1047972I0J984D01*
G01X484764Y1059193D02*
G03I-1103J0D01*
G01X486220Y1053917D02*
G03X487402Y1055098I1J1181D01*
G01X485236Y1059193D02*
G03I-1575J0D01*
G01X492520Y1043445D02*
G03X494488Y1045413I0J1968D01*
G01X479724Y1044823D02*
G03X480315Y1044232I591J0D01*
G01X482480Y1047972D02*
G03Y1046004I0J-984D01*
G01X479921Y1055098D02*
G03X481102Y1053917I1181J0D01*
G01X472835Y1045413D02*
G03X474803Y1043445I1968J0D01*
G01X489154Y1082185D02*
X488169D01*
G01X488171Y1081693D02*
X493504D01*
G01Y1081654D02*
X489156D01*
G01X493504Y1080315D02*
X488171D01*
G01X488169Y1079823D02*
X489154D01*
G01Y1077185D02*
X488169D01*
G01X488171Y1076693D02*
X493504D01*
G01Y1076654D02*
X489156D01*
G01X493504Y1075315D02*
X488171D01*
G01X488169Y1074823D02*
X489154D01*
G01Y1072185D02*
X488169D01*
G01X488171Y1071693D02*
X493504D01*
G01Y1071654D02*
X489156D01*
G01X493504Y1070315D02*
X488171D01*
G01X488169Y1069823D02*
X489154D01*
G01X484646Y1067185D02*
X479134D01*
G01X485827Y1066004D02*
X477953D01*
G01X491142Y1064508D02*
X476181D01*
G01X488169Y1081889D02*
X489124Y1081890D01*
G01X489154Y1080119D02*
X488169Y1080118D01*
G01Y1076889D02*
X489124Y1076890D01*
G01X489154Y1075119D02*
X488169Y1075118D01*
G01Y1071889D02*
X489124Y1071890D01*
G01X489154Y1070119D02*
X488169Y1070118D01*
G01X487402Y1063642D02*
X490551D01*
G01X479921D02*
X476181D01*
G01Y1062264D02*
X490551D01*
G01X484843Y1060295D02*
X482480D01*
G01X484843Y1058602D02*
X482480D01*
G01X486220Y1053917D02*
X481102D01*
G01X494488Y1053878D02*
X472835D01*
G01X487598Y1050925D02*
X479724D01*
G01Y1049350D02*
X487598D01*
G01X484843Y1047972D02*
X482480D01*
G01Y1046004D02*
X484843D01*
G01X487008Y1044232D02*
X480315D01*
G01X492520Y1043445D02*
X474803D01*
G01X491142Y1064508D02*
X494488Y1061161D01*
G01X484646Y1067185D02*
X485827Y1066004D01*
G01X482480Y1060295D02*
X481177Y1062264D01*
G01X484843Y1058602D02*
X487153Y1054373D01*
G01X489154Y1071667D02*
Y1071676D01*
G01Y1076667D02*
Y1076676D01*
G01Y1081667D02*
Y1081676D01*
G01X494488Y1045413D02*
Y1061161D01*
G01X493504Y1080315D02*
Y1081693D01*
G01Y1075315D02*
Y1076693D01*
G01Y1070315D02*
Y1071693D01*
G01X491142Y1202500D02*
Y1064508D01*
G01X490551Y1204744D02*
Y1062264D01*
G01X490335Y1071693D02*
Y1070315D01*
G01Y1076693D02*
Y1075315D01*
G01Y1081693D02*
Y1080315D01*
G01X489154Y1079823D02*
Y1082185D01*
G01Y1074823D02*
Y1077185D01*
G01Y1069823D02*
Y1072185D01*
G01Y1071667D02*
Y1071811D01*
G01Y1076667D02*
Y1076811D01*
G01Y1081667D02*
Y1081811D01*
G01X488169Y1072185D02*
Y1069823D01*
G01Y1077185D02*
Y1074823D01*
G01Y1082185D02*
Y1079823D01*
G01X487598Y1050925D02*
Y1044823D01*
G01X487402Y1063642D02*
Y1055098D01*
G01X485827Y1102461D02*
Y1066004D01*
G01X484843Y1060295D02*
Y1058602D01*
G01X484646Y1103642D02*
Y1067185D01*
G01X482480Y1058602D02*
Y1060295D01*
G01X479921Y1055098D02*
Y1063642D01*
G01X479724Y1050925D02*
Y1044823D01*
G01X479134Y1067185D02*
Y1199823D01*
G01X477953Y1066004D02*
Y1201004D01*
G01X476181Y1101299D02*
Y1062264D01*
G01X472835Y1061161D02*
Y1045413D01*
G01X479134Y1067185D02*
X477953Y1066004D01*
G01X476181Y1064508D02*
X472835Y1061161D01*
G01X486146Y1062264D02*
X484843Y1060295D01*
G01X480170Y1054373D02*
X482480Y1058602D01*
G01X474757Y1123535D02*
X474781Y1123543D01*
G01X474746Y1123520D02*
X474757Y1123535D01*
G01X474744Y1123514D02*
X474746Y1123520D01*
G01X474757Y1120385D02*
X474781Y1120394D01*
G01X474746Y1120371D02*
X474757Y1120385D01*
G01X474744Y1120364D02*
X474746Y1120371D01*
G01X474757Y1117236D02*
X474781Y1117244D01*
G01X474746Y1117221D02*
X474757Y1117236D01*
G01X474744Y1117215D02*
X474746Y1117221D01*
G01X474757Y1114086D02*
X474781Y1114094D01*
G01X474746Y1114072D02*
X474757Y1114086D01*
G01X474744Y1114065D02*
X474746Y1114072D01*
G01X474757Y1110937D02*
X474781Y1110945D01*
G01X474746Y1110922D02*
X474757Y1110937D01*
G01X474744Y1110915D02*
X474746Y1110922D01*
G01X474757Y1107787D02*
X474781Y1107795D01*
G01X474746Y1107772D02*
X474757Y1107787D01*
G01X474744Y1107766D02*
X474746Y1107772D01*
G01X474757Y1104637D02*
X474781Y1104646D01*
G01X474746Y1104623D02*
X474757Y1104637D01*
G01X474744Y1104616D02*
X474746Y1104623D01*
G01X475728Y1123510D02*
Y1123517D01*
G01Y1123506D02*
Y1123510D01*
G01X475727Y1123504D02*
X475728Y1123506D01*
G01Y1120361D02*
Y1120368D01*
G01Y1120356D02*
Y1120361D01*
G01X475727Y1120354D02*
X475728Y1120356D01*
G01Y1117211D02*
Y1117218D01*
G01Y1117207D02*
Y1117211D01*
G01X475727Y1117205D02*
X475728Y1117207D01*
G01Y1114061D02*
Y1114069D01*
G01Y1114057D02*
Y1114061D01*
G01X475727Y1114055D02*
X475728Y1114057D01*
G01Y1110912D02*
Y1110919D01*
G01Y1110907D02*
Y1110912D01*
G01X475727Y1110906D02*
X475728Y1110907D01*
G01Y1107762D02*
Y1107769D01*
G01Y1107758D02*
Y1107762D01*
G01X475727Y1107756D02*
X475728Y1107758D01*
G01Y1104613D02*
Y1104620D01*
G01Y1104608D02*
Y1104613D01*
G01X475727Y1104606D02*
X475728Y1104608D01*
G01X474744Y1112947D02*
Y1112939D01*
G01X474743Y1112952D02*
X474744Y1112947D01*
G01X474742Y1112949D02*
X474743Y1112952D01*
G01X474744Y1106648D02*
Y1106640D01*
G01X474743Y1106652D02*
X474744Y1106648D01*
G01X474742Y1106650D02*
X474743Y1106652D01*
G01X475689Y1123548D02*
Y1123555D01*
G01X475688Y1123545D02*
X475689Y1123548D01*
G01X475687Y1123543D02*
X475688Y1123545D01*
G01X475689Y1120399D02*
Y1120405D01*
G01X475688Y1120395D02*
X475689Y1120399D01*
G01X475687Y1120394D02*
X475688Y1120395D01*
G01X475689Y1117249D02*
Y1117256D01*
G01X475688Y1117246D02*
X475689Y1117249D01*
G01X475687Y1117244D02*
X475688Y1117246D01*
G01X475689Y1114100D02*
Y1114106D01*
G01X475688Y1114096D02*
X475689Y1114100D01*
G01X475687Y1114094D02*
X475688Y1114096D01*
G01X475689Y1110950D02*
Y1110956D01*
G01X475688Y1110946D02*
X475689Y1110950D01*
G01X475687Y1110945D02*
X475688Y1110946D01*
G01X475689Y1107800D02*
Y1107807D01*
G01X475688Y1107797D02*
X475689Y1107800D01*
G01X475687Y1107795D02*
X475688Y1107797D01*
G01X475689Y1104651D02*
Y1104657D01*
G01X475688Y1104647D02*
X475689Y1104651D01*
G01X475687Y1104646D02*
X475688Y1104647D01*
G01X489154Y1130308D02*
Y1130299D01*
G01X489155Y1130313D02*
X489154Y1130308D01*
G01X489156Y1130315D02*
X489155Y1130313D01*
G01X489154Y1125308D02*
Y1125299D01*
G01X489155Y1125313D02*
X489154Y1125308D01*
G01X489156Y1125315D02*
X489155Y1125313D01*
G01X489154Y1100308D02*
Y1100299D01*
G01X489155Y1100313D02*
X489154Y1100308D01*
G01X489156Y1100315D02*
X489155Y1100313D01*
G01X489154Y1095308D02*
Y1095299D01*
G01X489155Y1095313D02*
X489154Y1095308D01*
G01X489156Y1095315D02*
X489155Y1095313D01*
G01X489154Y1090308D02*
Y1090299D01*
G01X489155Y1090313D02*
X489154Y1090308D01*
G01X489156Y1090315D02*
X489155Y1090313D01*
G01X489154Y1085308D02*
Y1085299D01*
G01X489155Y1085313D02*
X489154Y1085308D01*
G01X489156Y1085315D02*
X489155Y1085313D01*
G01X474744Y1123510D02*
Y1123518D01*
G01X474743Y1123506D02*
X474744Y1123510D01*
G01X474742Y1123504D02*
X474743Y1123506D01*
G01X474744Y1120361D02*
Y1120368D01*
G01X474743Y1120356D02*
X474744Y1120361D01*
G01X474742Y1120354D02*
X474743Y1120356D01*
G01X474744Y1117211D02*
Y1117219D01*
G01X474743Y1117206D02*
X474744Y1117211D01*
G01X474742Y1117205D02*
X474743Y1117206D01*
G01X474744Y1114061D02*
Y1114069D01*
G01X474743Y1114057D02*
X474744Y1114061D01*
G01X474742Y1114055D02*
X474743Y1114057D01*
G01X474744Y1110912D02*
Y1110919D01*
G01X474743Y1110907D02*
X474744Y1110912D01*
G01X474742Y1110906D02*
X474743Y1110907D01*
G01X474744Y1107762D02*
Y1107770D01*
G01X474743Y1107757D02*
X474744Y1107762D01*
G01X474742Y1107756D02*
X474743Y1107757D01*
G01X474744Y1104613D02*
Y1104620D01*
G01X474743Y1104608D02*
X474744Y1104613D01*
G01X474742Y1104606D02*
X474743Y1104608D01*
G01X475726Y1122376D02*
X475728Y1122388D01*
G01X475719Y1122365D02*
X475726Y1122376D01*
G01X475709Y1122356D02*
X475719Y1122365D01*
G01X475726Y1116076D02*
X475728Y1116089D01*
G01X475719Y1116065D02*
X475726Y1116076D01*
G01X475709Y1116057D02*
X475719Y1116065D01*
G01X475726Y1112927D02*
X475728Y1112939D01*
G01X475719Y1112916D02*
X475726Y1112927D01*
G01X475709Y1112907D02*
X475719Y1112916D01*
G01X475726Y1109777D02*
X475728Y1109790D01*
G01X475719Y1109766D02*
X475726Y1109777D01*
G01X475709Y1109758D02*
X475719Y1109766D01*
G01X475726Y1106628D02*
X475728Y1106640D01*
G01X475719Y1106617D02*
X475726Y1106628D01*
G01X475709Y1106608D02*
X475719Y1106617D01*
G01X475726Y1103478D02*
X475728Y1103491D01*
G01X475719Y1103467D02*
X475726Y1103478D01*
G01X475709Y1103459D02*
X475719Y1103467D01*
G01X474783Y1123548D02*
Y1123555D01*
G01Y1123544D02*
Y1123548D01*
G01X474781Y1123543D02*
X474783Y1123544D01*
G01Y1120399D02*
Y1120405D01*
G01Y1120395D02*
Y1120399D01*
G01X474781Y1120394D02*
X474783Y1120395D01*
G01Y1117249D02*
Y1117256D01*
G01Y1117245D02*
Y1117249D01*
G01X474781Y1117244D02*
X474783Y1117245D01*
G01Y1114100D02*
Y1114106D01*
G01Y1114096D02*
Y1114100D01*
G01X474781Y1114094D02*
X474783Y1114096D01*
G01Y1110950D02*
Y1110956D01*
G01Y1110946D02*
Y1110950D01*
G01X474781Y1110945D02*
X474783Y1110946D01*
G01Y1107800D02*
Y1107807D01*
G01Y1107796D02*
Y1107800D01*
G01X474781Y1107795D02*
X474783Y1107796D01*
G01Y1104651D02*
Y1104657D01*
G01Y1104647D02*
Y1104651D01*
G01X474781Y1104646D02*
X474783Y1104647D01*
G01X474745Y1123524D02*
X474744Y1123518D01*
G01X474746Y1123530D02*
X474745Y1123524D01*
G01X474749Y1123536D02*
X474746Y1123530D01*
G01X474753Y1123541D02*
X474749Y1123536D01*
G01X474758Y1123546D02*
X474753Y1123541D01*
G01X474763Y1123550D02*
X474758Y1123546D01*
G01X474745Y1120374D02*
X474744Y1120368D01*
G01X474746Y1120381D02*
X474745Y1120374D01*
G01X474749Y1120386D02*
X474746Y1120381D01*
G01X474753Y1120392D02*
X474749Y1120386D01*
G01X474758Y1120396D02*
X474753Y1120392D01*
G01X474763Y1120400D02*
X474758Y1120396D01*
G01X474745Y1117225D02*
X474744Y1117219D01*
G01X474746Y1117231D02*
X474745Y1117225D01*
G01X474749Y1117237D02*
X474746Y1117231D01*
G01X474753Y1117242D02*
X474749Y1117237D01*
G01X474758Y1117246D02*
X474753Y1117242D01*
G01X474763Y1117250D02*
X474758Y1117246D01*
G01X474745Y1114075D02*
X474744Y1114069D01*
G01X474746Y1114081D02*
X474745Y1114075D01*
G01X474749Y1114087D02*
X474746Y1114081D01*
G01X474753Y1114093D02*
X474749Y1114087D01*
G01X474758Y1114097D02*
X474753Y1114093D01*
G01X474763Y1114101D02*
X474758Y1114097D01*
G01X474745Y1110926D02*
X474744Y1110919D01*
G01X474746Y1110932D02*
X474745Y1110926D01*
G01X474749Y1110937D02*
X474746Y1110932D01*
G01X474753Y1110943D02*
X474749Y1110937D01*
G01X474758Y1110947D02*
X474753Y1110943D01*
G01X474763Y1110951D02*
X474758Y1110947D01*
G01X474745Y1107776D02*
X474744Y1107770D01*
G01X474746Y1107782D02*
X474745Y1107776D01*
G01X474749Y1107788D02*
X474746Y1107782D01*
G01X474753Y1107793D02*
X474749Y1107788D01*
G01X474758Y1107798D02*
X474753Y1107793D01*
G01X474763Y1107802D02*
X474758Y1107798D01*
G01X474745Y1104626D02*
X474744Y1104620D01*
G01X474746Y1104633D02*
X474745Y1104626D01*
G01X474749Y1104638D02*
X474746Y1104633D01*
G01X474753Y1104644D02*
X474749Y1104638D01*
G01X474758Y1104648D02*
X474753Y1104644D01*
G01X474763Y1104652D02*
X474758Y1104648D01*
G01X489120Y1086791D02*
X489124Y1086890D01*
G01X489115Y1086719D02*
X489120Y1086791D01*
G01X489117Y1086693D02*
X489115Y1086719D01*
G01X489120Y1091791D02*
X489124Y1091890D01*
G01X489115Y1091719D02*
X489120Y1091791D01*
G01X489117Y1091693D02*
X489115Y1091719D01*
G01X489120Y1096791D02*
X489124Y1096890D01*
G01X489115Y1096719D02*
X489120Y1096791D01*
G01X489117Y1096693D02*
X489115Y1096719D01*
G01X489120Y1101791D02*
X489124Y1101890D01*
G01X489115Y1101719D02*
X489120Y1101791D01*
G01X489117Y1101693D02*
X489115Y1101719D01*
G01X489120Y1126791D02*
X489124Y1126890D01*
G01X489115Y1126719D02*
X489120Y1126791D01*
G01X489117Y1126693D02*
X489115Y1126719D01*
G01X474744Y1116096D02*
Y1116089D01*
G01X474743Y1116101D02*
X474744Y1116096D01*
G01X474743Y1116092D02*
Y1116101D01*
G01X474784Y1123728D02*
X474783Y1123740D01*
G01X474781Y1123715D02*
X474784Y1123728D01*
G01X474781Y1123701D02*
Y1123715D01*
G01X474784Y1120578D02*
X474783Y1120591D01*
G01X474781Y1120565D02*
X474784Y1120578D01*
G01X474781Y1120552D02*
Y1120565D01*
G01X474784Y1117429D02*
X474783Y1117441D01*
G01X474781Y1117416D02*
X474784Y1117429D01*
G01X474781Y1117402D02*
Y1117416D01*
G01X474784Y1114279D02*
X474783Y1114291D01*
G01X474781Y1114266D02*
X474784Y1114279D01*
G01X474781Y1114252D02*
Y1114266D01*
G01X474784Y1111130D02*
X474783Y1111142D01*
G01X474781Y1111117D02*
X474784Y1111130D01*
G01X474781Y1111103D02*
Y1111117D01*
G01X474784Y1107980D02*
X474783Y1107992D01*
G01X474781Y1107967D02*
X474784Y1107980D01*
G01X474781Y1107953D02*
Y1107967D01*
G01X474784Y1104830D02*
X474783Y1104843D01*
G01X474781Y1104817D02*
X474784Y1104830D01*
G01X474781Y1104804D02*
Y1104817D01*
G01X488170Y1130313D02*
X488171Y1130315D01*
G01X488169Y1130308D02*
X488170Y1130313D01*
G01X488169Y1130299D02*
Y1130308D01*
G01X488170Y1125313D02*
X488171Y1125315D01*
G01X488169Y1125308D02*
X488170Y1125313D01*
G01X488169Y1125299D02*
Y1125308D01*
G01X488170Y1100313D02*
X488171Y1100315D01*
G01X488169Y1100308D02*
X488170Y1100313D01*
G01X488169Y1100299D02*
Y1100308D01*
G01X488170Y1095313D02*
X488171Y1095315D01*
G01X488169Y1095308D02*
X488170Y1095313D01*
G01X488169Y1095299D02*
Y1095308D01*
G01X488170Y1090313D02*
X488171Y1090315D01*
G01X488169Y1090308D02*
X488170Y1090313D01*
G01X488169Y1090299D02*
Y1090308D01*
G01X488170Y1085313D02*
X488171Y1085315D01*
G01X488169Y1085308D02*
X488170Y1085313D01*
G01X488169Y1085299D02*
Y1085308D01*
G01X474744Y1122396D02*
Y1122388D01*
G01X474743Y1122400D02*
X474744Y1122396D01*
G01X474743Y1122393D02*
Y1122400D01*
G01X474781Y1122191D02*
X474780Y1122204D01*
G01X474784Y1122178D02*
X474781Y1122191D01*
G01X474783Y1122165D02*
X474784Y1122178D01*
G01X474781Y1119041D02*
X474780Y1119055D01*
G01X474784Y1119028D02*
X474781Y1119041D01*
G01X474783Y1119016D02*
X474784Y1119028D01*
G01X474781Y1115892D02*
X474780Y1115905D01*
G01X474784Y1115879D02*
X474781Y1115892D01*
G01X474783Y1115866D02*
X474784Y1115879D01*
G01X474781Y1112742D02*
X474780Y1112756D01*
G01X474784Y1112729D02*
X474781Y1112742D01*
G01X474783Y1112717D02*
X474784Y1112729D01*
G01X474781Y1109593D02*
X474780Y1109606D01*
G01X474784Y1109580D02*
X474781Y1109593D01*
G01X474783Y1109567D02*
X474784Y1109580D01*
G01X474781Y1106443D02*
X474780Y1106456D01*
G01X474784Y1106430D02*
X474781Y1106443D01*
G01X474783Y1106417D02*
X474784Y1106430D01*
G01X474781Y1103293D02*
X474780Y1103307D01*
G01X474784Y1103280D02*
X474781Y1103293D01*
G01X474783Y1103268D02*
X474784Y1103280D01*
G01X475691Y1123715D02*
X475693Y1123701D01*
G01X475688Y1123728D02*
X475691Y1123715D01*
G01X475689Y1123740D02*
X475688Y1123728D01*
G01X475691Y1120565D02*
X475693Y1120552D01*
G01X475688Y1120578D02*
X475691Y1120565D01*
G01X475689Y1120591D02*
X475688Y1120578D01*
G01X475691Y1117415D02*
X475693Y1117402D01*
G01X475688Y1117428D02*
X475691Y1117415D01*
G01X475689Y1117441D02*
X475688Y1117428D01*
G01X475691Y1114266D02*
X475693Y1114252D01*
G01X475688Y1114279D02*
X475691Y1114266D01*
G01X475689Y1114291D02*
X475688Y1114279D01*
G01X475691Y1111116D02*
X475693Y1111103D01*
G01X475688Y1111129D02*
X475691Y1111116D01*
G01X475689Y1111142D02*
X475688Y1111129D01*
G01X475691Y1107967D02*
X475693Y1107953D01*
G01X475688Y1107980D02*
X475691Y1107967D01*
G01X475689Y1107992D02*
X475688Y1107980D01*
G01X475691Y1104817D02*
X475693Y1104804D01*
G01X475688Y1104830D02*
X475691Y1104817D01*
G01X475689Y1104843D02*
X475688Y1104830D01*
G01X474744Y1109797D02*
Y1109790D01*
G01X474743Y1109802D02*
X474744Y1109797D01*
G01X474743Y1109795D02*
Y1109802D01*
G01X474744Y1119246D02*
Y1119239D01*
G01X474743Y1119251D02*
X474744Y1119246D01*
G01X474743Y1119244D02*
Y1119251D01*
G01X475688Y1122178D02*
X475689Y1122165D01*
G01X475691Y1122191D02*
X475688Y1122178D01*
G01X475692Y1122204D02*
X475691Y1122191D01*
G01X475688Y1119028D02*
X475689Y1119016D01*
G01X475691Y1119041D02*
X475688Y1119028D01*
G01X475692Y1119055D02*
X475691Y1119041D01*
G01X475688Y1115879D02*
X475689Y1115866D01*
G01X475691Y1115892D02*
X475688Y1115879D01*
G01X475692Y1115905D02*
X475691Y1115892D01*
G01X475688Y1112729D02*
X475689Y1112717D01*
G01X475691Y1112742D02*
X475688Y1112729D01*
G01X475692Y1112756D02*
X475691Y1112742D01*
G01X475688Y1109580D02*
X475689Y1109567D01*
G01X475691Y1109593D02*
X475688Y1109580D01*
G01X475692Y1109606D02*
X475691Y1109593D01*
G01X475688Y1106430D02*
X475689Y1106417D01*
G01X475691Y1106443D02*
X475688Y1106430D01*
G01X475692Y1106456D02*
X475691Y1106443D01*
G01X475688Y1103280D02*
X475689Y1103268D01*
G01X475691Y1103293D02*
X475688Y1103280D01*
G01X475692Y1103307D02*
X475691Y1103293D01*
G01X474744Y1103498D02*
Y1103491D01*
G01X474743Y1103503D02*
X474744Y1103498D01*
G01X474743Y1103496D02*
Y1103503D01*
G01X475700Y1122364D02*
X475687Y1122362D01*
G01X475710Y1122369D02*
X475700Y1122364D01*
G01Y1119215D02*
X475687Y1119213D01*
G01X475710Y1119220D02*
X475700Y1119215D01*
G01Y1116065D02*
X475687Y1116063D01*
G01X475710Y1116070D02*
X475700Y1116065D01*
G01Y1112915D02*
X475687Y1112913D01*
G01X475710Y1112920D02*
X475700Y1112915D01*
G01Y1109766D02*
X475687Y1109764D01*
G01X475710Y1109771D02*
X475700Y1109766D01*
G01Y1106616D02*
X475687Y1106614D01*
G01X475710Y1106621D02*
X475700Y1106616D01*
G01Y1103467D02*
X475687Y1103465D01*
G01X475710Y1103472D02*
X475700Y1103467D01*
G01X475721Y1110927D02*
X475713Y1110935D01*
G01X475725Y1110917D02*
X475721Y1110927D01*
G01X475727Y1110906D02*
X475725Y1110917D01*
G01X475721Y1104628D02*
X475713Y1104636D01*
G01X475726Y1104617D02*
X475721Y1104628D01*
G01X475727Y1104606D02*
X475726Y1104617D01*
G01X475721Y1107777D02*
X475713Y1107786D01*
G01X475726Y1107767D02*
X475721Y1107777D01*
G01X475727Y1107756D02*
X475726Y1107767D01*
G01X475721Y1114076D02*
X475713Y1114085D01*
G01X475726Y1114066D02*
X475721Y1114076D01*
G01X475727Y1114055D02*
X475726Y1114066D01*
G01X475721Y1117226D02*
X475713Y1117235D01*
G01X475726Y1117216D02*
X475721Y1117226D01*
G01X475727Y1117205D02*
X475726Y1117216D01*
G01X475721Y1120376D02*
X475713Y1120384D01*
G01X475726Y1120365D02*
X475721Y1120376D01*
G01X475727Y1120354D02*
X475726Y1120365D01*
G01X475721Y1123525D02*
X475713Y1123534D01*
G01X475726Y1123515D02*
X475721Y1123525D01*
G01X475727Y1123504D02*
X475726Y1123515D01*
G01X474762Y1112919D02*
X474781Y1112913D01*
G01X474748Y1112931D02*
X474762Y1112919D01*
G01X474742Y1112949D02*
X474748Y1112931D01*
G01X489136Y1086688D02*
X489117Y1086693D01*
G01X489151Y1086674D02*
X489136Y1086688D01*
G01X489156Y1086654D02*
X489151Y1086674D01*
G01X489136Y1091688D02*
X489117Y1091693D01*
G01X489151Y1091674D02*
X489136Y1091688D01*
G01X489156Y1091654D02*
X489151Y1091674D01*
G01X489136Y1096688D02*
X489117Y1096693D01*
G01X489151Y1096674D02*
X489136Y1096688D01*
G01X489156Y1096654D02*
X489151Y1096674D01*
G01X489136Y1101688D02*
X489117Y1101693D01*
G01X489151Y1101674D02*
X489136Y1101688D01*
G01X489156Y1101654D02*
X489151Y1101674D01*
G01X489136Y1126688D02*
X489117Y1126693D01*
G01X489151Y1126674D02*
X489136Y1126688D01*
G01X489156Y1126654D02*
X489151Y1126674D01*
G01X474767Y1109767D02*
X474781Y1109764D01*
G01X474754Y1109774D02*
X474767Y1109767D01*
G01X474743Y1109794D02*
X474754Y1109774D01*
G01X474767Y1119215D02*
X474781Y1119213D01*
G01X474754Y1119223D02*
X474767Y1119215D01*
G01X474743Y1119243D02*
X474754Y1119223D01*
G01X475728Y1103498D02*
Y1103491D01*
G01Y1103503D02*
Y1103498D01*
G01X475727Y1103504D02*
X475728Y1103503D01*
G01Y1106648D02*
Y1106640D01*
G01Y1106652D02*
Y1106648D01*
G01X475727Y1106654D02*
X475728Y1106652D01*
G01Y1109797D02*
Y1109790D01*
G01Y1109802D02*
Y1109797D01*
G01X475727Y1109803D02*
X475728Y1109802D01*
G01Y1112947D02*
Y1112939D01*
G01Y1112952D02*
Y1112947D01*
G01X475727Y1112953D02*
X475728Y1112952D01*
G01Y1116096D02*
Y1116089D01*
G01Y1116101D02*
Y1116096D01*
G01X475727Y1116102D02*
X475728Y1116101D01*
G01Y1119246D02*
Y1119239D01*
G01Y1119251D02*
Y1119246D01*
G01X475727Y1119252D02*
X475728Y1119251D01*
G01Y1122396D02*
Y1122388D01*
G01Y1122400D02*
Y1122396D01*
G01X475727Y1122402D02*
X475728Y1122400D01*
G01X474767Y1122365D02*
X474781Y1122362D01*
G01X474754Y1122373D02*
X474767Y1122365D01*
G01X474743Y1122393D02*
X474754Y1122373D01*
G01X474766Y1103468D02*
X474781Y1103465D01*
G01X474753Y1103476D02*
X474766Y1103468D01*
G01X474743Y1103496D02*
X474753Y1103476D01*
G01X475728Y1104627D02*
Y1104620D01*
G01X475726Y1104633D02*
X475728Y1104627D01*
G01X475723Y1104639D02*
X475726Y1104633D01*
G01X475728Y1107776D02*
Y1107770D01*
G01X475726Y1107783D02*
X475728Y1107776D01*
G01X475723Y1107789D02*
X475726Y1107783D01*
G01X475728Y1110926D02*
Y1110919D01*
G01X475726Y1110932D02*
X475728Y1110926D01*
G01X475723Y1110938D02*
X475726Y1110932D01*
G01X475728Y1114076D02*
Y1114069D01*
G01X475726Y1114082D02*
X475728Y1114076D01*
G01X475723Y1114088D02*
X475726Y1114082D01*
G01X475728Y1117225D02*
Y1117219D01*
G01X475726Y1117231D02*
X475728Y1117225D01*
G01X475723Y1117237D02*
X475726Y1117231D01*
G01X475728Y1120375D02*
Y1120368D01*
G01X475726Y1120381D02*
X475728Y1120375D01*
G01X475723Y1120387D02*
X475726Y1120381D01*
G01X475728Y1123524D02*
Y1123518D01*
G01X475726Y1123531D02*
X475728Y1123524D01*
G01X475723Y1123537D02*
X475726Y1123531D01*
G01X475689Y1103459D02*
X475690Y1103454D01*
G01X475688Y1103463D02*
X475689Y1103459D01*
G01X475687Y1103465D02*
X475688Y1103463D01*
G01X475689Y1106609D02*
X475690Y1106603D01*
G01X475688Y1106613D02*
X475689Y1106609D01*
G01X475687Y1106614D02*
X475688Y1106613D01*
G01X475689Y1109759D02*
X475690Y1109753D01*
G01X475688Y1109763D02*
X475689Y1109759D01*
G01X475687Y1109764D02*
X475688Y1109763D01*
G01X475689Y1112908D02*
X475690Y1112902D01*
G01X475688Y1112912D02*
X475689Y1112908D01*
G01X475687Y1112913D02*
X475688Y1112912D01*
G01X475689Y1116058D02*
X475690Y1116052D01*
G01X475688Y1116062D02*
X475689Y1116058D01*
G01X475687Y1116063D02*
X475688Y1116062D01*
G01X475689Y1122357D02*
X475690Y1122351D01*
G01X475688Y1122361D02*
X475689Y1122357D01*
G01X475687Y1122362D02*
X475688Y1122361D01*
G01X488169Y1086700D02*
Y1086709D01*
G01X488170Y1086695D02*
X488169Y1086700D01*
G01X488171Y1086693D02*
X488170Y1086695D01*
G01X488169Y1091700D02*
Y1091709D01*
G01X488170Y1091695D02*
X488169Y1091700D01*
G01X488171Y1091693D02*
X488170Y1091695D01*
G01X488169Y1096700D02*
Y1096709D01*
G01X488170Y1096695D02*
X488169Y1096700D01*
G01X488171Y1096693D02*
X488170Y1096695D01*
G01X488169Y1101700D02*
Y1101709D01*
G01X488170Y1101695D02*
X488169Y1101700D01*
G01X488171Y1101693D02*
X488170Y1101695D01*
G01X488169Y1126700D02*
Y1126709D01*
G01X488170Y1126695D02*
X488169Y1126700D01*
G01X488171Y1126693D02*
X488170Y1126695D01*
G01X489146Y1086837D02*
X489154Y1086811D01*
G01X489136Y1086863D02*
X489146Y1086837D01*
G01X489124Y1086890D02*
X489136Y1086863D01*
G01X489146Y1091837D02*
X489154Y1091811D01*
G01X489136Y1091863D02*
X489146Y1091837D01*
G01X489124Y1091890D02*
X489136Y1091863D01*
G01X489146Y1096837D02*
X489154Y1096811D01*
G01X489136Y1096863D02*
X489146Y1096837D01*
G01X489124Y1096890D02*
X489136Y1096863D01*
G01X489146Y1101837D02*
X489154Y1101811D01*
G01X489136Y1101863D02*
X489146Y1101837D01*
G01X489124Y1101890D02*
X489136Y1101863D01*
G01X489146Y1126837D02*
X489154Y1126811D01*
G01X489136Y1126863D02*
X489146Y1126837D01*
G01X489124Y1126890D02*
X489136Y1126863D01*
G01X489154Y1086660D02*
Y1086667D01*
G01X489155Y1086656D02*
X489154Y1086660D01*
G01X489156Y1086654D02*
X489155Y1086656D01*
G01X489154Y1091660D02*
Y1091667D01*
G01X489155Y1091656D02*
X489154Y1091660D01*
G01X489156Y1091654D02*
X489155Y1091656D01*
G01X489154Y1096660D02*
Y1096667D01*
G01X489155Y1096656D02*
X489154Y1096660D01*
G01X489156Y1096654D02*
X489155Y1096656D01*
G01X489154Y1101660D02*
Y1101667D01*
G01X489155Y1101656D02*
X489154Y1101660D01*
G01X489156Y1101654D02*
X489155Y1101656D01*
G01X489154Y1126660D02*
Y1126667D01*
G01X489155Y1126656D02*
X489154Y1126660D01*
G01X489156Y1126654D02*
X489155Y1126656D01*
G01X474767Y1106617D02*
X474781Y1106614D01*
G01X474756Y1106624D02*
X474767Y1106617D01*
G01X474743Y1106643D02*
X474756Y1106624D01*
G01X474767Y1116066D02*
X474781Y1116063D01*
G01X474755Y1116073D02*
X474767Y1116066D01*
G01X474743Y1116091D02*
X474755Y1116073D01*
G01X474783Y1103460D02*
Y1103454D01*
G01X474782Y1103463D02*
X474783Y1103460D01*
G01X474781Y1103465D02*
X474782Y1103463D01*
G01X474783Y1106609D02*
Y1106603D01*
G01X474782Y1106613D02*
X474783Y1106609D01*
G01X474781Y1106614D02*
X474782Y1106613D01*
G01X474783Y1109759D02*
Y1109753D01*
G01X474782Y1109763D02*
X474783Y1109759D01*
G01X474781Y1109764D02*
X474782Y1109763D01*
G01X475697Y1110944D02*
X475687Y1110945D01*
G01X475706Y1110941D02*
X475697Y1110944D01*
G01X475713Y1110935D02*
X475706Y1110941D01*
G01X475697Y1104644D02*
X475687Y1104646D01*
G01X475706Y1104641D02*
X475697Y1104644D01*
G01X475713Y1104636D02*
X475706Y1104641D01*
G01X475697Y1107794D02*
X475687Y1107795D01*
G01X475706Y1107791D02*
X475697Y1107794D01*
G01X475713Y1107786D02*
X475706Y1107791D01*
G01X475697Y1114093D02*
X475687Y1114094D01*
G01X475706Y1114090D02*
X475697Y1114093D01*
G01X475713Y1114085D02*
X475706Y1114090D01*
G01X475697Y1117243D02*
X475687Y1117244D01*
G01X475706Y1117240D02*
X475697Y1117243D01*
G01X475713Y1117235D02*
X475706Y1117240D01*
G01X475697Y1120393D02*
X475687Y1120394D01*
G01X475706Y1120389D02*
X475697Y1120393D01*
G01X475713Y1120384D02*
X475706Y1120389D01*
G01X475697Y1123542D02*
X475687Y1123543D01*
G01X475706Y1123539D02*
X475697Y1123542D01*
G01X475713Y1123534D02*
X475706Y1123539D01*
G01X474783Y1112909D02*
Y1112902D01*
G01X474782Y1112912D02*
X474783Y1112909D01*
G01X474781Y1112913D02*
X474782Y1112912D01*
G01X474783Y1116058D02*
Y1116052D01*
G01X474782Y1116062D02*
X474783Y1116058D01*
G01X474781Y1116063D02*
X474782Y1116062D01*
G01X474783Y1119208D02*
Y1119202D01*
G01X474782Y1119211D02*
X474783Y1119208D01*
G01X474781Y1119213D02*
X474782Y1119211D01*
G01X474783Y1122357D02*
Y1122351D01*
G01X474782Y1122361D02*
X474783Y1122357D01*
G01X474781Y1122362D02*
X474782Y1122361D01*
G01X474744Y1106644D02*
Y1106640D01*
G01X474746Y1106638D02*
X474744Y1106644D01*
G01X474757Y1106622D02*
X474746Y1106638D01*
G01X474782Y1106614D02*
X474757Y1106622D01*
G01X474744Y1109794D02*
Y1109790D01*
G01X474746Y1109787D02*
X474744Y1109794D01*
G01X474757Y1109772D02*
X474746Y1109787D01*
G01X474781Y1109764D02*
X474757Y1109772D01*
G01X474744Y1116093D02*
Y1116089D01*
G01X474746Y1116087D02*
X474744Y1116093D01*
G01X474757Y1116071D02*
X474746Y1116087D01*
G01X474781Y1116063D02*
X474757Y1116071D01*
G01X474744Y1119243D02*
Y1119239D01*
G01X474746Y1119236D02*
X474744Y1119243D01*
G01X474757Y1119221D02*
X474746Y1119236D01*
G01X474781Y1119213D02*
X474757Y1119221D01*
G01X474744Y1103494D02*
Y1103491D01*
G01X474746Y1103488D02*
X474744Y1103494D01*
G01X474757Y1103473D02*
X474746Y1103488D01*
G01X474781Y1103465D02*
X474757Y1103473D01*
G01X474744Y1122392D02*
Y1122388D01*
G01X474746Y1122386D02*
X474744Y1122392D01*
G01X474757Y1122370D02*
X474746Y1122386D01*
G01X474781Y1122362D02*
X474757Y1122370D01*
G01X489141Y1086685D02*
X489152Y1086669D01*
G01X489117Y1086693D02*
X489141Y1086685D01*
G01Y1091685D02*
X489152Y1091669D01*
G01X489117Y1091693D02*
X489141Y1091685D01*
G01Y1096685D02*
X489152Y1096669D01*
G01X489117Y1096693D02*
X489141Y1096685D01*
G01Y1101685D02*
X489152Y1101669D01*
G01X489117Y1101693D02*
X489141Y1101685D01*
G01Y1126685D02*
X489152Y1126669D01*
G01X489117Y1126693D02*
X489141Y1126685D01*
G01X474744Y1112943D02*
Y1112939D01*
G01X474745Y1112938D02*
X474744Y1112943D01*
G01X474756Y1112923D02*
X474745Y1112938D01*
G01X474779Y1112914D02*
X474756Y1112923D01*
G01X475719Y1104644D02*
X475723Y1104639D01*
G01X475714Y1104648D02*
X475719Y1104644D01*
G01X475708Y1104652D02*
X475714Y1104648D01*
G01X475702Y1104655D02*
X475708Y1104652D01*
G01X475696Y1104657D02*
X475702Y1104655D01*
G01X475689Y1104657D02*
X475696D01*
G01X474745Y1103483D02*
X474744Y1103491D01*
G01X474747Y1103476D02*
X474745Y1103483D01*
G01X474751Y1103470D02*
X474747Y1103476D01*
G01X474756Y1103464D02*
X474751Y1103470D01*
G01X474762Y1103459D02*
X474756Y1103464D01*
G01X474769Y1103456D02*
X474762Y1103459D01*
G01X474776Y1103454D02*
X474769Y1103456D01*
G01X474783Y1103454D02*
X474776D01*
G01X474745Y1106633D02*
X474744Y1106640D01*
G01X474747Y1106626D02*
X474745Y1106633D01*
G01X474751Y1106620D02*
X474747Y1106626D01*
G01X474756Y1106614D02*
X474751Y1106620D01*
G01X474762Y1106609D02*
X474756Y1106614D01*
G01X474769Y1106606D02*
X474762Y1106609D01*
G01X474776Y1106604D02*
X474769Y1106606D01*
G01X474783Y1106603D02*
X474776Y1106604D01*
G01X474745Y1109782D02*
X474744Y1109790D01*
G01X474747Y1109776D02*
X474745Y1109782D01*
G01X474751Y1109769D02*
X474747Y1109776D01*
G01X474756Y1109763D02*
X474751Y1109769D01*
G01X474762Y1109759D02*
X474756Y1109763D01*
G01X474769Y1109756D02*
X474762Y1109759D01*
G01X474776Y1109754D02*
X474769Y1109756D01*
G01X474783Y1109753D02*
X474776Y1109754D01*
G01X475698Y1104644D02*
X475707Y1104640D01*
G01X475687Y1104646D02*
X475698Y1104644D01*
G01Y1107794D02*
X475707Y1107790D01*
G01X475687Y1107795D02*
X475698Y1107794D01*
G01Y1110944D02*
X475707Y1110939D01*
G01X475687Y1110945D02*
X475698Y1110944D01*
G01Y1114093D02*
X475707Y1114089D01*
G01X475687Y1114094D02*
X475698Y1114093D01*
G01Y1117243D02*
X475707Y1117239D01*
G01X475687Y1117244D02*
X475698Y1117243D01*
G01Y1120393D02*
X475707Y1120388D01*
G01X475687Y1120394D02*
X475698Y1120393D01*
G01Y1123542D02*
X475707Y1123538D01*
G01X475687Y1123543D02*
X475698Y1123542D01*
G01X475706Y1103457D02*
X475709Y1103459D01*
G01X475703Y1103456D02*
X475706Y1103457D01*
G01X475700Y1103455D02*
X475703Y1103456D01*
G01X475696Y1103454D02*
X475700Y1103455D01*
G01X475693Y1103454D02*
X475696D01*
G01X475689D02*
X475693D01*
G01X474767Y1104654D02*
X474763Y1104652D01*
G01X474770Y1104655D02*
X474767Y1104654D01*
G01X474773Y1104656D02*
X474770Y1104655D01*
G01X474776Y1104656D02*
X474773D01*
G01X474780Y1104657D02*
X474776Y1104656D01*
G01X474783Y1104657D02*
X474780D01*
G01X475706Y1106607D02*
X475709Y1106608D01*
G01X475703Y1106606D02*
X475706Y1106607D01*
G01X475700Y1106604D02*
X475703Y1106606D01*
G01X475696Y1106604D02*
X475700D01*
G01X475693Y1106603D02*
X475696Y1106604D01*
G01X475689Y1106603D02*
X475693D01*
G01X474767Y1107803D02*
X474763Y1107802D01*
G01X474770Y1107804D02*
X474767Y1107803D01*
G01X474773Y1107806D02*
X474770Y1107804D01*
G01X474776Y1107806D02*
X474773D01*
G01X474780Y1107807D02*
X474776Y1107806D01*
G01X474783Y1107807D02*
X474780D01*
G01X475706Y1109756D02*
X475709Y1109758D01*
G01X475703Y1109755D02*
X475706Y1109756D01*
G01X475700Y1109754D02*
X475703Y1109755D01*
G01X475696Y1109753D02*
X475700Y1109754D01*
G01X475693Y1109753D02*
X475696D01*
G01X475689D02*
X475693D01*
G01X474767Y1110953D02*
X474763Y1110951D01*
G01X474770Y1110954D02*
X474767Y1110953D01*
G01X474773Y1110955D02*
X474770Y1110954D01*
G01X474776Y1110956D02*
X474773Y1110955D01*
G01X474780Y1110956D02*
X474776D01*
G01X474783D02*
X474780D01*
G01X475706Y1112906D02*
X475709Y1112907D01*
G01X475703Y1112905D02*
X475706Y1112906D01*
G01X475700Y1112904D02*
X475703Y1112905D01*
G01X475696Y1112903D02*
X475700Y1112904D01*
G01X475693Y1112902D02*
X475696Y1112903D01*
G01X475689Y1112902D02*
X475693D01*
G01X474767Y1114102D02*
X474763Y1114101D01*
G01X474770Y1114104D02*
X474767Y1114102D01*
G01X474773Y1114105D02*
X474770Y1114104D01*
G01X474776Y1114105D02*
X474773D01*
G01X474780Y1114106D02*
X474776Y1114105D01*
G01X474783Y1114106D02*
X474780D01*
G01X475706Y1116056D02*
X475709Y1116057D01*
G01X475703Y1116054D02*
X475706Y1116056D01*
G01X475700Y1116053D02*
X475703Y1116054D01*
G01X475696Y1116052D02*
X475700Y1116053D01*
G01X475693Y1116052D02*
X475696D01*
G01X475689D02*
X475693D01*
G01X474767Y1117252D02*
X474763Y1117250D01*
G01X474770Y1117253D02*
X474767Y1117252D01*
G01X474773Y1117254D02*
X474770Y1117253D01*
G01X474776Y1117255D02*
X474773Y1117254D01*
G01X474780Y1117256D02*
X474776Y1117255D01*
G01X474783Y1117256D02*
X474780D01*
G01X474767Y1120402D02*
X474763Y1120400D01*
G01X474770Y1120403D02*
X474767Y1120402D01*
G01X474773Y1120404D02*
X474770Y1120403D01*
G01X474776Y1120404D02*
X474773D01*
G01X474780Y1120405D02*
X474776Y1120404D01*
G01X474783Y1120405D02*
X474780D01*
G01X475706Y1122355D02*
X475709Y1122356D01*
G01X475703Y1122354D02*
X475706Y1122355D01*
G01X475700Y1122352D02*
X475703Y1122354D01*
G01X475696Y1122352D02*
X475700D01*
G01X475693Y1122351D02*
X475696Y1122352D01*
G01X475689Y1122351D02*
X475693D01*
G01X474767Y1123551D02*
X474763Y1123550D01*
G01X474770Y1123552D02*
X474767Y1123551D01*
G01X474773Y1123554D02*
X474770Y1123552D01*
G01X474776Y1123554D02*
X474773D01*
G01X474780Y1123555D02*
X474776Y1123554D01*
G01X474783Y1123555D02*
X474780D01*
G01X473997Y1106654D02*
X473563D01*
G01X474370D02*
X473997D01*
G01Y1112953D02*
X473563D01*
G01X474370D02*
X473997D01*
G01Y1116102D02*
X473563D01*
G01X474370D02*
X473997D01*
G01X475719Y1107794D02*
X475723Y1107789D01*
G01X475714Y1107798D02*
X475719Y1107794D01*
G01X475708Y1107802D02*
X475714Y1107798D01*
G01X475702Y1107804D02*
X475708Y1107802D01*
G01X475696Y1107806D02*
X475702Y1107804D01*
G01X475689Y1107807D02*
X475696Y1107806D01*
G01X475719Y1110943D02*
X475723Y1110938D01*
G01X475714Y1110948D02*
X475719Y1110943D01*
G01X475708Y1110952D02*
X475714Y1110948D01*
G01X475702Y1110954D02*
X475708Y1110952D01*
G01X475696Y1110956D02*
X475702Y1110954D01*
G01X475689Y1110956D02*
X475696D01*
G01X475719Y1114093D02*
X475723Y1114088D01*
G01X475714Y1114097D02*
X475719Y1114093D01*
G01X475708Y1114101D02*
X475714Y1114097D01*
G01X475702Y1114104D02*
X475708Y1114101D01*
G01X475696Y1114106D02*
X475702Y1114104D01*
G01X475689Y1114106D02*
X475696D01*
G01X475719Y1117243D02*
X475723Y1117237D01*
G01X475714Y1117247D02*
X475719Y1117243D01*
G01X475708Y1117251D02*
X475714Y1117247D01*
G01X475702Y1117253D02*
X475708Y1117251D01*
G01X475696Y1117255D02*
X475702Y1117253D01*
G01X475689Y1117256D02*
X475696Y1117255D01*
G01X475719Y1120392D02*
X475723Y1120387D01*
G01X475714Y1120396D02*
X475719Y1120392D01*
G01X475708Y1120400D02*
X475714Y1120396D01*
G01X475702Y1120403D02*
X475708Y1120400D01*
G01X475696Y1120405D02*
X475702Y1120403D01*
G01X475689Y1120405D02*
X475696D01*
G01X475719Y1123542D02*
X475723Y1123537D01*
G01X475714Y1123546D02*
X475719Y1123542D01*
G01X475708Y1123550D02*
X475714Y1123546D01*
G01X475702Y1123552D02*
X475708Y1123550D01*
G01X475696Y1123554D02*
X475702Y1123552D01*
G01X475689Y1123555D02*
X475696Y1123554D01*
G01X474745Y1112932D02*
X474744Y1112939D01*
G01X474747Y1112925D02*
X474745Y1112932D01*
G01X474751Y1112919D02*
X474747Y1112925D01*
G01X474756Y1112913D02*
X474751Y1112919D01*
G01X474762Y1112908D02*
X474756Y1112913D01*
G01X474769Y1112905D02*
X474762Y1112908D01*
G01X474776Y1112903D02*
X474769Y1112905D01*
G01X474783Y1112902D02*
X474776Y1112903D01*
G01X474745Y1116081D02*
X474744Y1116089D01*
G01X474747Y1116075D02*
X474745Y1116081D01*
G01X474751Y1116069D02*
X474747Y1116075D01*
G01X474756Y1116063D02*
X474751Y1116069D01*
G01X474762Y1116058D02*
X474756Y1116063D01*
G01X474769Y1116055D02*
X474762Y1116058D01*
G01X474776Y1116053D02*
X474769Y1116055D01*
G01X474783Y1116052D02*
X474776Y1116053D01*
G01X474745Y1119231D02*
X474744Y1119239D01*
G01X474747Y1119224D02*
X474745Y1119231D01*
G01X474751Y1119218D02*
X474747Y1119224D01*
G01X474756Y1119212D02*
X474751Y1119218D01*
G01X474762Y1119207D02*
X474756Y1119212D01*
G01X474769Y1119204D02*
X474762Y1119207D01*
G01X474776Y1119202D02*
X474769Y1119204D01*
G01X474783Y1119202D02*
X474776D01*
G01X474745Y1122381D02*
X474744Y1122388D01*
G01X474747Y1122374D02*
X474745Y1122381D01*
G01X474751Y1122368D02*
X474747Y1122374D01*
G01X474756Y1122362D02*
X474751Y1122368D01*
G01X474762Y1122357D02*
X474756Y1122362D01*
G01X474769Y1122354D02*
X474762Y1122357D01*
G01X474776Y1122352D02*
X474769Y1122354D01*
G01X474783Y1122351D02*
X474776Y1122352D01*
G01X474747Y1104626D02*
X474742Y1104606D01*
G01X474761Y1104641D02*
X474747Y1104626D01*
G01X474781Y1104646D02*
X474761Y1104641D01*
G01X474747Y1107776D02*
X474742Y1107756D01*
G01X474761Y1107790D02*
X474747Y1107776D01*
G01X474781Y1107795D02*
X474761Y1107790D01*
G01X474747Y1110925D02*
X474742Y1110906D01*
G01X474761Y1110940D02*
X474747Y1110925D01*
G01X474781Y1110945D02*
X474761Y1110940D01*
G01X474747Y1114075D02*
X474742Y1114055D01*
G01X474761Y1114089D02*
X474747Y1114075D01*
G01X474781Y1114094D02*
X474761Y1114089D01*
G01X474747Y1117224D02*
X474742Y1117205D01*
G01X474761Y1117239D02*
X474747Y1117224D01*
G01X474781Y1117244D02*
X474761Y1117239D01*
G01X474747Y1120374D02*
X474742Y1120354D01*
G01X474761Y1120389D02*
X474747Y1120374D01*
G01X474781Y1120394D02*
X474761Y1120389D01*
G01X474747Y1123524D02*
X474742Y1123504D01*
G01X474761Y1123538D02*
X474747Y1123524D01*
G01X474781Y1123543D02*
X474761Y1123538D01*
G01X475722Y1103484D02*
X475727Y1103504D01*
G01X475707Y1103470D02*
X475722Y1103484D01*
G01X475687Y1103465D02*
X475707Y1103470D01*
G01X475722Y1106634D02*
X475727Y1106654D01*
G01X475707Y1106620D02*
X475722Y1106634D01*
G01X475687Y1106614D02*
X475707Y1106620D01*
G01X475722Y1109783D02*
X475727Y1109803D01*
G01X475707Y1109769D02*
X475722Y1109783D01*
G01X475687Y1109764D02*
X475707Y1109769D01*
G01X475722Y1112933D02*
X475727Y1112953D01*
G01X475707Y1112919D02*
X475722Y1112933D01*
G01X475687Y1112913D02*
X475707Y1112919D01*
G01X475722Y1116083D02*
X475727Y1116102D01*
G01X475707Y1116069D02*
X475722Y1116083D01*
G01X475687Y1116063D02*
X475707Y1116069D01*
G01X475722Y1119232D02*
X475727Y1119252D01*
G01X475707Y1119218D02*
X475722Y1119232D01*
G01X475687Y1119213D02*
X475707Y1119218D01*
G01X475722Y1122382D02*
X475727Y1122402D01*
G01X475707Y1122368D02*
X475722Y1122382D01*
G01X475687Y1122362D02*
X475707Y1122368D01*
G01X475728Y1119231D02*
Y1119239D01*
G01X475725Y1119224D02*
X475728Y1119231D01*
G01X475722Y1119218D02*
X475725Y1119224D01*
G01X475717Y1119212D02*
X475722Y1119218D01*
G01X475711Y1119207D02*
X475717Y1119212D01*
G01X475704Y1119204D02*
X475711Y1119207D01*
G01X475696Y1119202D02*
X475704Y1119204D01*
G01X475689Y1119202D02*
X475696D01*
G01X474631Y1122402D02*
X474743Y1122393D01*
G01X474742Y1112949D02*
X474631Y1112953D01*
G01X474742Y1106650D02*
X474631Y1106654D01*
G01X474742Y1116099D02*
X474631Y1116102D01*
G01X493504Y1130315D02*
X488171D01*
G01X488169Y1129823D02*
X489154D01*
G01Y1127185D02*
X488169D01*
G01X488171Y1126693D02*
X493504D01*
G01Y1126654D02*
X489156D01*
G01X476181Y1125709D02*
X472835D01*
G01X493504Y1125315D02*
X488171D01*
G01X488169Y1124823D02*
X489154D01*
G01X485827Y1124547D02*
X489764D01*
G01X475689Y1123740D02*
X474783D01*
G01X475728Y1123701D02*
X474744D01*
G01X475687Y1123543D02*
X469803D01*
G01Y1123504D02*
X475727D01*
G01X484646Y1123366D02*
X488583D01*
G01X475727Y1122402D02*
X469803D01*
G01X475687Y1122362D02*
X469803D01*
G01X474744Y1122205D02*
X475728D01*
G01X474783Y1122165D02*
X475689D01*
G01Y1120591D02*
X474783D01*
G01X475728Y1120551D02*
X474744D01*
G01X475687Y1120394D02*
X469803D01*
G01Y1120354D02*
X475727D01*
G01Y1119252D02*
X469803D01*
G01X475687Y1119213D02*
X469803D01*
G01X474744Y1119055D02*
X475728D01*
G01X474783Y1119016D02*
X475689D01*
G01Y1117441D02*
X474783D01*
G01X475728Y1117402D02*
X474744D01*
G01X475687Y1117244D02*
X469803D01*
G01Y1117205D02*
X475727D01*
G01Y1116102D02*
X469803D01*
G01X475687Y1116063D02*
X469803D01*
G01X474744Y1115906D02*
X475728D01*
G01X474783Y1115866D02*
X475689D01*
G01Y1114291D02*
X474783D01*
G01X475728Y1114252D02*
X474744D01*
G01X475687Y1114094D02*
X469803D01*
G01Y1114055D02*
X475727D01*
G01Y1112953D02*
X469803D01*
G01X475687Y1112913D02*
X469803D01*
G01X474744Y1112756D02*
X475728D01*
G01X474783Y1112717D02*
X475689D01*
G01Y1111142D02*
X474783D01*
G01X475728Y1111102D02*
X474744D01*
G01X475687Y1110945D02*
X469803D01*
G01Y1110906D02*
X475727D01*
G01Y1109803D02*
X469803D01*
G01X475687Y1109764D02*
X469803D01*
G01X474744Y1109606D02*
X475728D01*
G01X474783Y1109567D02*
X475689D01*
G01Y1107992D02*
X474783D01*
G01X475728Y1107953D02*
X474744D01*
G01X475687Y1107795D02*
X469803D01*
G01Y1107756D02*
X475727D01*
G01Y1106654D02*
X469803D01*
G01X475687Y1106614D02*
X469803D01*
G01X474744Y1106457D02*
X475728D01*
G01X474783Y1106417D02*
X475689D01*
G01Y1104843D02*
X474783D01*
G01X475728Y1104803D02*
X474744D01*
G01X475687Y1104646D02*
X469803D01*
G01Y1104606D02*
X475727D01*
G01X488583Y1103642D02*
X484646D01*
G01X475727Y1103504D02*
X469803D01*
G01X475687Y1103465D02*
X469803D01*
G01X474744Y1103307D02*
X475728D01*
G01X474783Y1103268D02*
X475689D01*
G01X489764Y1102461D02*
X485827D01*
G01X489154Y1102185D02*
X488169D01*
G01X488171Y1101693D02*
X493504D01*
G01Y1101654D02*
X489156D01*
G01X476181Y1101299D02*
X472835D01*
G01X493504Y1100315D02*
X488171D01*
G01X488169Y1099823D02*
X489154D01*
G01Y1097185D02*
X488169D01*
G01X488171Y1096693D02*
X493504D01*
G01Y1096654D02*
X489156D01*
G01X493504Y1095315D02*
X488171D01*
G01X488169Y1094823D02*
X489154D01*
G01Y1092185D02*
X488169D01*
G01X488171Y1091693D02*
X493504D01*
G01Y1091654D02*
X489156D01*
G01X493504Y1090315D02*
X488171D01*
G01X488169Y1089823D02*
X489154D01*
G01Y1087185D02*
X488169D01*
G01X488171Y1086693D02*
X493504D01*
G01Y1086654D02*
X489156D01*
G01X493504Y1085315D02*
X488171D01*
G01X488169Y1084823D02*
X489154D01*
G01Y1130119D02*
X488169Y1130118D01*
G01Y1126889D02*
X489124Y1126890D01*
G01X489154Y1125119D02*
X488169Y1125118D01*
G01Y1101889D02*
X489124Y1101890D01*
G01X489154Y1100119D02*
X488169Y1100118D01*
G01Y1096889D02*
X489124Y1096890D01*
G01X489154Y1095119D02*
X488169Y1095118D01*
G01Y1091889D02*
X489124Y1091890D01*
G01X489154Y1090119D02*
X488169Y1090118D01*
G01Y1086889D02*
X489124Y1086890D01*
G01X489154Y1085119D02*
X488169Y1085118D01*
G01X488583Y1103642D02*
X489764Y1102461D01*
G01X484646Y1103642D02*
X485827Y1102461D01*
G01X475687Y1119213D02*
X475691Y1119202D01*
G01X475728Y1104609D02*
Y1104620D01*
G01Y1107758D02*
Y1107769D01*
G01Y1110908D02*
Y1110919D01*
G01Y1114057D02*
Y1114069D01*
G01Y1117207D02*
Y1117218D01*
G01Y1120357D02*
Y1120368D01*
G01Y1123506D02*
Y1123517D01*
G01X489154Y1086667D02*
Y1086676D01*
G01Y1091667D02*
Y1091676D01*
G01Y1096667D02*
Y1096676D01*
G01Y1101667D02*
Y1101676D01*
G01Y1126667D02*
Y1126676D01*
G01X493504Y1130315D02*
Y1131693D01*
G01Y1125315D02*
Y1126693D01*
G01Y1100315D02*
Y1101693D01*
G01Y1095315D02*
Y1096693D01*
G01Y1090315D02*
Y1091693D01*
G01Y1085315D02*
Y1086693D01*
G01X490335D02*
Y1085315D01*
G01Y1091693D02*
Y1090315D01*
G01Y1096693D02*
Y1095315D01*
G01Y1101693D02*
Y1100315D01*
G01Y1126693D02*
Y1125315D01*
G01Y1131693D02*
Y1130315D01*
G01X489764Y1124547D02*
Y1102461D01*
G01X489154Y1129823D02*
Y1132185D01*
G01Y1124823D02*
Y1127185D01*
G01Y1099823D02*
Y1102185D01*
G01Y1094823D02*
Y1097185D01*
G01Y1089823D02*
Y1092185D01*
G01Y1084823D02*
Y1087185D01*
G01Y1086667D02*
Y1086811D01*
G01Y1091667D02*
Y1091811D01*
G01Y1096667D02*
Y1096811D01*
G01Y1101667D02*
Y1101811D01*
G01Y1126667D02*
Y1126811D01*
G01X488583Y1123366D02*
Y1103642D01*
G01X488169Y1087185D02*
Y1084823D01*
G01Y1092185D02*
Y1089823D01*
G01Y1097185D02*
Y1094823D01*
G01Y1102185D02*
Y1099823D01*
G01Y1127185D02*
Y1124823D01*
G01Y1132185D02*
Y1129823D01*
G01X485827Y1201004D02*
Y1124547D01*
G01X484646Y1199823D02*
Y1123366D01*
G01X476181Y1204744D02*
Y1125709D01*
G01X475728Y1122205D02*
Y1123701D01*
G01Y1119055D02*
Y1120551D01*
G01Y1115906D02*
Y1117402D01*
G01Y1112756D02*
Y1114252D01*
G01Y1109606D02*
Y1111102D01*
G01Y1106457D02*
Y1107953D01*
G01Y1103307D02*
Y1104803D01*
G01X475689Y1106603D02*
Y1106456D01*
G01Y1103454D02*
Y1103307D01*
G01Y1104804D02*
Y1104657D01*
G01Y1109753D02*
Y1109606D01*
G01Y1111103D02*
Y1110956D01*
G01Y1107953D02*
Y1107807D01*
G01Y1116052D02*
Y1115905D01*
G01Y1112902D02*
Y1112756D01*
G01Y1114252D02*
Y1114106D01*
G01Y1119202D02*
Y1119055D01*
G01Y1120552D02*
Y1120405D01*
G01Y1117402D02*
Y1117256D01*
G01Y1122351D02*
Y1122204D01*
G01Y1123701D02*
Y1123555D01*
G01X474783Y1122204D02*
Y1122351D01*
G01Y1123555D02*
Y1123702D01*
G01Y1119054D02*
Y1119202D01*
G01Y1120405D02*
Y1120552D01*
G01Y1117256D02*
Y1117402D01*
G01Y1115905D02*
Y1116052D01*
G01Y1112755D02*
Y1112902D01*
G01Y1114106D02*
Y1114253D01*
G01Y1109606D02*
Y1109753D01*
G01Y1110956D02*
Y1111103D01*
G01Y1107807D02*
Y1107954D01*
G01Y1106456D02*
Y1106603D01*
G01Y1103306D02*
Y1103454D01*
G01Y1104657D02*
Y1104804D01*
G01X474744Y1104803D02*
Y1103307D01*
G01Y1111102D02*
Y1109606D01*
G01Y1107953D02*
Y1106457D01*
G01Y1114252D02*
Y1112756D01*
G01Y1120551D02*
Y1119055D01*
G01Y1117402D02*
Y1115906D01*
G01Y1123701D02*
Y1122205D01*
G01X473563Y1107795D02*
Y1106614D01*
G01Y1104646D02*
Y1103465D01*
G01Y1110945D02*
Y1109764D01*
G01Y1117244D02*
Y1116063D01*
G01Y1114094D02*
Y1112913D01*
G01Y1120394D02*
Y1119213D01*
G01Y1123543D02*
Y1122362D01*
G01X473228Y1125709D02*
Y1101299D01*
G01X472835D02*
Y1125709D01*
G01X469803Y1122362D02*
Y1123543D01*
G01Y1119213D02*
Y1120394D01*
G01Y1116063D02*
Y1117244D01*
G01Y1112913D02*
Y1114094D01*
G01Y1109764D02*
Y1110945D01*
G01Y1106614D02*
Y1107795D01*
G01Y1103465D02*
Y1104646D01*
G01X475728Y1122388D02*
Y1122399D01*
G01Y1119239D02*
Y1119250D01*
G01Y1116089D02*
Y1116100D01*
G01Y1112939D02*
Y1112950D01*
G01Y1109790D02*
Y1109801D01*
G01Y1106640D02*
Y1106651D01*
G01Y1103491D02*
Y1103502D01*
G01X488583Y1123366D02*
X489764Y1124547D01*
G01X484646Y1123366D02*
X485827Y1124547D01*
G01X489154Y1175308D02*
Y1175299D01*
G01X489155Y1175313D02*
X489154Y1175308D01*
G01X489156Y1175315D02*
X489155Y1175313D01*
G01X489154Y1170308D02*
Y1170299D01*
G01X489155Y1170313D02*
X489154Y1170308D01*
G01X489156Y1170315D02*
X489155Y1170313D01*
G01X489154Y1165308D02*
Y1165299D01*
G01X489155Y1165313D02*
X489154Y1165308D01*
G01X489156Y1165315D02*
X489155Y1165313D01*
G01X489154Y1160308D02*
Y1160299D01*
G01X489155Y1160313D02*
X489154Y1160308D01*
G01X489156Y1160315D02*
X489155Y1160313D01*
G01X489154Y1155308D02*
Y1155299D01*
G01X489155Y1155313D02*
X489154Y1155308D01*
G01X489156Y1155315D02*
X489155Y1155313D01*
G01X489154Y1150308D02*
Y1150299D01*
G01X489155Y1150313D02*
X489154Y1150308D01*
G01X489156Y1150315D02*
X489155Y1150313D01*
G01X489154Y1145308D02*
Y1145299D01*
G01X489155Y1145313D02*
X489154Y1145308D01*
G01X489156Y1145315D02*
X489155Y1145313D01*
G01X489154Y1140308D02*
Y1140299D01*
G01X489155Y1140313D02*
X489154Y1140308D01*
G01X489156Y1140315D02*
X489155Y1140313D01*
G01X489154Y1135308D02*
Y1135299D01*
G01X489155Y1135313D02*
X489154Y1135308D01*
G01X489156Y1135315D02*
X489155Y1135313D01*
G01X489120Y1131791D02*
X489124Y1131890D01*
G01X489115Y1131719D02*
X489120Y1131791D01*
G01X489117Y1131693D02*
X489115Y1131719D01*
G01X489120Y1136791D02*
X489124Y1136890D01*
G01X489115Y1136719D02*
X489120Y1136791D01*
G01X489117Y1136693D02*
X489115Y1136719D01*
G01X489120Y1141791D02*
X489124Y1141890D01*
G01X489115Y1141719D02*
X489120Y1141791D01*
G01X489117Y1141693D02*
X489115Y1141719D01*
G01X489120Y1146791D02*
X489124Y1146890D01*
G01X489115Y1146719D02*
X489120Y1146791D01*
G01X489117Y1146693D02*
X489115Y1146719D01*
G01X489120Y1151791D02*
X489124Y1151890D01*
G01X489115Y1151719D02*
X489120Y1151791D01*
G01X489117Y1151693D02*
X489115Y1151719D01*
G01X489120Y1156791D02*
X489124Y1156890D01*
G01X489115Y1156719D02*
X489120Y1156791D01*
G01X489117Y1156693D02*
X489115Y1156719D01*
G01X489120Y1161791D02*
X489124Y1161890D01*
G01X489115Y1161719D02*
X489120Y1161791D01*
G01X489117Y1161693D02*
X489115Y1161719D01*
G01X489120Y1166791D02*
X489124Y1166890D01*
G01X489115Y1166719D02*
X489120Y1166791D01*
G01X489117Y1166693D02*
X489115Y1166719D01*
G01X489120Y1171791D02*
X489124Y1171890D01*
G01X489115Y1171719D02*
X489120Y1171791D01*
G01X489117Y1171693D02*
X489115Y1171719D01*
G01X489120Y1176791D02*
X489124Y1176890D01*
G01X489115Y1176719D02*
X489120Y1176791D01*
G01X489117Y1176693D02*
X489115Y1176719D01*
G01X488170Y1175313D02*
X488171Y1175315D01*
G01X488169Y1175308D02*
X488170Y1175313D01*
G01X488169Y1175299D02*
Y1175308D01*
G01X488170Y1170313D02*
X488171Y1170315D01*
G01X488169Y1170308D02*
X488170Y1170313D01*
G01X488169Y1170299D02*
Y1170308D01*
G01X488170Y1165313D02*
X488171Y1165315D01*
G01X488169Y1165308D02*
X488170Y1165313D01*
G01X488169Y1165299D02*
Y1165308D01*
G01X488170Y1160313D02*
X488171Y1160315D01*
G01X488169Y1160308D02*
X488170Y1160313D01*
G01X488169Y1160299D02*
Y1160308D01*
G01X488170Y1155313D02*
X488171Y1155315D01*
G01X488169Y1155308D02*
X488170Y1155313D01*
G01X488169Y1155299D02*
Y1155308D01*
G01X488170Y1150313D02*
X488171Y1150315D01*
G01X488169Y1150308D02*
X488170Y1150313D01*
G01X488169Y1150299D02*
Y1150308D01*
G01X488170Y1145313D02*
X488171Y1145315D01*
G01X488169Y1145308D02*
X488170Y1145313D01*
G01X488169Y1145299D02*
Y1145308D01*
G01X488170Y1140313D02*
X488171Y1140315D01*
G01X488169Y1140308D02*
X488170Y1140313D01*
G01X488169Y1140299D02*
Y1140308D01*
G01X488170Y1135313D02*
X488171Y1135315D01*
G01X488169Y1135308D02*
X488170Y1135313D01*
G01X488169Y1135299D02*
Y1135308D01*
G01X489136Y1131688D02*
X489117Y1131693D01*
G01X489151Y1131674D02*
X489136Y1131688D01*
G01X489156Y1131654D02*
X489151Y1131674D01*
G01X489136Y1136688D02*
X489117Y1136693D01*
G01X489151Y1136674D02*
X489136Y1136688D01*
G01X489156Y1136654D02*
X489151Y1136674D01*
G01X489136Y1141688D02*
X489117Y1141693D01*
G01X489151Y1141674D02*
X489136Y1141688D01*
G01X489156Y1141654D02*
X489151Y1141674D01*
G01X489136Y1146688D02*
X489117Y1146693D01*
G01X489151Y1146674D02*
X489136Y1146688D01*
G01X489156Y1146654D02*
X489151Y1146674D01*
G01X489136Y1151688D02*
X489117Y1151693D01*
G01X489151Y1151674D02*
X489136Y1151688D01*
G01X489156Y1151654D02*
X489151Y1151674D01*
G01X489136Y1156688D02*
X489117Y1156693D01*
G01X489151Y1156674D02*
X489136Y1156688D01*
G01X489156Y1156654D02*
X489151Y1156674D01*
G01X489136Y1161688D02*
X489117Y1161693D01*
G01X489151Y1161674D02*
X489136Y1161688D01*
G01X489156Y1161654D02*
X489151Y1161674D01*
G01X489136Y1166688D02*
X489117Y1166693D01*
G01X489151Y1166674D02*
X489136Y1166688D01*
G01X489156Y1166654D02*
X489151Y1166674D01*
G01X489136Y1171688D02*
X489117Y1171693D01*
G01X489151Y1171674D02*
X489136Y1171688D01*
G01X489156Y1171654D02*
X489151Y1171674D01*
G01X489136Y1176688D02*
X489117Y1176693D01*
G01X489151Y1176674D02*
X489136Y1176688D01*
G01X489156Y1176654D02*
X489151Y1176674D01*
G01X488169Y1131700D02*
Y1131709D01*
G01X488170Y1131695D02*
X488169Y1131700D01*
G01X488171Y1131693D02*
X488170Y1131695D01*
G01X488169Y1136700D02*
Y1136709D01*
G01X488170Y1136695D02*
X488169Y1136700D01*
G01X488171Y1136693D02*
X488170Y1136695D01*
G01X488169Y1141700D02*
Y1141709D01*
G01X488170Y1141695D02*
X488169Y1141700D01*
G01X488171Y1141693D02*
X488170Y1141695D01*
G01X488169Y1146700D02*
Y1146709D01*
G01X488170Y1146695D02*
X488169Y1146700D01*
G01X488171Y1146693D02*
X488170Y1146695D01*
G01X488169Y1151700D02*
Y1151709D01*
G01X488170Y1151695D02*
X488169Y1151700D01*
G01X488171Y1151693D02*
X488170Y1151695D01*
G01X488169Y1156700D02*
Y1156709D01*
G01X488170Y1156695D02*
X488169Y1156700D01*
G01X488171Y1156693D02*
X488170Y1156695D01*
G01X488169Y1161700D02*
Y1161709D01*
G01X488170Y1161695D02*
X488169Y1161700D01*
G01X488171Y1161693D02*
X488170Y1161695D01*
G01X488169Y1166700D02*
Y1166709D01*
G01X488170Y1166695D02*
X488169Y1166700D01*
G01X488171Y1166693D02*
X488170Y1166695D01*
G01X488169Y1171700D02*
Y1171709D01*
G01X488170Y1171695D02*
X488169Y1171700D01*
G01X488171Y1171693D02*
X488170Y1171695D01*
G01X488169Y1176700D02*
Y1176709D01*
G01X488170Y1176695D02*
X488169Y1176700D01*
G01X488171Y1176693D02*
X488170Y1176695D01*
G01X489146Y1131837D02*
X489154Y1131811D01*
G01X489136Y1131863D02*
X489146Y1131837D01*
G01X489124Y1131890D02*
X489136Y1131863D01*
G01X489146Y1136837D02*
X489154Y1136811D01*
G01X489136Y1136863D02*
X489146Y1136837D01*
G01X489124Y1136890D02*
X489136Y1136863D01*
G01X489146Y1141837D02*
X489154Y1141811D01*
G01X489136Y1141863D02*
X489146Y1141837D01*
G01X489124Y1141890D02*
X489136Y1141863D01*
G01X489146Y1146837D02*
X489154Y1146811D01*
G01X489136Y1146863D02*
X489146Y1146837D01*
G01X489124Y1146890D02*
X489136Y1146863D01*
G01X489146Y1151837D02*
X489154Y1151811D01*
G01X489136Y1151863D02*
X489146Y1151837D01*
G01X489124Y1151890D02*
X489136Y1151863D01*
G01X489146Y1156837D02*
X489154Y1156811D01*
G01X489136Y1156863D02*
X489146Y1156837D01*
G01X489124Y1156890D02*
X489136Y1156863D01*
G01X489146Y1161837D02*
X489154Y1161811D01*
G01X489136Y1161863D02*
X489146Y1161837D01*
G01X489124Y1161890D02*
X489136Y1161863D01*
G01X489146Y1166837D02*
X489154Y1166811D01*
G01X489136Y1166863D02*
X489146Y1166837D01*
G01X489124Y1166890D02*
X489136Y1166863D01*
G01X489146Y1171837D02*
X489154Y1171811D01*
G01X489136Y1171863D02*
X489146Y1171837D01*
G01X489124Y1171890D02*
X489136Y1171863D01*
G01X489146Y1176837D02*
X489154Y1176811D01*
G01X489136Y1176863D02*
X489146Y1176837D01*
G01X489124Y1176890D02*
X489136Y1176863D01*
G01X489154Y1131660D02*
Y1131667D01*
G01X489155Y1131656D02*
X489154Y1131660D01*
G01X489156Y1131654D02*
X489155Y1131656D01*
G01X489154Y1136660D02*
Y1136667D01*
G01X489155Y1136656D02*
X489154Y1136660D01*
G01X489156Y1136654D02*
X489155Y1136656D01*
G01X489154Y1141660D02*
Y1141667D01*
G01X489155Y1141656D02*
X489154Y1141660D01*
G01X489156Y1141654D02*
X489155Y1141656D01*
G01X489154Y1146660D02*
Y1146667D01*
G01X489155Y1146656D02*
X489154Y1146660D01*
G01X489156Y1146654D02*
X489155Y1146656D01*
G01X489154Y1151660D02*
Y1151667D01*
G01X489155Y1151656D02*
X489154Y1151660D01*
G01X489156Y1151654D02*
X489155Y1151656D01*
G01X489154Y1156660D02*
Y1156667D01*
G01X489155Y1156656D02*
X489154Y1156660D01*
G01X489156Y1156654D02*
X489155Y1156656D01*
G01X489154Y1161660D02*
Y1161667D01*
G01X489155Y1161656D02*
X489154Y1161660D01*
G01X489156Y1161654D02*
X489155Y1161656D01*
G01X489154Y1166660D02*
Y1166667D01*
G01X489155Y1166656D02*
X489154Y1166660D01*
G01X489156Y1166654D02*
X489155Y1166656D01*
G01X489154Y1171660D02*
Y1171667D01*
G01X489155Y1171656D02*
X489154Y1171660D01*
G01X489156Y1171654D02*
X489155Y1171656D01*
G01X489154Y1176660D02*
Y1176667D01*
G01X489155Y1176656D02*
X489154Y1176660D01*
G01X489156Y1176654D02*
X489155Y1176656D01*
G01X489141Y1131685D02*
X489152Y1131669D01*
G01X489117Y1131693D02*
X489141Y1131685D01*
G01Y1136685D02*
X489152Y1136669D01*
G01X489117Y1136693D02*
X489141Y1136685D01*
G01Y1141685D02*
X489152Y1141669D01*
G01X489117Y1141693D02*
X489141Y1141685D01*
G01Y1146685D02*
X489152Y1146669D01*
G01X489117Y1146693D02*
X489141Y1146685D01*
G01Y1151685D02*
X489152Y1151669D01*
G01X489117Y1151693D02*
X489141Y1151685D01*
G01Y1156685D02*
X489152Y1156669D01*
G01X489117Y1156693D02*
X489141Y1156685D01*
G01Y1161685D02*
X489152Y1161669D01*
G01X489117Y1161693D02*
X489141Y1161685D01*
G01Y1166685D02*
X489152Y1166669D01*
G01X489117Y1166693D02*
X489141Y1166685D01*
G01Y1171685D02*
X489152Y1171669D01*
G01X489117Y1171693D02*
X489141Y1171685D01*
G01Y1176685D02*
X489152Y1176669D01*
G01X489117Y1176693D02*
X489141Y1176685D01*
G01X489154Y1177185D02*
X488169D01*
G01X488171Y1176693D02*
X493504D01*
G01Y1176654D02*
X489156D01*
G01X493504Y1175315D02*
X488171D01*
G01X488169Y1174823D02*
X489154D01*
G01Y1172185D02*
X488169D01*
G01X488171Y1171693D02*
X493504D01*
G01Y1171654D02*
X489156D01*
G01X493504Y1170315D02*
X488171D01*
G01X488169Y1169823D02*
X489154D01*
G01Y1167185D02*
X488169D01*
G01X488171Y1166693D02*
X493504D01*
G01Y1166654D02*
X489156D01*
G01X493504Y1165315D02*
X488171D01*
G01X488169Y1164823D02*
X489154D01*
G01Y1162185D02*
X488169D01*
G01X488171Y1161693D02*
X493504D01*
G01Y1161654D02*
X489156D01*
G01X493504Y1160315D02*
X488171D01*
G01X488169Y1159823D02*
X489154D01*
G01Y1157185D02*
X488169D01*
G01X488171Y1156693D02*
X493504D01*
G01Y1156654D02*
X489156D01*
G01X493504Y1155315D02*
X488171D01*
G01X488169Y1154823D02*
X489154D01*
G01X488169Y1176889D02*
X489124Y1176890D01*
G01X489154Y1175119D02*
X488169Y1175118D01*
G01Y1171889D02*
X489124Y1171890D01*
G01X489154Y1170119D02*
X488169Y1170118D01*
G01Y1166889D02*
X489124Y1166890D01*
G01X489154Y1165119D02*
X488169Y1165118D01*
G01Y1161889D02*
X489124Y1161890D01*
G01X489154Y1160119D02*
X488169Y1160118D01*
G01Y1156889D02*
X489124Y1156890D01*
G01X489154Y1155119D02*
X488169Y1155118D01*
G01X489154Y1152185D02*
X488169D01*
G01X488171Y1151693D02*
X493504D01*
G01Y1151654D02*
X489156D01*
G01X493504Y1150315D02*
X488171D01*
G01X488169Y1149823D02*
X489154D01*
G01Y1147185D02*
X488169D01*
G01X488171Y1146693D02*
X493504D01*
G01Y1146654D02*
X489156D01*
G01X493504Y1145315D02*
X488171D01*
G01X488169Y1144823D02*
X489154D01*
G01Y1142185D02*
X488169D01*
G01X488171Y1141693D02*
X493504D01*
G01Y1141654D02*
X489156D01*
G01X493504Y1140315D02*
X488171D01*
G01X488169Y1139823D02*
X489154D01*
G01Y1137185D02*
X488169D01*
G01X488171Y1136693D02*
X493504D01*
G01Y1136654D02*
X489156D01*
G01X493504Y1135315D02*
X488171D01*
G01X488169Y1134823D02*
X489154D01*
G01Y1132185D02*
X488169D01*
G01X488171Y1131693D02*
X493504D01*
G01Y1131654D02*
X489156D01*
G01X488169Y1151889D02*
X489124Y1151890D01*
G01X489154Y1150119D02*
X488169Y1150118D01*
G01Y1146889D02*
X489124Y1146890D01*
G01X489154Y1145119D02*
X488169Y1145118D01*
G01Y1141889D02*
X489124Y1141890D01*
G01X489154Y1140119D02*
X488169Y1140118D01*
G01Y1136889D02*
X489124Y1136890D01*
G01X489154Y1135119D02*
X488169Y1135118D01*
G01Y1131889D02*
X489124Y1131890D01*
G01X489154Y1131667D02*
Y1131676D01*
G01Y1136667D02*
Y1136676D01*
G01Y1141667D02*
Y1141676D01*
G01Y1146667D02*
Y1146676D01*
G01Y1151667D02*
Y1151676D01*
G01Y1156667D02*
Y1156676D01*
G01Y1161667D02*
Y1161676D01*
G01Y1166667D02*
Y1166676D01*
G01Y1171667D02*
Y1171676D01*
G01Y1176667D02*
Y1176676D01*
G01X493504Y1175315D02*
Y1176693D01*
G01Y1170315D02*
Y1171693D01*
G01Y1165315D02*
Y1166693D01*
G01Y1160315D02*
Y1161693D01*
G01Y1155315D02*
Y1156693D01*
G01Y1150315D02*
Y1151693D01*
G01Y1145315D02*
Y1146693D01*
G01Y1140315D02*
Y1141693D01*
G01Y1135315D02*
Y1136693D01*
G01X490335D02*
Y1135315D01*
G01Y1141693D02*
Y1140315D01*
G01Y1146693D02*
Y1145315D01*
G01Y1151693D02*
Y1150315D01*
G01Y1156693D02*
Y1155315D01*
G01Y1161693D02*
Y1160315D01*
G01Y1166693D02*
Y1165315D01*
G01Y1171693D02*
Y1170315D01*
G01Y1176693D02*
Y1175315D01*
G01X489154Y1174823D02*
Y1177185D01*
G01Y1169823D02*
Y1172185D01*
G01Y1164823D02*
Y1167185D01*
G01Y1159823D02*
Y1162185D01*
G01Y1154823D02*
Y1157185D01*
G01Y1149823D02*
Y1152185D01*
G01Y1144823D02*
Y1147185D01*
G01Y1139823D02*
Y1142185D01*
G01Y1134823D02*
Y1137185D01*
G01Y1131667D02*
Y1131811D01*
G01Y1136667D02*
Y1136811D01*
G01Y1141667D02*
Y1141811D01*
G01Y1146667D02*
Y1146811D01*
G01Y1151667D02*
Y1151811D01*
G01Y1156667D02*
Y1156811D01*
G01Y1161667D02*
Y1161811D01*
G01Y1166667D02*
Y1166811D01*
G01Y1171667D02*
Y1171811D01*
G01Y1176667D02*
Y1176811D01*
G01X488169Y1137185D02*
Y1134823D01*
G01Y1142185D02*
Y1139823D01*
G01Y1147185D02*
Y1144823D01*
G01Y1152185D02*
Y1149823D01*
G01Y1157185D02*
Y1154823D01*
G01Y1162185D02*
Y1159823D01*
G01Y1167185D02*
Y1164823D01*
G01Y1172185D02*
Y1169823D01*
G01Y1177185D02*
Y1174823D01*
G01X489154Y1195308D02*
Y1195299D01*
G01X489155Y1195313D02*
X489154Y1195308D01*
G01X489156Y1195315D02*
X489155Y1195313D01*
G01X489154Y1190308D02*
Y1190299D01*
G01X489155Y1190313D02*
X489154Y1190308D01*
G01X489156Y1190315D02*
X489155Y1190313D01*
G01X489154Y1185308D02*
Y1185299D01*
G01X489155Y1185313D02*
X489154Y1185308D01*
G01X489156Y1185315D02*
X489155Y1185313D01*
G01X489154Y1180308D02*
Y1180299D01*
G01X489155Y1180313D02*
X489154Y1180308D01*
G01X489156Y1180315D02*
X489155Y1180313D01*
G01X489120Y1181791D02*
X489124Y1181890D01*
G01X489115Y1181719D02*
X489120Y1181791D01*
G01X489117Y1181693D02*
X489115Y1181719D01*
G01X489120Y1186791D02*
X489124Y1186890D01*
G01X489115Y1186719D02*
X489120Y1186791D01*
G01X489117Y1186693D02*
X489115Y1186719D01*
G01X489120Y1191791D02*
X489124Y1191890D01*
G01X489115Y1191719D02*
X489120Y1191791D01*
G01X489117Y1191693D02*
X489115Y1191719D01*
G01X489120Y1196791D02*
X489124Y1196890D01*
G01X489115Y1196719D02*
X489120Y1196791D01*
G01X489117Y1196693D02*
X489115Y1196719D01*
G01X488170Y1195313D02*
X488171Y1195315D01*
G01X488169Y1195308D02*
X488170Y1195313D01*
G01X488169Y1195299D02*
Y1195308D01*
G01X488170Y1190313D02*
X488171Y1190315D01*
G01X488169Y1190308D02*
X488170Y1190313D01*
G01X488169Y1190299D02*
Y1190308D01*
G01X488170Y1185313D02*
X488171Y1185315D01*
G01X488169Y1185308D02*
X488170Y1185313D01*
G01X488169Y1185299D02*
Y1185308D01*
G01X488170Y1180313D02*
X488171Y1180315D01*
G01X488169Y1180308D02*
X488170Y1180313D01*
G01X488169Y1180299D02*
Y1180308D01*
G01X489136Y1181688D02*
X489117Y1181693D01*
G01X489151Y1181674D02*
X489136Y1181688D01*
G01X489156Y1181654D02*
X489151Y1181674D01*
G01X489136Y1186688D02*
X489117Y1186693D01*
G01X489151Y1186674D02*
X489136Y1186688D01*
G01X489156Y1186654D02*
X489151Y1186674D01*
G01X489136Y1191688D02*
X489117Y1191693D01*
G01X489151Y1191674D02*
X489136Y1191688D01*
G01X489156Y1191654D02*
X489151Y1191674D01*
G01X489136Y1196688D02*
X489117Y1196693D01*
G01X489151Y1196674D02*
X489136Y1196688D01*
G01X489156Y1196654D02*
X489151Y1196674D01*
G01X488169Y1181700D02*
Y1181709D01*
G01X488170Y1181695D02*
X488169Y1181700D01*
G01X488171Y1181693D02*
X488170Y1181695D01*
G01X488169Y1186700D02*
Y1186709D01*
G01X488170Y1186695D02*
X488169Y1186700D01*
G01X488171Y1186693D02*
X488170Y1186695D01*
G01X488169Y1191700D02*
Y1191709D01*
G01X488170Y1191695D02*
X488169Y1191700D01*
G01X488171Y1191693D02*
X488170Y1191695D01*
G01X488169Y1196700D02*
Y1196709D01*
G01X488170Y1196695D02*
X488169Y1196700D01*
G01X488171Y1196693D02*
X488170Y1196695D01*
G01X489146Y1181837D02*
X489154Y1181811D01*
G01X489136Y1181863D02*
X489146Y1181837D01*
G01X489124Y1181890D02*
X489136Y1181863D01*
G01X489146Y1186837D02*
X489154Y1186811D01*
G01X489136Y1186863D02*
X489146Y1186837D01*
G01X489124Y1186890D02*
X489136Y1186863D01*
G01X489146Y1191837D02*
X489154Y1191811D01*
G01X489136Y1191863D02*
X489146Y1191837D01*
G01X489124Y1191890D02*
X489136Y1191863D01*
G01X489146Y1196837D02*
X489154Y1196811D01*
G01X489136Y1196863D02*
X489146Y1196837D01*
G01X489124Y1196890D02*
X489136Y1196863D01*
G01X489154Y1181660D02*
Y1181667D01*
G01X489155Y1181656D02*
X489154Y1181660D01*
G01X489156Y1181654D02*
X489155Y1181656D01*
G01X489154Y1186660D02*
Y1186667D01*
G01X489155Y1186656D02*
X489154Y1186660D01*
G01X489156Y1186654D02*
X489155Y1186656D01*
G01X489154Y1191660D02*
Y1191667D01*
G01X489155Y1191656D02*
X489154Y1191660D01*
G01X489156Y1191654D02*
X489155Y1191656D01*
G01X489154Y1196660D02*
Y1196667D01*
G01X489155Y1196656D02*
X489154Y1196660D01*
G01X489156Y1196654D02*
X489155Y1196656D01*
G01X489141Y1181685D02*
X489152Y1181669D01*
G01X489117Y1181693D02*
X489141Y1181685D01*
G01Y1186685D02*
X489152Y1186669D01*
G01X489117Y1186693D02*
X489141Y1186685D01*
G01Y1191685D02*
X489152Y1191669D01*
G01X489117Y1191693D02*
X489141Y1191685D01*
G01Y1196685D02*
X489152Y1196669D01*
G01X489117Y1196693D02*
X489141Y1196685D01*
G01X487598Y1222185D02*
G03X487008Y1222776I-590J1D01*
G01X484843Y1219035D02*
G03Y1221004I0J985D01*
G01X494488Y1221594D02*
G03X492520Y1223563I-1968J1D01*
G01X487402Y1211909D02*
G03X486220Y1213091I-1181J1D01*
G01X485551Y1207815D02*
G03I-1890J0D01*
G01X486024D02*
G03I-2363J0D01*
G01X480315Y1222776D02*
G03X479724Y1222185I0J-591D01*
G01X482480Y1221004D02*
G03Y1219035I0J-985D01*
G01X474803Y1223563D02*
G03X472835Y1221594I0J-1968D01*
G01X481102Y1213091D02*
G03X479921Y1211909I0J-1181D01*
G01X492520Y1223563D02*
X474803D01*
G01X487008Y1222776D02*
X480315D01*
G01X484843Y1221004D02*
X482480D01*
G01Y1219035D02*
X484843D01*
G01X487598Y1217657D02*
X479724D01*
G01Y1216083D02*
X487598D01*
G01X494488Y1213130D02*
X472835D01*
G01X481102Y1213091D02*
X486220D01*
G01X482480Y1208406D02*
X484843D01*
G01X482480Y1206713D02*
X484843D01*
G01X476181Y1204744D02*
X490551D01*
G01X476181Y1203366D02*
X479921D01*
G01X490551D02*
X487402D01*
G01X476181Y1202500D02*
X491142D01*
G01X477953Y1201004D02*
X485827D01*
G01X479134Y1199823D02*
X484646D01*
G01X489154Y1197185D02*
X488169D01*
G01X488171Y1196693D02*
X493504D01*
G01Y1196654D02*
X489156D01*
G01X493504Y1195315D02*
X488171D01*
G01X488169Y1194823D02*
X489154D01*
G01Y1192185D02*
X488169D01*
G01X488171Y1191693D02*
X493504D01*
G01Y1191654D02*
X489156D01*
G01X493504Y1190315D02*
X488171D01*
G01X488169Y1189823D02*
X489154D01*
G01Y1187185D02*
X488169D01*
G01X488171Y1186693D02*
X493504D01*
G01Y1186654D02*
X489156D01*
G01X493504Y1185315D02*
X488171D01*
G01X488169Y1184823D02*
X489154D01*
G01Y1182185D02*
X488169D01*
G01X488171Y1181693D02*
X493504D01*
G01Y1181654D02*
X489156D01*
G01X493504Y1180315D02*
X488171D01*
G01X488169Y1179823D02*
X489154D01*
G01X488169Y1196889D02*
X489124Y1196890D01*
G01X489154Y1195119D02*
X488169Y1195118D01*
G01Y1191889D02*
X489124Y1191890D01*
G01X489154Y1190119D02*
X488169Y1190118D01*
G01Y1186889D02*
X489124Y1186890D01*
G01X489154Y1185119D02*
X488169Y1185118D01*
G01Y1181889D02*
X489124Y1181890D01*
G01X489154Y1180119D02*
X488169Y1180118D01*
G01X477953Y1201004D02*
X479134Y1199823D01*
G01X472835Y1205846D02*
X476181Y1202500D01*
G01X482480Y1208406D02*
X480170Y1212635D01*
G01X484843Y1206713D02*
X486146Y1204744D01*
G01X489154Y1181667D02*
Y1181676D01*
G01Y1186667D02*
Y1186676D01*
G01Y1191667D02*
Y1191676D01*
G01Y1196667D02*
Y1196676D01*
G01X494488Y1205846D02*
Y1221594D01*
G01X493504Y1195315D02*
Y1196693D01*
G01Y1190315D02*
Y1191693D01*
G01Y1185315D02*
Y1186693D01*
G01Y1180315D02*
Y1181693D01*
G01X490335D02*
Y1180315D01*
G01Y1186693D02*
Y1185315D01*
G01Y1191693D02*
Y1190315D01*
G01Y1196693D02*
Y1195315D01*
G01X489154Y1194823D02*
Y1197185D01*
G01Y1189823D02*
Y1192185D01*
G01Y1184823D02*
Y1187185D01*
G01Y1179823D02*
Y1182185D01*
G01Y1181667D02*
Y1181811D01*
G01Y1186667D02*
Y1186811D01*
G01Y1191667D02*
Y1191811D01*
G01Y1196667D02*
Y1196811D01*
G01X488169Y1182185D02*
Y1179823D01*
G01Y1187185D02*
Y1184823D01*
G01Y1192185D02*
Y1189823D01*
G01Y1197185D02*
Y1194823D01*
G01X487598Y1216083D02*
Y1222185D01*
G01X487402Y1211909D02*
Y1203366D01*
G01X484843Y1208406D02*
Y1206713D01*
G01X482480D02*
Y1208406D01*
G01X479921Y1203366D02*
Y1211909D01*
G01X479724Y1216083D02*
Y1222185D01*
G01X472835Y1221594D02*
Y1205846D01*
G01X494488D02*
X491142Y1202500D01*
G01X484646Y1199823D02*
X485827Y1201004D01*
G01X481177Y1204744D02*
X482480Y1206713D01*
G01X487153Y1212635D02*
X484843Y1208406D01*
G01X540236Y-335933D02*
Y-354870D01*
G01Y1841823D02*
Y1822886D01*
G01X582677Y3937D02*
G03X594488Y-7874I11811J0D01*
G01X582677Y51181D02*
Y3937D01*
G01X594488Y-7874D02*
X628765D01*
G01X594488Y0D02*
X783465D01*
G01X590551Y3937D02*
G03X594488Y0I3937J0D01*
G01X590551Y55118D02*
Y3937D01*
G01X582677D02*
G03X594488Y-7874I11811J0D01*
G01D02*
X628765D01*
G01X582677Y51181D02*
Y3937D01*
G01X590551D02*
G03X594488Y0I3937J0D01*
G01X590551Y55118D02*
Y3937D01*
G01X594488Y0D02*
X783465D01*
G01X590551Y55118D02*
G03X586614Y59055I-3937J0D01*
G01X590551Y55118D02*
G03X586614Y59055I-3937J0D01*
G01X603937Y139311D02*
G03X604528Y138720I591J0D01*
G01X604134Y149587D02*
G03X605315Y148406I1181J0D01*
G01X597047Y139902D02*
G03X599016Y137933I1969J0D01*
G01X603346Y161673D02*
X602165Y160492D01*
G01X600394Y158996D02*
X597047Y155650D01*
G01X604383Y148861D02*
X606693Y153091D01*
G01X604134Y149587D02*
Y158130D01*
G01X603937Y145413D02*
Y139311D01*
G01X603346Y161673D02*
Y294311D01*
G01X602165Y160492D02*
Y295492D01*
G01X600394Y195787D02*
Y156752D01*
G01X597047Y155650D02*
Y139902D01*
G01X608858Y161673D02*
X603346D01*
G01X610039Y160492D02*
X602165D01*
G01X615354Y158996D02*
X600394D01*
G01X604134Y158130D02*
X600394D01*
G01Y156752D02*
X614764D01*
G01X618701Y148366D02*
X597047D01*
G01X611811Y145413D02*
X603937D01*
G01Y143839D02*
X611811D01*
G01X616732Y137933D02*
X599016D01*
G01X598957Y197971D02*
Y197979D01*
G01X598960Y197965D02*
X598957Y197971D01*
G01X598963Y197958D02*
X598960Y197965D01*
G01X598968Y197952D02*
X598963Y197958D01*
G01X598974Y197948D02*
X598968Y197952D01*
G01X598981Y197944D02*
X598974Y197948D01*
G01X598989Y197943D02*
X598981Y197944D01*
G01X598996Y197942D02*
X598989Y197943D01*
G01X599911Y199133D02*
X599920Y199128D01*
G01X599900Y199134D02*
X599911Y199133D01*
G01Y202282D02*
X599920Y202278D01*
G01X599900Y202283D02*
X599911Y202282D01*
G01Y205432D02*
X599920Y205428D01*
G01X599900Y205433D02*
X599911Y205432D01*
G01Y208581D02*
X599920Y208577D01*
G01X599900Y208583D02*
X599911Y208581D01*
G01X598957Y201132D02*
Y201128D01*
G01X598958Y201126D02*
X598957Y201132D01*
G01X598970Y201111D02*
X598958Y201126D01*
G01X598995Y201102D02*
X598970Y201111D01*
G01X598957Y204282D02*
Y204278D01*
G01X598958Y204276D02*
X598957Y204282D01*
G01X598970Y204260D02*
X598958Y204276D01*
G01X598994Y204252D02*
X598970Y204260D01*
G01X598957Y210581D02*
Y210577D01*
G01X598958Y210575D02*
X598957Y210581D01*
G01X598970Y210559D02*
X598958Y210575D01*
G01X598994Y210551D02*
X598970Y210559D01*
G01X598957Y197983D02*
Y197979D01*
G01X598958Y197976D02*
X598957Y197983D01*
G01X598970Y197961D02*
X598958Y197976D01*
G01X598994Y197953D02*
X598970Y197961D01*
G01X598957Y207431D02*
Y207428D01*
G01X598958Y207426D02*
X598957Y207431D01*
G01X598968Y207411D02*
X598958Y207426D01*
G01X598991Y207402D02*
X598968Y207411D01*
G01X599909Y205432D02*
X599900Y205433D01*
G01X599918Y205429D02*
X599909Y205432D01*
G01X599926Y205424D02*
X599918Y205429D01*
G01X599909Y199133D02*
X599900Y199134D01*
G01X599919Y199130D02*
X599909Y199133D01*
G01X599926Y199124D02*
X599919Y199130D01*
G01X599909Y202282D02*
X599900Y202283D01*
G01X599919Y202279D02*
X599909Y202282D01*
G01X599926Y202274D02*
X599919Y202279D01*
G01X599909Y208581D02*
X599900Y208583D01*
G01X599919Y208578D02*
X599909Y208581D01*
G01X599926Y208573D02*
X599919Y208578D01*
G01X599909Y211731D02*
X599900Y211732D01*
G01X599919Y211728D02*
X599909Y211731D01*
G01X599926Y211723D02*
X599919Y211728D01*
G01X598996Y197948D02*
Y197942D01*
G01X598995Y197952D02*
X598996Y197948D01*
G01X598994Y197953D02*
X598995Y197952D01*
G01X598996Y201098D02*
Y201091D01*
G01X598995Y201101D02*
X598996Y201098D01*
G01X598994Y201102D02*
X598995Y201101D01*
G01X598996Y204247D02*
Y204241D01*
G01X598995Y204251D02*
X598996Y204247D01*
G01X598994Y204252D02*
X598995Y204251D01*
G01X598996Y207397D02*
Y207391D01*
G01X598995Y207400D02*
X598996Y207397D01*
G01X598994Y207402D02*
X598995Y207400D01*
G01X598996Y210546D02*
Y210540D01*
G01X598995Y210550D02*
X598996Y210546D01*
G01X598994Y210551D02*
X598995Y210550D01*
G01X598980Y201105D02*
X598994Y201102D01*
G01X598968Y201112D02*
X598980Y201105D01*
G01X598956Y201131D02*
X598968Y201112D01*
G01X598980Y210554D02*
X598994Y210551D01*
G01X598968Y210561D02*
X598980Y210554D01*
G01X598956Y210580D02*
X598968Y210561D01*
G01X599919Y197945D02*
X599922Y197947D01*
G01X599915Y197944D02*
X599919Y197945D01*
G01X599912Y197943D02*
X599915Y197944D01*
G01X599909Y197942D02*
X599912Y197943D01*
G01X599905Y197942D02*
X599909D01*
G01X599902D02*
X599905D01*
G01X598979Y199142D02*
X598976Y199140D01*
G01X598982Y199143D02*
X598979Y199142D01*
G01X598985Y199144D02*
X598982Y199143D01*
G01X598989Y199144D02*
X598985D01*
G01X598993Y199145D02*
X598989Y199144D01*
G01X598996Y199145D02*
X598993D01*
G01X599919Y201095D02*
X599922Y201096D01*
G01X599915Y201094D02*
X599919Y201095D01*
G01X599912Y201093D02*
X599915Y201094D01*
G01X599909Y201092D02*
X599912Y201093D01*
G01X599905Y201091D02*
X599909Y201092D01*
G01X599902Y201091D02*
X599905D01*
G01X598979Y202291D02*
X598976Y202290D01*
G01X598982Y202293D02*
X598979Y202291D01*
G01X598985Y202294D02*
X598982Y202293D01*
G01X598989Y202294D02*
X598985D01*
G01X598993Y202295D02*
X598989Y202294D01*
G01X598996Y202295D02*
X598993D01*
G01X599919Y204244D02*
X599922Y204246D01*
G01X599915Y204243D02*
X599919Y204244D01*
G01X599912Y204242D02*
X599915Y204243D01*
G01X599909Y204241D02*
X599912Y204242D01*
G01X599905Y204241D02*
X599909D01*
G01X599902D02*
X599905D01*
G01X598979Y205441D02*
X598976Y205439D01*
G01X598982Y205442D02*
X598979Y205441D01*
G01X598985Y205443D02*
X598982Y205442D01*
G01X598989Y205444D02*
X598985Y205443D01*
G01X598993Y205444D02*
X598989D01*
G01X598996D02*
X598993D01*
G01X599919Y207394D02*
X599922Y207396D01*
G01X599915Y207393D02*
X599919Y207394D01*
G01X599912Y207392D02*
X599915Y207393D01*
G01X599909Y207391D02*
X599912Y207392D01*
G01X599905Y207391D02*
X599909D01*
G01X599902D02*
X599905D01*
G01X598979Y208591D02*
X598976Y208589D01*
G01X598982Y208592D02*
X598979Y208591D01*
G01X598985Y208593D02*
X598982Y208592D01*
G01X598989Y208593D02*
X598985D01*
G01X598993Y208594D02*
X598989Y208593D01*
G01X598996Y208594D02*
X598993D01*
G01X599919Y210544D02*
X599922Y210545D01*
G01X599915Y210543D02*
X599919Y210544D01*
G01X599912Y210541D02*
X599915Y210543D01*
G01X599909Y210541D02*
X599912D01*
G01X599905Y210540D02*
X599909Y210541D01*
G01X599902Y210540D02*
X599905D01*
G01X598979Y211740D02*
X598976Y211739D01*
G01X598982Y211741D02*
X598979Y211740D01*
G01X598985Y211743D02*
X598982Y211741D01*
G01X598989Y211743D02*
X598985D01*
G01X598993Y211744D02*
X598989Y211743D01*
G01X598996Y211744D02*
X598993D01*
G01X598209Y201142D02*
X597776D01*
G01X598583D02*
X598209D01*
G01Y207441D02*
X597776D01*
G01X598583D02*
X598209D01*
G01Y210591D02*
X597776D01*
G01X598583D02*
X598209D01*
G01X599931Y199132D02*
X599935Y199127D01*
G01X599927Y199137D02*
X599931Y199132D01*
G01X599921Y199141D02*
X599927Y199137D01*
G01X599915Y199143D02*
X599921Y199141D01*
G01X599908Y199145D02*
X599915Y199143D01*
G01X599902Y199145D02*
X599908D01*
G01X599931Y202282D02*
X599935Y202277D01*
G01X599927Y202286D02*
X599931Y202282D01*
G01X599921Y202290D02*
X599927Y202286D01*
G01X599915Y202293D02*
X599921Y202290D01*
G01X599908Y202294D02*
X599915Y202293D01*
G01X599902Y202295D02*
X599908Y202294D01*
G01X599931Y205431D02*
X599935Y205426D01*
G01X599927Y205436D02*
X599931Y205431D01*
G01X599921Y205440D02*
X599927Y205436D01*
G01X599915Y205442D02*
X599921Y205440D01*
G01X599908Y205444D02*
X599915Y205442D01*
G01X599902Y205444D02*
X599908D01*
G01X599931Y208581D02*
X599935Y208576D01*
G01X599927Y208585D02*
X599931Y208581D01*
G01X599921Y208589D02*
X599927Y208585D01*
G01X599915Y208592D02*
X599921Y208589D01*
G01X599908Y208594D02*
X599915Y208592D01*
G01X599902Y208594D02*
X599908D01*
G01X599931Y211731D02*
X599935Y211726D01*
G01X599927Y211735D02*
X599931Y211731D01*
G01X599921Y211739D02*
X599927Y211735D01*
G01X599915Y211741D02*
X599921Y211739D01*
G01X599908Y211743D02*
X599915Y211741D01*
G01X599902Y211744D02*
X599908Y211743D01*
G01X598957Y201121D02*
Y201128D01*
G01X598960Y201114D02*
X598957Y201121D01*
G01X598963Y201108D02*
X598960Y201114D01*
G01X598968Y201102D02*
X598963Y201108D01*
G01X598974Y201097D02*
X598968Y201102D01*
G01X598981Y201094D02*
X598974Y201097D01*
G01X598989Y201092D02*
X598981Y201094D01*
G01X598996Y201091D02*
X598989Y201092D01*
G01X598957Y204270D02*
Y204278D01*
G01X598960Y204264D02*
X598957Y204270D01*
G01X598963Y204257D02*
X598960Y204264D01*
G01X598968Y204252D02*
X598963Y204257D01*
G01X598974Y204247D02*
X598968Y204252D01*
G01X598981Y204244D02*
X598974Y204247D01*
G01X598989Y204242D02*
X598981Y204244D01*
G01X598996Y204241D02*
X598989Y204242D01*
G01X598957Y207420D02*
Y207428D01*
G01X598960Y207413D02*
X598957Y207420D01*
G01X598963Y207407D02*
X598960Y207413D01*
G01X598968Y207401D02*
X598963Y207407D01*
G01X598974Y207396D02*
X598968Y207401D01*
G01X598981Y207393D02*
X598974Y207396D01*
G01X598989Y207391D02*
X598981Y207393D01*
G01X598996Y207391D02*
X598989D01*
G01X598957Y210570D02*
Y210577D01*
G01X598960Y210563D02*
X598957Y210570D01*
G01X598963Y210557D02*
X598960Y210563D01*
G01X598968Y210551D02*
X598963Y210557D01*
G01X598974Y210546D02*
X598968Y210551D01*
G01X598981Y210543D02*
X598974Y210546D01*
G01X598989Y210541D02*
X598981Y210543D01*
G01X598996Y210540D02*
X598989Y210541D01*
G01X599911Y211731D02*
X599920Y211727D01*
G01X599900Y211732D02*
X599911Y211731D01*
G01X598979Y204255D02*
X598994Y204252D01*
G01X598967Y204263D02*
X598979Y204255D01*
G01X598955Y204283D02*
X598967Y204263D01*
G01X599941Y197986D02*
Y197979D01*
G01X599940Y197991D02*
X599941Y197986D01*
G01X599939Y197992D02*
X599940Y197991D01*
G01X599941Y201136D02*
Y201128D01*
G01X599940Y201141D02*
X599941Y201136D01*
G01X599939Y201142D02*
X599940Y201141D01*
G01X599941Y204285D02*
Y204278D01*
G01X599940Y204290D02*
X599941Y204285D01*
G01X599939Y204291D02*
X599940Y204290D01*
G01X599941Y207435D02*
Y207428D01*
G01X599940Y207440D02*
X599941Y207435D01*
G01X599939Y207441D02*
X599940Y207440D01*
G01X599941Y210585D02*
Y210577D01*
G01X599940Y210589D02*
X599941Y210585D01*
G01X599939Y210591D02*
X599940Y210589D01*
G01X598979Y197956D02*
X598994Y197953D01*
G01X598966Y197964D02*
X598979Y197956D01*
G01X598955Y197985D02*
X598966Y197964D01*
G01X599940Y199115D02*
X599941Y199108D01*
G01X599939Y199121D02*
X599940Y199115D01*
G01X599935Y199127D02*
X599939Y199121D01*
G01X599940Y202265D02*
X599941Y202258D01*
G01X599939Y202271D02*
X599940Y202265D01*
G01X599935Y202277D02*
X599939Y202271D01*
G01X599940Y205414D02*
X599941Y205407D01*
G01X599939Y205420D02*
X599940Y205414D01*
G01X599935Y205426D02*
X599939Y205420D01*
G01X599940Y208564D02*
X599941Y208557D01*
G01X599939Y208570D02*
X599940Y208564D01*
G01X599935Y208576D02*
X599939Y208570D01*
G01X599940Y211713D02*
X599941Y211707D01*
G01X599939Y211720D02*
X599940Y211713D01*
G01X599935Y211726D02*
X599939Y211720D01*
G01X599902Y197948D02*
Y197942D01*
G01X599901Y197952D02*
X599902Y197948D01*
G01X599900Y197953D02*
X599901Y197952D01*
G01X599902Y201097D02*
Y201091D01*
G01X599901Y201101D02*
X599902Y201097D01*
G01X599900Y201102D02*
X599901Y201101D01*
G01X599902Y204247D02*
Y204241D01*
G01X599901Y204251D02*
X599902Y204247D01*
G01X599900Y204252D02*
X599901Y204251D01*
G01X599902Y207396D02*
Y207391D01*
G01X599901Y207400D02*
X599902Y207396D01*
G01X599900Y207402D02*
X599901Y207400D01*
G01X599902Y210546D02*
Y210540D01*
G01X599901Y210550D02*
X599902Y210546D01*
G01X599900Y210551D02*
X599901Y210550D01*
G01X598974Y207407D02*
X598994Y207402D01*
G01X598961Y207419D02*
X598974Y207407D01*
G01X598954Y207437D02*
X598961Y207419D01*
G01X598959Y199114D02*
X598954Y199094D01*
G01X598974Y199129D02*
X598959Y199114D01*
G01X598994Y199134D02*
X598974Y199129D01*
G01X598959Y202264D02*
X598954Y202244D01*
G01X598974Y202278D02*
X598959Y202264D01*
G01X598994Y202283D02*
X598974Y202278D01*
G01X598959Y205413D02*
X598954Y205394D01*
G01X598974Y205428D02*
X598959Y205413D01*
G01X598994Y205433D02*
X598974Y205428D01*
G01X598959Y208563D02*
X598954Y208543D01*
G01X598974Y208578D02*
X598959Y208563D01*
G01X598994Y208583D02*
X598974Y208578D01*
G01X598959Y211713D02*
X598954Y211693D01*
G01X598974Y211727D02*
X598959Y211713D01*
G01X598994Y211732D02*
X598974Y211727D01*
G01X599934Y197972D02*
X599939Y197992D01*
G01X599920Y197958D02*
X599934Y197972D01*
G01X599900Y197953D02*
X599920Y197958D01*
G01X599934Y201122D02*
X599939Y201142D01*
G01X599920Y201108D02*
X599934Y201122D01*
G01X599900Y201102D02*
X599920Y201108D01*
G01X599934Y204272D02*
X599939Y204291D01*
G01X599920Y204257D02*
X599934Y204272D01*
G01X599900Y204252D02*
X599920Y204257D01*
G01X599934Y207421D02*
X599939Y207441D01*
G01X599920Y207407D02*
X599934Y207421D01*
G01X599900Y207402D02*
X599920Y207407D01*
G01X599934Y210571D02*
X599939Y210591D01*
G01X599920Y210557D02*
X599934Y210571D01*
G01X599900Y210551D02*
X599920Y210557D01*
G01X599933Y205415D02*
X599926Y205424D01*
G01X599938Y205405D02*
X599933Y205415D01*
G01X599940Y205394D02*
X599938Y205405D01*
G01X599933Y199116D02*
X599926Y199124D01*
G01X599938Y199106D02*
X599933Y199116D01*
G01X599940Y199094D02*
X599938Y199106D01*
G01X599933Y202265D02*
X599926Y202274D01*
G01X599938Y202255D02*
X599933Y202265D01*
G01X599940Y202244D02*
X599938Y202255D01*
G01X599933Y208565D02*
X599926Y208573D01*
G01X599938Y208554D02*
X599933Y208565D01*
G01X599940Y208543D02*
X599938Y208554D01*
G01X599933Y211714D02*
X599926Y211723D01*
G01X599938Y211704D02*
X599933Y211714D01*
G01X599940Y211693D02*
X599938Y211704D01*
G01X598956Y210585D02*
X598957Y210577D01*
G01X598956Y210589D02*
Y210585D01*
G01Y210580D02*
Y210589D01*
G01X598997Y211917D02*
X598996Y211929D01*
G01X598994Y211904D02*
X598997Y211917D01*
G01X598994Y211890D02*
Y211904D01*
G01X598997Y208767D02*
X598996Y208780D01*
G01X598994Y208754D02*
X598997Y208767D01*
G01X598994Y208741D02*
Y208754D01*
G01X598997Y205618D02*
X598996Y205630D01*
G01X598994Y205605D02*
X598997Y205618D01*
G01X598994Y205591D02*
Y205605D01*
G01X598997Y202468D02*
X598996Y202480D01*
G01X598994Y202455D02*
X598997Y202468D01*
G01X598994Y202441D02*
Y202455D01*
G01X598997Y199319D02*
X598996Y199331D01*
G01X598994Y199306D02*
X598997Y199319D01*
G01X598994Y199292D02*
Y199306D01*
G01Y210380D02*
X598993Y210393D01*
G01X598997Y210367D02*
X598994Y210380D01*
G01X598996Y210354D02*
X598997Y210367D01*
G01X598994Y207230D02*
X598993Y207244D01*
G01X598997Y207217D02*
X598994Y207230D01*
G01X598996Y207205D02*
X598997Y207217D01*
G01X598994Y204081D02*
X598993Y204094D01*
G01X598997Y204068D02*
X598994Y204081D01*
G01X598996Y204055D02*
X598997Y204068D01*
G01X598994Y200931D02*
X598993Y200944D01*
G01X598997Y200918D02*
X598994Y200931D01*
G01X598996Y200906D02*
X598997Y200918D01*
G01X598994Y197781D02*
X598993Y197795D01*
G01X598997Y197769D02*
X598994Y197781D01*
G01X598996Y197756D02*
X598997Y197769D01*
G01X599904Y211904D02*
X599905Y211890D01*
G01X599901Y211917D02*
X599904Y211904D01*
G01X599902Y211929D02*
X599901Y211917D01*
G01X599904Y208754D02*
X599905Y208741D01*
G01X599901Y208767D02*
X599904Y208754D01*
G01X599902Y208780D02*
X599901Y208767D01*
G01X599904Y205604D02*
X599905Y205591D01*
G01X599901Y205617D02*
X599904Y205604D01*
G01X599902Y205630D02*
X599901Y205617D01*
G01X599904Y202455D02*
X599905Y202441D01*
G01X599901Y202468D02*
X599904Y202455D01*
G01X599902Y202480D02*
X599901Y202468D01*
G01X599904Y199305D02*
X599905Y199292D01*
G01X599901Y199318D02*
X599904Y199305D01*
G01X599902Y199331D02*
X599901Y199318D01*
G01X598956Y204285D02*
X598957Y204278D01*
G01X598956Y204290D02*
Y204285D01*
G01X598955Y204283D02*
X598956Y204290D01*
G01X599901Y210367D02*
X599902Y210354D01*
G01X599904Y210380D02*
X599901Y210367D01*
G01X599905Y210393D02*
X599904Y210380D01*
G01X599901Y207217D02*
X599902Y207205D01*
G01X599904Y207230D02*
X599901Y207217D01*
G01X599905Y207244D02*
X599904Y207230D01*
G01X599901Y204068D02*
X599902Y204055D01*
G01X599904Y204081D02*
X599901Y204068D01*
G01X599905Y204094D02*
X599904Y204081D01*
G01X599901Y200918D02*
X599902Y200906D01*
G01X599904Y200931D02*
X599901Y200918D01*
G01X599905Y200944D02*
X599904Y200931D01*
G01X599901Y197769D02*
X599902Y197756D01*
G01X599904Y197781D02*
X599901Y197769D01*
G01X599905Y197795D02*
X599904Y197781D01*
G01X598956Y197987D02*
X598957Y197979D01*
G01X598956Y197991D02*
Y197987D01*
G01X598955Y197985D02*
X598956Y197991D01*
G01X598970Y211724D02*
X598994Y211732D01*
G01X598958Y211709D02*
X598970Y211724D01*
G01X598957Y211703D02*
X598958Y211709D01*
G01X598970Y208574D02*
X598994Y208583D01*
G01X598958Y208560D02*
X598970Y208574D01*
G01X598957Y208553D02*
X598958Y208560D01*
G01X598970Y205425D02*
X598994Y205433D01*
G01X598958Y205410D02*
X598970Y205425D01*
G01X598957Y205404D02*
X598958Y205410D01*
G01X598970Y202275D02*
X598994Y202283D01*
G01X598958Y202261D02*
X598970Y202275D01*
G01X598957Y202254D02*
X598958Y202261D01*
G01X598970Y199126D02*
X598994Y199134D01*
G01X598958Y199111D02*
X598970Y199126D01*
G01X598957Y199104D02*
X598958Y199111D01*
G01X599941Y211699D02*
Y211706D01*
G01Y211695D02*
Y211699D01*
G01X599940Y211693D02*
X599941Y211695D01*
G01Y208550D02*
Y208557D01*
G01Y208545D02*
Y208550D01*
G01X599940Y208543D02*
X599941Y208545D01*
G01Y205400D02*
Y205407D01*
G01Y205396D02*
Y205400D01*
G01X599940Y205394D02*
X599941Y205396D01*
G01Y202250D02*
Y202257D01*
G01Y202246D02*
Y202250D01*
G01X599940Y202244D02*
X599941Y202246D01*
G01Y199101D02*
Y199108D01*
G01Y199096D02*
Y199101D01*
G01X599940Y199094D02*
X599941Y199096D01*
G01X598956Y207435D02*
X598957Y207428D01*
G01X598956Y207440D02*
Y207435D01*
G01X598954Y207437D02*
X598956Y207440D01*
G01Y201136D02*
X598957Y201128D01*
G01X598956Y201141D02*
Y201136D01*
G01X598954Y201138D02*
X598956Y201141D01*
G01X599902Y211737D02*
Y211744D01*
G01X599901Y211734D02*
X599902Y211737D01*
G01X599900Y211732D02*
X599901Y211734D01*
G01X599902Y208588D02*
Y208594D01*
G01X599901Y208584D02*
X599902Y208588D01*
G01X599900Y208583D02*
X599901Y208584D01*
G01X599902Y205438D02*
Y205444D01*
G01X599901Y205435D02*
X599902Y205438D01*
G01X599900Y205433D02*
X599901Y205435D01*
G01X599902Y202289D02*
Y202295D01*
G01X599901Y202285D02*
X599902Y202289D01*
G01X599900Y202283D02*
X599901Y202285D01*
G01X599902Y199139D02*
Y199145D01*
G01X599901Y199135D02*
X599902Y199139D01*
G01X599900Y199134D02*
X599901Y199135D01*
G01X598956Y211699D02*
X598957Y211707D01*
G01X598956Y211694D02*
Y211699D01*
G01X598954Y211693D02*
X598956Y211694D01*
G01Y208550D02*
X598957Y208557D01*
G01X598956Y208545D02*
Y208550D01*
G01X598954Y208543D02*
X598956Y208545D01*
G01Y205400D02*
X598957Y205407D01*
G01X598956Y205395D02*
Y205400D01*
G01X598954Y205394D02*
X598956Y205395D01*
G01Y202250D02*
X598957Y202258D01*
G01X598956Y202246D02*
Y202250D01*
G01X598954Y202244D02*
X598956Y202246D01*
G01Y199101D02*
X598957Y199108D01*
G01X598956Y199096D02*
Y199101D01*
G01X598954Y199094D02*
X598956Y199096D01*
G01X599939Y210565D02*
X599941Y210577D01*
G01X599932Y210554D02*
X599939Y210565D01*
G01X599922Y210545D02*
X599932Y210554D01*
G01X599939Y207415D02*
X599941Y207428D01*
G01X599932Y207404D02*
X599939Y207415D01*
G01X599922Y207396D02*
X599932Y207404D01*
G01X599939Y204265D02*
X599941Y204278D01*
G01X599932Y204254D02*
X599939Y204265D01*
G01X599922Y204246D02*
X599932Y204254D01*
G01X599939Y201116D02*
X599941Y201128D01*
G01X599932Y201105D02*
X599939Y201116D01*
G01X599922Y201096D02*
X599932Y201105D01*
G01X599939Y197966D02*
X599941Y197979D01*
G01X599932Y197955D02*
X599939Y197966D01*
G01X599922Y197947D02*
X599932Y197955D01*
G01X598995Y211737D02*
Y211744D01*
G01Y211733D02*
Y211737D01*
G01X598993Y211732D02*
X598995Y211733D01*
G01Y208588D02*
Y208594D01*
G01Y208584D02*
Y208588D01*
G01X598993Y208583D02*
X598995Y208584D01*
G01Y205438D02*
Y205444D01*
G01Y205434D02*
Y205438D01*
G01X598993Y205433D02*
X598995Y205434D01*
G01Y202289D02*
Y202295D01*
G01Y202285D02*
Y202289D01*
G01X598993Y202283D02*
X598995Y202285D01*
G01Y199139D02*
Y199145D01*
G01Y199135D02*
Y199139D01*
G01X598993Y199134D02*
X598995Y199135D01*
G01X598957Y211713D02*
Y211707D01*
G01X598959Y211719D02*
X598957Y211713D01*
G01X598962Y211725D02*
X598959Y211719D01*
G01X598966Y211730D02*
X598962Y211725D01*
G01X598970Y211735D02*
X598966Y211730D01*
G01X598976Y211739D02*
X598970Y211735D01*
G01X598957Y208563D02*
Y208557D01*
G01X598959Y208570D02*
X598957Y208563D01*
G01X598962Y208575D02*
X598959Y208570D01*
G01X598966Y208581D02*
X598962Y208575D01*
G01X598970Y208585D02*
X598966Y208581D01*
G01X598976Y208589D02*
X598970Y208585D01*
G01X598957Y205414D02*
Y205407D01*
G01X598959Y205420D02*
X598957Y205414D01*
G01X598962Y205426D02*
X598959Y205420D01*
G01X598966Y205431D02*
X598962Y205426D01*
G01X598970Y205435D02*
X598966Y205431D01*
G01X598976Y205439D02*
X598970Y205435D01*
G01X598957Y202264D02*
Y202258D01*
G01X598959Y202270D02*
X598957Y202264D01*
G01X598962Y202276D02*
X598959Y202270D01*
G01X598966Y202281D02*
X598962Y202276D01*
G01X598970Y202286D02*
X598966Y202281D01*
G01X598976Y202290D02*
X598970Y202286D01*
G01X598957Y199115D02*
Y199108D01*
G01X598959Y199121D02*
X598957Y199115D01*
G01X598962Y199126D02*
X598959Y199121D01*
G01X598966Y199132D02*
X598962Y199126D01*
G01X598970Y199136D02*
X598966Y199132D01*
G01X598976Y199140D02*
X598970Y199136D01*
G01X599912Y210553D02*
X599900Y210551D01*
G01X599922Y210558D02*
X599912Y210553D01*
G01Y207404D02*
X599900Y207402D01*
G01X599922Y207409D02*
X599912Y207404D01*
G01Y204254D02*
X599900Y204252D01*
G01X599922Y204259D02*
X599912Y204254D01*
G01Y201104D02*
X599900Y201102D01*
G01X599922Y201109D02*
X599912Y201104D01*
G01Y197955D02*
X599900Y197953D01*
G01X599922Y197960D02*
X599912Y197955D01*
G01X599941Y199097D02*
Y199108D01*
G01Y202246D02*
Y202257D01*
G01Y205396D02*
Y205407D01*
G01Y208546D02*
Y208557D01*
G01Y211695D02*
Y211706D01*
G01Y210394D02*
Y211890D01*
G01Y207244D02*
Y208740D01*
G01Y204094D02*
Y205591D01*
G01Y200945D02*
Y202441D01*
G01Y197795D02*
Y199291D01*
G01X599902Y197942D02*
Y197795D01*
G01Y201091D02*
Y200944D01*
G01Y202441D02*
Y202295D01*
G01Y199292D02*
Y199145D01*
G01Y207391D02*
Y207244D01*
G01Y204241D02*
Y204094D01*
G01Y205591D02*
Y205444D01*
G01Y210540D02*
Y210393D01*
G01Y211890D02*
Y211744D01*
G01Y208741D02*
Y208594D01*
G01X598996Y210393D02*
Y210540D01*
G01Y211744D02*
Y211891D01*
G01Y208594D02*
Y208741D01*
G01Y207243D02*
Y207391D01*
G01Y204094D02*
Y204241D01*
G01Y205444D02*
Y205591D01*
G01Y200944D02*
Y201091D01*
G01Y202295D02*
Y202442D01*
G01Y199145D02*
Y199292D01*
G01Y197794D02*
Y197942D01*
G01X598957Y202441D02*
Y200945D01*
G01Y199291D02*
Y197795D01*
G01Y205591D02*
Y204094D01*
G01Y211890D02*
Y210394D01*
G01Y208740D02*
Y207244D01*
G01X597776Y199134D02*
Y197953D01*
G01Y202283D02*
Y201102D01*
G01Y208583D02*
Y207402D01*
G01Y205433D02*
Y204252D01*
G01Y211732D02*
Y210551D01*
G01X597441Y220197D02*
Y195787D01*
G01X597047D02*
Y220197D01*
G01X594016Y210551D02*
Y211732D01*
G01Y207402D02*
Y208583D01*
G01Y204252D02*
Y205433D01*
G01Y201102D02*
Y202283D01*
G01Y197953D02*
Y199134D01*
G01X599941Y210577D02*
Y210588D01*
G01Y207428D02*
Y207439D01*
G01Y204278D02*
Y204289D01*
G01Y201128D02*
Y201139D01*
G01Y197979D02*
Y197990D01*
G01X598954Y207437D02*
X598843Y207441D01*
G01X598954Y201138D02*
X598843Y201142D01*
G01X598954Y210587D02*
X598843Y210591D01*
G01X599902Y211929D02*
X598996D01*
G01X599941Y211890D02*
X598957D01*
G01X599900Y211732D02*
X594016D01*
G01Y211693D02*
X599940D01*
G01X599939Y210591D02*
X594016D01*
G01X599900Y210551D02*
X594016D01*
G01X598957Y210394D02*
X599941D01*
G01X598996Y210354D02*
X599902D01*
G01Y208780D02*
X598996D01*
G01X599941Y208740D02*
X598957D01*
G01X599900Y208583D02*
X594016D01*
G01Y208543D02*
X599940D01*
G01X599939Y207441D02*
X594016D01*
G01X599900Y207402D02*
X594016D01*
G01X598957Y207244D02*
X599941D01*
G01X598996Y207205D02*
X599902D01*
G01Y205630D02*
X598996D01*
G01X599941Y205591D02*
X598957D01*
G01X599900Y205433D02*
X594016D01*
G01Y205394D02*
X599940D01*
G01X599939Y204291D02*
X594016D01*
G01X599900Y204252D02*
X594016D01*
G01X598957Y204094D02*
X599941D01*
G01X598996Y204055D02*
X599902D01*
G01Y202480D02*
X598996D01*
G01X599941Y202441D02*
X598957D01*
G01X599900Y202283D02*
X594016D01*
G01Y202244D02*
X599940D01*
G01X599939Y201142D02*
X594016D01*
G01X599900Y201102D02*
X594016D01*
G01X598957Y200945D02*
X599941D01*
G01X598996Y200906D02*
X599902D01*
G01Y199331D02*
X598996D01*
G01X599941Y199291D02*
X598957D01*
G01X599900Y199134D02*
X594016D01*
G01Y199094D02*
X599940D01*
G01X599939Y197992D02*
X594016D01*
G01X599900Y197953D02*
X594016D01*
G01X598957Y197795D02*
X599941D01*
G01X598996Y197756D02*
X599902D01*
G01X600394Y195787D02*
X597047D01*
G01X598957Y213731D02*
Y213727D01*
G01X598958Y213724D02*
X598957Y213731D01*
G01X598970Y213709D02*
X598958Y213724D01*
G01X598994Y213701D02*
X598970Y213709D01*
G01X598957Y216880D02*
Y216876D01*
G01X598958Y216874D02*
X598957Y216880D01*
G01X598970Y216859D02*
X598958Y216874D01*
G01X598994Y216850D02*
X598970Y216859D01*
G01X599909Y214881D02*
X599900Y214882D01*
G01X599919Y214878D02*
X599909Y214881D01*
G01X599926Y214872D02*
X599919Y214878D01*
G01X599909Y218030D02*
X599900Y218031D01*
G01X599919Y218027D02*
X599909Y218030D01*
G01X599926Y218022D02*
X599919Y218027D01*
G01X598996Y213696D02*
Y213690D01*
G01X598995Y213700D02*
X598996Y213696D01*
G01X598994Y213701D02*
X598995Y213700D01*
G01X598996Y216846D02*
Y216839D01*
G01X598995Y216849D02*
X598996Y216846D01*
G01X598994Y216850D02*
X598995Y216849D01*
G01X599940Y213719D02*
X599941Y213727D01*
G01X599938Y213713D02*
X599940Y213719D01*
G01X599934Y213706D02*
X599938Y213713D01*
G01X599930Y213700D02*
X599934Y213706D01*
G01X599923Y213696D02*
X599930Y213700D01*
G01X599917Y213693D02*
X599923Y213696D01*
G01X599909Y213691D02*
X599917Y213693D01*
G01X599902Y213690D02*
X599909Y213691D01*
G01X598979Y214890D02*
X598976Y214888D01*
G01X598982Y214891D02*
X598979Y214890D01*
G01X598985Y214892D02*
X598982Y214891D01*
G01X598989Y214893D02*
X598985Y214892D01*
G01X598993Y214893D02*
X598989D01*
G01X598996D02*
X598993D01*
G01X599919Y216843D02*
X599922Y216844D01*
G01X599915Y216842D02*
X599919Y216843D01*
G01X599912Y216841D02*
X599915Y216842D01*
G01X599909Y216840D02*
X599912Y216841D01*
G01X599905Y216839D02*
X599909Y216840D01*
G01X599902Y216839D02*
X599905D01*
G01X598979Y218039D02*
X598976Y218038D01*
G01X598982Y218041D02*
X598979Y218039D01*
G01X598985Y218042D02*
X598982Y218041D01*
G01X598989Y218042D02*
X598985D01*
G01X598993Y218043D02*
X598989Y218042D01*
G01X598996Y218043D02*
X598993D01*
G01X599931Y214880D02*
X599935Y214875D01*
G01X599927Y214885D02*
X599931Y214880D01*
G01X599921Y214889D02*
X599927Y214885D01*
G01X599915Y214891D02*
X599921Y214889D01*
G01X599908Y214893D02*
X599915Y214891D01*
G01X599902Y214893D02*
X599908D01*
G01X599931Y218030D02*
X599935Y218025D01*
G01X599927Y218034D02*
X599931Y218030D01*
G01X599921Y218038D02*
X599927Y218034D01*
G01X599915Y218041D02*
X599921Y218038D01*
G01X599908Y218043D02*
X599915Y218041D01*
G01X599902Y218043D02*
X599908D01*
G01X598957Y213719D02*
Y213727D01*
G01X598960Y213713D02*
X598957Y213719D01*
G01X598963Y213706D02*
X598960Y213713D01*
G01X598968Y213700D02*
X598963Y213706D01*
G01X598974Y213696D02*
X598968Y213700D01*
G01X598981Y213693D02*
X598974Y213696D01*
G01X598989Y213691D02*
X598981Y213693D01*
G01X598996Y213690D02*
X598989Y213691D01*
G01X598957Y216869D02*
Y216876D01*
G01X598960Y216862D02*
X598957Y216869D01*
G01X598963Y216856D02*
X598960Y216862D01*
G01X598968Y216850D02*
X598963Y216856D01*
G01X598974Y216845D02*
X598968Y216850D01*
G01X598981Y216842D02*
X598974Y216845D01*
G01X598989Y216840D02*
X598981Y216842D01*
G01X598996Y216839D02*
X598989Y216840D01*
G01X599911Y214881D02*
X599920Y214876D01*
G01X599900Y214882D02*
X599911Y214881D01*
G01Y218030D02*
X599920Y218026D01*
G01X599900Y218031D02*
X599911Y218030D01*
G01X598979Y213704D02*
X598994Y213701D01*
G01X598967Y213711D02*
X598979Y213704D01*
G01X598955Y213731D02*
X598967Y213711D01*
G01X599941Y213734D02*
Y213727D01*
G01X599940Y213739D02*
X599941Y213734D01*
G01X599939Y213740D02*
X599940Y213739D01*
G01X599941Y216884D02*
Y216876D01*
G01X599940Y216889D02*
X599941Y216884D01*
G01X599939Y216890D02*
X599940Y216889D01*
G01X598979Y216853D02*
X598994Y216850D01*
G01X598967Y216861D02*
X598979Y216853D01*
G01X598955Y216881D02*
X598967Y216861D01*
G01X599940Y214863D02*
X599941Y214856D01*
G01X599939Y214869D02*
X599940Y214863D01*
G01X599935Y214875D02*
X599939Y214869D01*
G01X599940Y218013D02*
X599941Y218006D01*
G01X599939Y218019D02*
X599940Y218013D01*
G01X599935Y218025D02*
X599939Y218019D01*
G01X599902Y216845D02*
Y216839D01*
G01X599901Y216849D02*
X599902Y216845D01*
G01X599900Y216850D02*
X599901Y216849D01*
G01X598959Y214862D02*
X598954Y214843D01*
G01X598974Y214877D02*
X598959Y214862D01*
G01X598994Y214882D02*
X598974Y214877D01*
G01X598959Y218012D02*
X598954Y217992D01*
G01X598974Y218026D02*
X598959Y218012D01*
G01X598994Y218031D02*
X598974Y218026D01*
G01X599934Y213720D02*
X599939Y213740D01*
G01X599920Y213706D02*
X599934Y213720D01*
G01X599900Y213701D02*
X599920Y213706D01*
G01X599934Y216870D02*
X599939Y216890D01*
G01X599920Y216856D02*
X599934Y216870D01*
G01X599900Y216850D02*
X599920Y216856D01*
G01X599933Y214864D02*
X599926Y214872D01*
G01X599938Y214854D02*
X599933Y214864D01*
G01X599940Y214843D02*
X599938Y214854D01*
G01X599933Y218013D02*
X599926Y218022D01*
G01X599938Y218003D02*
X599933Y218013D01*
G01X599940Y217992D02*
X599938Y218003D01*
G01X598997Y218216D02*
X598996Y218228D01*
G01X598994Y218203D02*
X598997Y218216D01*
G01X598994Y218189D02*
Y218203D01*
G01X598997Y215067D02*
X598996Y215079D01*
G01X598994Y215054D02*
X598997Y215067D01*
G01X598994Y215040D02*
Y215054D01*
G01X598956Y216884D02*
X598957Y216876D01*
G01X598956Y216889D02*
Y216884D01*
G01Y216881D02*
Y216889D01*
G01X598994Y216679D02*
X598993Y216693D01*
G01X598997Y216666D02*
X598994Y216679D01*
G01X598996Y216654D02*
X598997Y216666D01*
G01X598994Y213530D02*
X598993Y213543D01*
G01X598997Y213517D02*
X598994Y213530D01*
G01X598996Y213504D02*
X598997Y213517D01*
G01X599904Y218203D02*
X599905Y218189D01*
G01X599901Y218216D02*
X599904Y218203D01*
G01X599902Y218228D02*
X599901Y218216D01*
G01X599904Y215053D02*
X599905Y215040D01*
G01X599901Y215066D02*
X599904Y215053D01*
G01X599902Y215079D02*
X599901Y215066D01*
G01X598956Y213734D02*
X598957Y213727D01*
G01X598956Y213739D02*
Y213734D01*
G01X598955Y213732D02*
X598956Y213739D01*
G01X599901Y216666D02*
X599902Y216654D01*
G01X599904Y216679D02*
X599901Y216666D01*
G01X599905Y216693D02*
X599904Y216679D01*
G01X599901Y213517D02*
X599902Y213504D01*
G01X599904Y213530D02*
X599901Y213517D01*
G01X599905Y213543D02*
X599904Y213530D01*
G01X598970Y218023D02*
X598994Y218031D01*
G01X598958Y218009D02*
X598970Y218023D01*
G01X598957Y218002D02*
X598958Y218009D01*
G01X598970Y214874D02*
X598994Y214882D01*
G01X598958Y214859D02*
X598970Y214874D01*
G01X598957Y214852D02*
X598958Y214859D01*
G01X599941Y217998D02*
Y218006D01*
G01Y217994D02*
Y217998D01*
G01X599940Y217992D02*
X599941Y217994D01*
G01Y214849D02*
Y214856D01*
G01Y214844D02*
Y214849D01*
G01X599940Y214843D02*
X599941Y214844D01*
G01X599902Y218037D02*
Y218043D01*
G01X599901Y218033D02*
X599902Y218037D01*
G01X599900Y218031D02*
X599901Y218033D01*
G01X599902Y214887D02*
Y214893D01*
G01X599901Y214883D02*
X599902Y214887D01*
G01X599900Y214882D02*
X599901Y214883D01*
G01X598956Y217998D02*
X598957Y218006D01*
G01X598956Y217994D02*
Y217998D01*
G01X598954Y217992D02*
X598956Y217994D01*
G01Y214849D02*
X598957Y214856D01*
G01X598956Y214844D02*
Y214849D01*
G01X598954Y214843D02*
X598956Y214844D01*
G01X599939Y216864D02*
X599941Y216876D01*
G01X599932Y216853D02*
X599939Y216864D01*
G01X599922Y216844D02*
X599932Y216853D01*
G01X598995Y218037D02*
Y218043D01*
G01Y218033D02*
Y218037D01*
G01X598993Y218031D02*
X598995Y218033D01*
G01Y214887D02*
Y214893D01*
G01Y214883D02*
Y214887D01*
G01X598993Y214882D02*
X598995Y214883D01*
G01X598957Y218012D02*
Y218006D01*
G01X598959Y218019D02*
X598957Y218012D01*
G01X598962Y218024D02*
X598959Y218019D01*
G01X598966Y218030D02*
X598962Y218024D01*
G01X598970Y218034D02*
X598966Y218030D01*
G01X598976Y218038D02*
X598970Y218034D01*
G01X598957Y214863D02*
Y214856D01*
G01X598959Y214869D02*
X598957Y214863D01*
G01X598962Y214874D02*
X598959Y214869D01*
G01X598966Y214880D02*
X598962Y214874D01*
G01X598970Y214884D02*
X598966Y214880D01*
G01X598976Y214888D02*
X598970Y214884D01*
G01X599912Y216852D02*
X599900Y216850D01*
G01X599922Y216857D02*
X599912Y216852D01*
G01Y213703D02*
X599900Y213701D01*
G01X599922Y213708D02*
X599912Y213703D01*
G01X599941Y214845D02*
Y214856D01*
G01Y217994D02*
Y218006D01*
G01X600394Y299232D02*
Y220197D01*
G01X599941Y216693D02*
Y218189D01*
G01Y213543D02*
Y215039D01*
G01X599902Y216839D02*
Y216693D01*
G01Y213690D02*
Y213543D01*
G01Y215040D02*
Y214893D01*
G01Y218189D02*
Y218043D01*
G01X598996D02*
Y218190D01*
G01Y216692D02*
Y216839D01*
G01Y213543D02*
Y213690D01*
G01Y214893D02*
Y215040D01*
G01X598957Y215039D02*
Y213543D01*
G01Y218189D02*
Y216693D01*
G01X597776Y218031D02*
Y216850D01*
G01Y214882D02*
Y213701D01*
G01X594016Y216850D02*
Y218031D01*
G01Y213701D02*
Y214882D01*
G01X599941Y216876D02*
Y216887D01*
G01Y213727D02*
Y213738D01*
G01X599900Y213701D02*
X599904Y213690D01*
G01X598843Y216890D02*
X598955Y216881D01*
G01X600394Y220197D02*
X597047D01*
G01X599902Y218228D02*
X598996D01*
G01X599941Y218189D02*
X598957D01*
G01X599900Y218031D02*
X594016D01*
G01Y217992D02*
X599940D01*
G01X599939Y216890D02*
X594016D01*
G01X599900Y216850D02*
X594016D01*
G01X598957Y216693D02*
X599941D01*
G01X598996Y216654D02*
X599902D01*
G01Y215079D02*
X598996D01*
G01X599941Y215039D02*
X598957D01*
G01X599900Y214882D02*
X594016D01*
G01Y214843D02*
X599940D01*
G01X599939Y213740D02*
X594016D01*
G01X599900Y213701D02*
X594016D01*
G01X598957Y213543D02*
X599941D01*
G01X598996Y213504D02*
X599902D01*
G01X605315Y307579D02*
G03X604134Y306398I0J-1181D01*
G01Y297854D02*
Y306398D01*
G01X597047Y316083D02*
Y300335D01*
G01X618701Y307618D02*
X597047D01*
G01X600394Y299232D02*
X614764D01*
G01X600394Y297854D02*
X604134D01*
G01X600394Y296988D02*
X615354D01*
G01X602165Y295492D02*
X610039D01*
G01X603346Y294311D02*
X608858D01*
G01X606693Y302894D02*
X604383Y307123D01*
G01X602165Y295492D02*
X603346Y294311D01*
G01X597047Y300335D02*
X600394Y296988D01*
G01X604528Y317264D02*
G03X603937Y316673I0J-591D01*
G01X599016Y318051D02*
G03X597047Y316083I-1J-1968D01*
G01X603937Y310571D02*
Y316673D01*
G01X616732Y318051D02*
X599016D01*
G01X611811Y312146D02*
X603937D01*
G01Y310571D02*
X611811D01*
G01X567913Y374803D02*
G03X569094I591J0D01*
G01Y368504D02*
G03X567913I-590J0D01*
G01X565945D02*
G03X564764I-590J0D01*
G01Y374803D02*
G03X565945I590J0D01*
G01X567913D02*
G03X569094I591J0D01*
G01Y368504D02*
G03X567913I-590J0D01*
G01X565945D02*
G03X564764I-590J0D01*
G01Y374803D02*
G03X565945I590J0D01*
G01X567913D02*
X565945D01*
G01X564764D02*
X563976D01*
G01X567913D02*
X565945D01*
G01X564764D02*
X563976D01*
G01X569882D02*
X569094D01*
G01X569882D02*
X569094D01*
G01X569882Y373819D02*
X563976D01*
G01Y373622D02*
X569882D01*
G01X563976Y369685D02*
X569882D01*
G01Y369488D02*
X563976D01*
G01X569094Y368504D02*
X569882D01*
G01X569094D02*
X569882D01*
G01X565945D02*
X567913D01*
G01X563976D02*
X564764D01*
G01X565945D02*
X567913D01*
G01X563976D02*
X564764D01*
G01X569882D02*
Y374803D01*
G01Y368504D02*
Y374803D01*
G01X563976Y368504D02*
Y374803D01*
G01D02*
Y368504D01*
G01X603937Y592067D02*
G03X604528Y591476I591J0D01*
G01X597047Y592657D02*
G03X599016Y590689I1969J1D01*
G01X611811Y598169D02*
X603937D01*
G01Y596594D02*
X611811D01*
G01X616732Y590689D02*
X599016D01*
G01X603937Y598169D02*
Y592067D01*
G01X597047Y608406D02*
Y592657D01*
G01X604134Y602343D02*
G03X605315Y601161I1181J-1D01*
G01X603346Y614429D02*
X602165Y613248D01*
G01X600394Y611752D02*
X597047Y608406D01*
G01X608858Y614429D02*
X603346D01*
G01X610039Y613248D02*
X602165D01*
G01X615354Y611752D02*
X600394D01*
G01X604134Y610886D02*
X600394D01*
G01Y609508D02*
X614764D01*
G01X618701Y601122D02*
X597047D01*
G01X604383Y601617D02*
X606693Y605846D01*
G01X604134Y602343D02*
Y610886D01*
G01X603346Y614429D02*
Y747067D01*
G01X602165Y613248D02*
Y748248D01*
G01X600394Y648543D02*
Y609508D01*
G01X598956Y663341D02*
X598957Y663333D01*
G01X598956Y663345D02*
Y663341D01*
G01Y663336D02*
Y663345D01*
G01X598997Y670972D02*
X598996Y670984D01*
G01X598994Y670959D02*
X598997Y670972D01*
G01X598994Y670945D02*
Y670959D01*
G01X598997Y667822D02*
X598996Y667835D01*
G01X598994Y667809D02*
X598997Y667822D01*
G01X598994Y667796D02*
Y667809D01*
G01X598997Y664673D02*
X598996Y664685D01*
G01X598994Y664660D02*
X598997Y664673D01*
G01X598994Y664646D02*
Y664660D01*
G01X598997Y661523D02*
X598996Y661535D01*
G01X598994Y661510D02*
X598997Y661523D01*
G01X598994Y661496D02*
Y661510D01*
G01X598997Y658374D02*
X598996Y658386D01*
G01X598994Y658361D02*
X598997Y658374D01*
G01X598994Y658347D02*
Y658361D01*
G01X598997Y655224D02*
X598996Y655236D01*
G01X598994Y655211D02*
X598997Y655224D01*
G01X598994Y655197D02*
Y655211D01*
G01X598997Y652074D02*
X598996Y652087D01*
G01X598994Y652061D02*
X598997Y652074D01*
G01X598994Y652048D02*
Y652061D01*
G01X598956Y669640D02*
X598957Y669632D01*
G01X598956Y669644D02*
Y669640D01*
G01Y669637D02*
Y669644D01*
G01X598994Y669435D02*
X598993Y669448D01*
G01X598997Y669422D02*
X598994Y669435D01*
G01X598996Y669409D02*
X598997Y669422D01*
G01X598994Y666285D02*
X598993Y666299D01*
G01X598997Y666272D02*
X598994Y666285D01*
G01X598996Y666260D02*
X598997Y666272D01*
G01X598994Y663136D02*
X598993Y663149D01*
G01X598997Y663123D02*
X598994Y663136D01*
G01X598996Y663110D02*
X598997Y663123D01*
G01X598994Y659986D02*
X598993Y660000D01*
G01X598997Y659973D02*
X598994Y659986D01*
G01X598996Y659961D02*
X598997Y659973D01*
G01X598994Y656837D02*
X598993Y656850D01*
G01X598997Y656824D02*
X598994Y656837D01*
G01X598996Y656811D02*
X598997Y656824D01*
G01X598994Y653687D02*
X598993Y653700D01*
G01X598997Y653674D02*
X598994Y653687D01*
G01X598996Y653661D02*
X598997Y653674D01*
G01X598994Y650537D02*
X598993Y650551D01*
G01X598997Y650524D02*
X598994Y650537D01*
G01X598996Y650512D02*
X598997Y650524D01*
G01X599904Y670959D02*
X599905Y670945D01*
G01X599901Y670972D02*
X599904Y670959D01*
G01X599902Y670984D02*
X599901Y670972D01*
G01X599904Y667809D02*
X599905Y667796D01*
G01X599901Y667822D02*
X599904Y667809D01*
G01X599902Y667835D02*
X599901Y667822D01*
G01X599904Y664659D02*
X599905Y664646D01*
G01X599901Y664672D02*
X599904Y664659D01*
G01X599902Y664685D02*
X599901Y664672D01*
G01X599904Y661510D02*
X599905Y661496D01*
G01X599901Y661523D02*
X599904Y661510D01*
G01X599902Y661535D02*
X599901Y661523D01*
G01X599904Y658360D02*
X599905Y658347D01*
G01X599901Y658373D02*
X599904Y658360D01*
G01X599902Y658386D02*
X599901Y658373D01*
G01X599904Y655211D02*
X599905Y655197D01*
G01X599901Y655224D02*
X599904Y655211D01*
G01X599902Y655236D02*
X599901Y655224D01*
G01X599904Y652061D02*
X599905Y652048D01*
G01X599901Y652074D02*
X599904Y652061D01*
G01X599902Y652087D02*
X599901Y652074D01*
G01X598956Y657041D02*
X598957Y657034D01*
G01X598956Y657046D02*
Y657041D01*
G01X598955Y657039D02*
X598956Y657046D01*
G01Y666490D02*
X598957Y666483D01*
G01X598956Y666495D02*
Y666490D01*
G01X598955Y666488D02*
X598956Y666495D01*
G01X599901Y669422D02*
X599902Y669409D01*
G01X599904Y669435D02*
X599901Y669422D01*
G01X599905Y669448D02*
X599904Y669435D01*
G01X599901Y666272D02*
X599902Y666260D01*
G01X599904Y666285D02*
X599901Y666272D01*
G01X599905Y666299D02*
X599904Y666285D01*
G01X599901Y663123D02*
X599902Y663110D01*
G01X599904Y663136D02*
X599901Y663123D01*
G01X599905Y663149D02*
X599904Y663136D01*
G01X599901Y659973D02*
X599902Y659961D01*
G01X599904Y659986D02*
X599901Y659973D01*
G01X599905Y660000D02*
X599904Y659986D01*
G01X599901Y656824D02*
X599902Y656811D01*
G01X599904Y656837D02*
X599901Y656824D01*
G01X599905Y656850D02*
X599904Y656837D01*
G01X599901Y653674D02*
X599902Y653661D01*
G01X599904Y653687D02*
X599901Y653674D01*
G01X599905Y653700D02*
X599904Y653687D01*
G01X599901Y650524D02*
X599902Y650512D01*
G01X599904Y650537D02*
X599901Y650524D01*
G01X599905Y650551D02*
X599904Y650537D01*
G01X598956Y650743D02*
X598957Y650735D01*
G01X598956Y650747D02*
Y650743D01*
G01X598955Y650741D02*
X598956Y650747D01*
G01X598980Y653861D02*
X598994Y653858D01*
G01X598968Y653868D02*
X598980Y653861D01*
G01X598956Y653887D02*
X598968Y653868D01*
G01X598980Y663310D02*
X598994Y663307D01*
G01X598968Y663317D02*
X598980Y663310D01*
G01X598956Y663335D02*
X598968Y663317D01*
G01X598979Y657011D02*
X598994Y657008D01*
G01X598967Y657019D02*
X598979Y657011D01*
G01X598955Y657039D02*
X598967Y657019D01*
G01X598979Y666459D02*
X598994Y666457D01*
G01X598967Y666467D02*
X598979Y666459D01*
G01X598955Y666487D02*
X598967Y666467D01*
G01X599941Y650742D02*
Y650735D01*
G01X599940Y650747D02*
X599941Y650742D01*
G01X599939Y650748D02*
X599940Y650747D01*
G01X599941Y653892D02*
Y653884D01*
G01X599940Y653896D02*
X599941Y653892D01*
G01X599939Y653898D02*
X599940Y653896D01*
G01X599941Y657041D02*
Y657034D01*
G01X599940Y657046D02*
X599941Y657041D01*
G01X599939Y657047D02*
X599940Y657046D01*
G01X599941Y660191D02*
Y660183D01*
G01X599940Y660196D02*
X599941Y660191D01*
G01X599939Y660197D02*
X599940Y660196D01*
G01X599941Y663341D02*
Y663333D01*
G01X599940Y663345D02*
X599941Y663341D01*
G01X599939Y663346D02*
X599940Y663345D01*
G01X599941Y666490D02*
Y666483D01*
G01X599940Y666495D02*
X599941Y666490D01*
G01X599939Y666496D02*
X599940Y666495D01*
G01X599941Y669640D02*
Y669632D01*
G01X599940Y669644D02*
X599941Y669640D01*
G01X599939Y669646D02*
X599940Y669644D01*
G01X598979Y669609D02*
X598994Y669606D01*
G01X598967Y669617D02*
X598979Y669609D01*
G01X598955Y669637D02*
X598967Y669617D01*
G01X598979Y650712D02*
X598994Y650709D01*
G01X598966Y650720D02*
X598979Y650712D01*
G01X598955Y650741D02*
X598966Y650720D01*
G01X599940Y651871D02*
X599941Y651864D01*
G01X599939Y651877D02*
X599940Y651871D01*
G01X599935Y651883D02*
X599939Y651877D01*
G01X599940Y655020D02*
X599941Y655014D01*
G01X599939Y655027D02*
X599940Y655020D01*
G01X599935Y655033D02*
X599939Y655027D01*
G01X599940Y658170D02*
X599941Y658163D01*
G01X599939Y658176D02*
X599940Y658170D01*
G01X599935Y658182D02*
X599939Y658176D01*
G01X599940Y661320D02*
X599941Y661313D01*
G01X599939Y661326D02*
X599940Y661320D01*
G01X599935Y661332D02*
X599939Y661326D01*
G01X599940Y664469D02*
X599941Y664463D01*
G01X599939Y664476D02*
X599940Y664469D01*
G01X599935Y664481D02*
X599939Y664476D01*
G01X599940Y667619D02*
X599941Y667612D01*
G01X599939Y667625D02*
X599940Y667619D01*
G01X599935Y667631D02*
X599939Y667625D01*
G01X599940Y670769D02*
X599941Y670762D01*
G01X599939Y670775D02*
X599940Y670769D01*
G01X599935Y670781D02*
X599939Y670775D01*
G01X599902Y650704D02*
Y650698D01*
G01X599901Y650707D02*
X599902Y650704D01*
G01X599900Y650709D02*
X599901Y650707D01*
G01X599902Y653853D02*
Y653847D01*
G01X599901Y653857D02*
X599902Y653853D01*
G01X599900Y653858D02*
X599901Y653857D01*
G01X599902Y657003D02*
Y656997D01*
G01X599901Y657007D02*
X599902Y657003D01*
G01X599900Y657008D02*
X599901Y657007D01*
G01X599902Y660152D02*
Y660146D01*
G01X599901Y660156D02*
X599902Y660152D01*
G01X599900Y660157D02*
X599901Y660156D01*
G01X599902Y663302D02*
Y663296D01*
G01X599901Y663306D02*
X599902Y663302D01*
G01X599900Y663307D02*
X599901Y663306D01*
G01X599902Y669601D02*
Y669595D01*
G01X599901Y669605D02*
X599902Y669601D01*
G01X599900Y669606D02*
X599901Y669605D01*
G01X598974Y660163D02*
X598994Y660157D01*
G01X598961Y660175D02*
X598974Y660163D01*
G01X598954Y660193D02*
X598961Y660175D01*
G01X599933Y658171D02*
X599926Y658180D01*
G01X599938Y658161D02*
X599933Y658171D01*
G01X599940Y658150D02*
X599938Y658161D01*
G01X599933Y651872D02*
X599926Y651880D01*
G01X599938Y651861D02*
X599933Y651872D01*
G01X599940Y651850D02*
X599938Y651861D01*
G01X599933Y655021D02*
X599926Y655030D01*
G01X599938Y655011D02*
X599933Y655021D01*
G01X599940Y655000D02*
X599938Y655011D01*
G01X599933Y661320D02*
X599926Y661329D01*
G01X599938Y661310D02*
X599933Y661320D01*
G01X599940Y661299D02*
X599938Y661310D01*
G01X599933Y664470D02*
X599926Y664479D01*
G01X599938Y664460D02*
X599933Y664470D01*
G01X599940Y664449D02*
X599938Y664460D01*
G01X599933Y667620D02*
X599926Y667628D01*
G01X599938Y667609D02*
X599933Y667620D01*
G01X599940Y667598D02*
X599938Y667609D01*
G01X599933Y670769D02*
X599926Y670778D01*
G01X599938Y670759D02*
X599933Y670769D01*
G01X599940Y670748D02*
X599938Y670759D01*
G01X598970Y670779D02*
X598994Y670787D01*
G01X598958Y670765D02*
X598970Y670779D01*
G01X598957Y670758D02*
X598958Y670765D01*
G01X598970Y667630D02*
X598994Y667638D01*
G01X598958Y667615D02*
X598970Y667630D01*
G01X598957Y667608D02*
X598958Y667615D01*
G01X598970Y664480D02*
X598994Y664488D01*
G01X598958Y664465D02*
X598970Y664480D01*
G01X598957Y664459D02*
X598958Y664465D01*
G01X598970Y661330D02*
X598994Y661339D01*
G01X598958Y661316D02*
X598970Y661330D01*
G01X598957Y661309D02*
X598958Y661316D01*
G01X598970Y658181D02*
X598994Y658189D01*
G01X598958Y658166D02*
X598970Y658181D01*
G01X598957Y658159D02*
X598958Y658166D01*
G01X598970Y655031D02*
X598994Y655039D01*
G01X598958Y655017D02*
X598970Y655031D01*
G01X598957Y655010D02*
X598958Y655017D01*
G01X598970Y651881D02*
X598994Y651890D01*
G01X598958Y651867D02*
X598970Y651881D01*
G01X598957Y651860D02*
X598958Y651867D01*
G01X599941Y670754D02*
Y670761D01*
G01Y670750D02*
Y670754D01*
G01X599940Y670748D02*
X599941Y670750D01*
G01Y667605D02*
Y667612D01*
G01Y667600D02*
Y667605D01*
G01X599940Y667598D02*
X599941Y667600D01*
G01Y664455D02*
Y664462D01*
G01Y664451D02*
Y664455D01*
G01X599940Y664449D02*
X599941Y664451D01*
G01Y661306D02*
Y661313D01*
G01Y661301D02*
Y661306D01*
G01X599940Y661299D02*
X599941Y661301D01*
G01Y658156D02*
Y658163D01*
G01Y658152D02*
Y658156D01*
G01X599940Y658150D02*
X599941Y658152D01*
G01Y655006D02*
Y655013D01*
G01Y655002D02*
Y655006D01*
G01X599940Y655000D02*
X599941Y655002D01*
G01Y651857D02*
Y651864D01*
G01Y651852D02*
Y651857D01*
G01X599940Y651850D02*
X599941Y651852D01*
G01X598956Y660191D02*
X598957Y660183D01*
G01X598956Y660196D02*
Y660191D01*
G01X598954Y660193D02*
X598956Y660196D01*
G01X599909Y658188D02*
X599900Y658189D01*
G01X599918Y658185D02*
X599909Y658188D01*
G01X599926Y658180D02*
X599918Y658185D01*
G01X599909Y651889D02*
X599900Y651890D01*
G01X599919Y651885D02*
X599909Y651889D01*
G01X599926Y651880D02*
X599919Y651885D01*
G01X599909Y655038D02*
X599900Y655039D01*
G01X599919Y655035D02*
X599909Y655038D01*
G01X599926Y655030D02*
X599919Y655035D01*
G01X599909Y661337D02*
X599900Y661339D01*
G01X599919Y661334D02*
X599909Y661337D01*
G01X599926Y661329D02*
X599919Y661334D01*
G01X599909Y664487D02*
X599900Y664488D01*
G01X599919Y664484D02*
X599909Y664487D01*
G01X599926Y664479D02*
X599919Y664484D01*
G01X599909Y667637D02*
X599900Y667638D01*
G01X599919Y667633D02*
X599909Y667637D01*
G01X599926Y667628D02*
X599919Y667633D01*
G01X599909Y670786D02*
X599900Y670787D01*
G01X599919Y670783D02*
X599909Y670786D01*
G01X599926Y670778D02*
X599919Y670783D01*
G01X598996Y650704D02*
Y650698D01*
G01X598995Y650707D02*
X598996Y650704D01*
G01X598994Y650709D02*
X598995Y650707D01*
G01X598996Y653854D02*
Y653847D01*
G01X598995Y653857D02*
X598996Y653854D01*
G01X598994Y653858D02*
X598995Y653857D01*
G01X598996Y657003D02*
Y656997D01*
G01X598995Y657007D02*
X598996Y657003D01*
G01X598994Y657008D02*
X598995Y657007D01*
G01X598996Y660153D02*
Y660146D01*
G01X598995Y660156D02*
X598996Y660153D01*
G01X598994Y660157D02*
X598995Y660156D01*
G01X598996Y663302D02*
Y663296D01*
G01X598995Y663306D02*
X598996Y663302D01*
G01X598994Y663307D02*
X598995Y663306D01*
G01X598996Y666452D02*
Y666446D01*
G01X598995Y666456D02*
X598996Y666452D01*
G01X598994Y666457D02*
X598995Y666456D01*
G01X598996Y669602D02*
Y669595D01*
G01X598995Y669605D02*
X598996Y669602D01*
G01X598994Y669606D02*
X598995Y669605D01*
G01X598956Y653892D02*
X598957Y653884D01*
G01X598956Y653896D02*
Y653892D01*
G01X598954Y653894D02*
X598956Y653896D01*
G01X599902Y670793D02*
Y670799D01*
G01X599901Y670789D02*
X599902Y670793D01*
G01X599900Y670787D02*
X599901Y670789D01*
G01X599902Y667643D02*
Y667649D01*
G01X599901Y667639D02*
X599902Y667643D01*
G01X599900Y667638D02*
X599901Y667639D01*
G01X599902Y664493D02*
Y664500D01*
G01X599901Y664490D02*
X599902Y664493D01*
G01X599900Y664488D02*
X599901Y664490D01*
G01X599902Y661344D02*
Y661350D01*
G01X599901Y661340D02*
X599902Y661344D01*
G01X599900Y661339D02*
X599901Y661340D01*
G01X599902Y658194D02*
Y658200D01*
G01X599901Y658191D02*
X599902Y658194D01*
G01X599900Y658189D02*
X599901Y658191D01*
G01X599902Y655044D02*
Y655051D01*
G01X599901Y655041D02*
X599902Y655044D01*
G01X599900Y655039D02*
X599901Y655041D01*
G01X599902Y651895D02*
Y651901D01*
G01X599901Y651891D02*
X599902Y651895D01*
G01X599900Y651890D02*
X599901Y651891D01*
G01X598956Y670754D02*
X598957Y670762D01*
G01X598956Y670750D02*
Y670754D01*
G01X598954Y670748D02*
X598956Y670750D01*
G01Y667605D02*
X598957Y667612D01*
G01X598956Y667600D02*
Y667605D01*
G01X598954Y667598D02*
X598956Y667600D01*
G01Y664455D02*
X598957Y664463D01*
G01X598956Y664450D02*
Y664455D01*
G01X598954Y664449D02*
X598956Y664450D01*
G01Y661306D02*
X598957Y661313D01*
G01X598956Y661301D02*
Y661306D01*
G01X598954Y661299D02*
X598956Y661301D01*
G01Y658156D02*
X598957Y658163D01*
G01X598956Y658151D02*
Y658156D01*
G01X598954Y658150D02*
X598956Y658151D01*
G01Y655006D02*
X598957Y655014D01*
G01X598956Y655002D02*
Y655006D01*
G01X598954Y655000D02*
X598956Y655002D01*
G01Y651857D02*
X598957Y651864D01*
G01X598956Y651852D02*
Y651857D01*
G01X598954Y651850D02*
X598956Y651852D01*
G01X599911Y651889D02*
X599920Y651884D01*
G01X599900Y651890D02*
X599911Y651889D01*
G01Y655038D02*
X599920Y655034D01*
G01X599900Y655039D02*
X599911Y655038D01*
G01Y658188D02*
X599920Y658183D01*
G01X599900Y658189D02*
X599911Y658188D01*
G01Y661337D02*
X599920Y661333D01*
G01X599900Y661339D02*
X599911Y661337D01*
G01Y664487D02*
X599920Y664483D01*
G01X599900Y664488D02*
X599911Y664487D01*
G01X598957Y653888D02*
Y653884D01*
G01X598958Y653882D02*
X598957Y653888D01*
G01X598970Y653867D02*
X598958Y653882D01*
G01X598995Y653858D02*
X598970Y653867D01*
G01X598957Y657038D02*
Y657034D01*
G01X598958Y657031D02*
X598957Y657038D01*
G01X598970Y657016D02*
X598958Y657031D01*
G01X598994Y657008D02*
X598970Y657016D01*
G01X598957Y663337D02*
Y663333D01*
G01X598958Y663331D02*
X598957Y663337D01*
G01X598970Y663315D02*
X598958Y663331D01*
G01X598994Y663307D02*
X598970Y663315D01*
G01X598957Y666487D02*
Y666483D01*
G01X598958Y666480D02*
X598957Y666487D01*
G01X598970Y666465D02*
X598958Y666480D01*
G01X598994Y666457D02*
X598970Y666465D01*
G01X598957Y650739D02*
Y650735D01*
G01X598958Y650732D02*
X598957Y650739D01*
G01X598970Y650717D02*
X598958Y650732D01*
G01X598994Y650709D02*
X598970Y650717D01*
G01X598957Y669636D02*
Y669632D01*
G01X598958Y669630D02*
X598957Y669636D01*
G01X598970Y669615D02*
X598958Y669630D01*
G01X598994Y669606D02*
X598970Y669615D01*
G01X598957Y660187D02*
Y660183D01*
G01X598958Y660182D02*
X598957Y660187D01*
G01X598968Y660167D02*
X598958Y660182D01*
G01X598991Y660158D02*
X598968Y660167D01*
G01X599939Y669620D02*
X599941Y669632D01*
G01X599932Y669609D02*
X599939Y669620D01*
G01X599922Y669600D02*
X599932Y669609D01*
G01X599939Y663320D02*
X599941Y663333D01*
G01X599932Y663309D02*
X599939Y663320D01*
G01X599922Y663301D02*
X599932Y663309D01*
G01X599939Y660171D02*
X599941Y660183D01*
G01X599932Y660160D02*
X599939Y660171D01*
G01X599922Y660152D02*
X599932Y660160D01*
G01X599939Y657021D02*
X599941Y657034D01*
G01X599932Y657010D02*
X599939Y657021D01*
G01X599922Y657002D02*
X599932Y657010D01*
G01X599939Y653872D02*
X599941Y653884D01*
G01X599932Y653861D02*
X599939Y653872D01*
G01X599922Y653852D02*
X599932Y653861D01*
G01X599939Y650722D02*
X599941Y650735D01*
G01X599932Y650711D02*
X599939Y650722D01*
G01X599922Y650703D02*
X599932Y650711D01*
G01X598995Y670793D02*
Y670799D01*
G01Y670789D02*
Y670793D01*
G01X598993Y670787D02*
X598995Y670789D01*
G01Y667643D02*
Y667649D01*
G01Y667639D02*
Y667643D01*
G01X598993Y667638D02*
X598995Y667639D01*
G01Y664493D02*
Y664500D01*
G01Y664489D02*
Y664493D01*
G01X598993Y664488D02*
X598995Y664489D01*
G01Y661344D02*
Y661350D01*
G01Y661340D02*
Y661344D01*
G01X598993Y661339D02*
X598995Y661340D01*
G01Y658194D02*
Y658200D01*
G01Y658190D02*
Y658194D01*
G01X598993Y658189D02*
X598995Y658190D01*
G01Y655044D02*
Y655051D01*
G01Y655041D02*
Y655044D01*
G01X598993Y655039D02*
X598995Y655041D01*
G01Y651895D02*
Y651901D01*
G01Y651891D02*
Y651895D01*
G01X598993Y651890D02*
X598995Y651891D01*
G01X598957Y670768D02*
Y670762D01*
G01X598959Y670774D02*
X598957Y670768D01*
G01X598962Y670780D02*
X598959Y670774D01*
G01X598966Y670785D02*
X598962Y670780D01*
G01X598970Y670790D02*
X598966Y670785D01*
G01X598976Y670794D02*
X598970Y670790D01*
G01X598957Y667619D02*
Y667612D01*
G01X598959Y667625D02*
X598957Y667619D01*
G01X598962Y667630D02*
X598959Y667625D01*
G01X598966Y667636D02*
X598962Y667630D01*
G01X598970Y667640D02*
X598966Y667636D01*
G01X598976Y667644D02*
X598970Y667640D01*
G01X598957Y664469D02*
Y664463D01*
G01X598959Y664475D02*
X598957Y664469D01*
G01X598962Y664481D02*
X598959Y664475D01*
G01X598966Y664486D02*
X598962Y664481D01*
G01X598970Y664491D02*
X598966Y664486D01*
G01X598976Y664494D02*
X598970Y664491D01*
G01X598957Y661319D02*
Y661313D01*
G01X598959Y661326D02*
X598957Y661319D01*
G01X598962Y661331D02*
X598959Y661326D01*
G01X598966Y661337D02*
X598962Y661331D01*
G01X598970Y661341D02*
X598966Y661337D01*
G01X598976Y661345D02*
X598970Y661341D01*
G01X598957Y658170D02*
Y658163D01*
G01X598959Y658176D02*
X598957Y658170D01*
G01X598962Y658181D02*
X598959Y658176D01*
G01X598966Y658187D02*
X598962Y658181D01*
G01X598970Y658191D02*
X598966Y658187D01*
G01X598976Y658195D02*
X598970Y658191D01*
G01X598957Y655020D02*
Y655014D01*
G01X598959Y655026D02*
X598957Y655020D01*
G01X598962Y655032D02*
X598959Y655026D01*
G01X598966Y655037D02*
X598962Y655032D01*
G01X598970Y655042D02*
X598966Y655037D01*
G01X598976Y655046D02*
X598970Y655042D01*
G01X598957Y651870D02*
Y651864D01*
G01X598959Y651877D02*
X598957Y651870D01*
G01X598962Y651882D02*
X598959Y651877D01*
G01X598966Y651888D02*
X598962Y651882D01*
G01X598970Y651892D02*
X598966Y651888D01*
G01X598976Y651896D02*
X598970Y651892D01*
G01X599940Y666475D02*
X599941Y666483D01*
G01X599938Y666469D02*
X599940Y666475D01*
G01X599934Y666462D02*
X599938Y666469D01*
G01X599930Y666456D02*
X599934Y666462D01*
G01X599923Y666452D02*
X599930Y666456D01*
G01X599917Y666448D02*
X599923Y666452D01*
G01X599909Y666446D02*
X599917Y666448D01*
G01X599902Y666446D02*
X599909D01*
G01X599919Y650701D02*
X599922Y650703D01*
G01X599915Y650700D02*
X599919Y650701D01*
G01X599912Y650699D02*
X599915Y650700D01*
G01X599909Y650698D02*
X599912Y650699D01*
G01X599905Y650698D02*
X599909D01*
G01X599902D02*
X599905D01*
G01X598979Y651898D02*
X598976Y651896D01*
G01X598982Y651899D02*
X598979Y651898D01*
G01X598985Y651900D02*
X598982Y651899D01*
G01X598989Y651900D02*
X598985D01*
G01X598993Y651901D02*
X598989Y651900D01*
G01X598996Y651901D02*
X598993D01*
G01X599919Y653851D02*
X599922Y653852D01*
G01X599915Y653850D02*
X599919Y653851D01*
G01X599912Y653848D02*
X599915Y653850D01*
G01X599909Y653848D02*
X599912D01*
G01X599905Y653847D02*
X599909Y653848D01*
G01X599902Y653847D02*
X599905D01*
G01X598979Y655047D02*
X598976Y655046D01*
G01X598982Y655048D02*
X598979Y655047D01*
G01X598985Y655050D02*
X598982Y655048D01*
G01X598989Y655050D02*
X598985D01*
G01X598993Y655051D02*
X598989Y655050D01*
G01X598996Y655051D02*
X598993D01*
G01X599919Y657000D02*
X599922Y657002D01*
G01X599915Y656999D02*
X599919Y657000D01*
G01X599912Y656998D02*
X599915Y656999D01*
G01X599909Y656997D02*
X599912Y656998D01*
G01X599905Y656997D02*
X599909D01*
G01X599902D02*
X599905D01*
G01X598979Y658197D02*
X598976Y658195D01*
G01X598982Y658198D02*
X598979Y658197D01*
G01X598985Y658199D02*
X598982Y658198D01*
G01X598989Y658200D02*
X598985Y658199D01*
G01X598993Y658200D02*
X598989D01*
G01X598996D02*
X598993D01*
G01X599919Y660150D02*
X599922Y660152D01*
G01X599915Y660149D02*
X599919Y660150D01*
G01X599912Y660148D02*
X599915Y660149D01*
G01X599909Y660147D02*
X599912Y660148D01*
G01X599905Y660146D02*
X599909Y660147D01*
G01X599902Y660146D02*
X599905D01*
G01X598979Y661346D02*
X598976Y661345D01*
G01X598982Y661348D02*
X598979Y661346D01*
G01X598985Y661349D02*
X598982Y661348D01*
G01X598989Y661349D02*
X598985D01*
G01X598993Y661350D02*
X598989Y661349D01*
G01X598996Y661350D02*
X598993D01*
G01X599919Y663300D02*
X599922Y663301D01*
G01X599915Y663298D02*
X599919Y663300D01*
G01X599912Y663297D02*
X599915Y663298D01*
G01X599909Y663296D02*
X599912Y663297D01*
G01X599905Y663296D02*
X599909D01*
G01X599902D02*
X599905D01*
G01X598979Y664496D02*
X598976Y664494D01*
G01X598982Y664497D02*
X598979Y664496D01*
G01X598985Y664498D02*
X598982Y664497D01*
G01X598989Y664499D02*
X598985Y664498D01*
G01X598993Y664500D02*
X598989Y664499D01*
G01X598996Y664500D02*
X598993D01*
G01X598979Y667646D02*
X598976Y667644D01*
G01X598982Y667647D02*
X598979Y667646D01*
G01X598985Y667648D02*
X598982Y667647D01*
G01X598989Y667648D02*
X598985D01*
G01X598993Y667649D02*
X598989Y667648D01*
G01X598996Y667649D02*
X598993D01*
G01X599919Y669599D02*
X599922Y669600D01*
G01X599915Y669598D02*
X599919Y669599D01*
G01X599912Y669596D02*
X599915Y669598D01*
G01X599909Y669596D02*
X599912D01*
G01X599905Y669595D02*
X599909Y669596D01*
G01X599902Y669595D02*
X599905D01*
G01X598979Y670795D02*
X598976Y670794D01*
G01X598982Y670796D02*
X598979Y670795D01*
G01X598985Y670798D02*
X598982Y670796D01*
G01X598989Y670798D02*
X598985D01*
G01X598993Y670799D02*
X598989Y670798D01*
G01X598996Y670799D02*
X598993D01*
G01X598209Y653898D02*
X597776D01*
G01X598583D02*
X598209D01*
G01Y660197D02*
X597776D01*
G01X598583D02*
X598209D01*
G01Y663346D02*
X597776D01*
G01X598583D02*
X598209D01*
G01X599931Y651888D02*
X599935Y651883D01*
G01X599927Y651893D02*
X599931Y651888D01*
G01X599921Y651896D02*
X599927Y651893D01*
G01X599915Y651899D02*
X599921Y651896D01*
G01X599908Y651901D02*
X599915Y651899D01*
G01X599902Y651901D02*
X599908D01*
G01X599931Y655038D02*
X599935Y655033D01*
G01X599927Y655042D02*
X599931Y655038D01*
G01X599921Y655046D02*
X599927Y655042D01*
G01X599915Y655048D02*
X599921Y655046D01*
G01X599908Y655050D02*
X599915Y655048D01*
G01X599902Y655051D02*
X599908Y655050D01*
G01X599931Y658187D02*
X599935Y658182D01*
G01X599927Y658192D02*
X599931Y658187D01*
G01X599921Y658196D02*
X599927Y658192D01*
G01X599915Y658198D02*
X599921Y658196D01*
G01X599908Y658200D02*
X599915Y658198D01*
G01X599902Y658200D02*
X599908D01*
G01X599931Y661337D02*
X599935Y661332D01*
G01X599927Y661341D02*
X599931Y661337D01*
G01X599921Y661345D02*
X599927Y661341D01*
G01X599915Y661348D02*
X599921Y661345D01*
G01X599908Y661350D02*
X599915Y661348D01*
G01X599902Y661350D02*
X599908D01*
G01X599931Y664487D02*
X599935Y664481D01*
G01X599927Y664491D02*
X599931Y664487D01*
G01X599921Y664495D02*
X599927Y664491D01*
G01X599915Y664497D02*
X599921Y664495D01*
G01X599908Y664499D02*
X599915Y664497D01*
G01X599902Y664500D02*
X599908Y664499D01*
G01X599931Y667636D02*
X599935Y667631D01*
G01X599927Y667641D02*
X599931Y667636D01*
G01X599921Y667644D02*
X599927Y667641D01*
G01X599915Y667647D02*
X599921Y667644D01*
G01X599908Y667649D02*
X599915Y667647D01*
G01X599902Y667649D02*
X599908D01*
G01X599931Y670786D02*
X599935Y670781D01*
G01X599927Y670790D02*
X599931Y670786D01*
G01X599921Y670794D02*
X599927Y670790D01*
G01X599915Y670796D02*
X599921Y670794D01*
G01X599908Y670798D02*
X599915Y670796D01*
G01X599902Y670799D02*
X599908Y670798D01*
G01X598957Y650727D02*
Y650735D01*
G01X598960Y650720D02*
X598957Y650727D01*
G01X598963Y650714D02*
X598960Y650720D01*
G01X598968Y650708D02*
X598963Y650714D01*
G01X598974Y650704D02*
X598968Y650708D01*
G01X598981Y650700D02*
X598974Y650704D01*
G01X598989Y650698D02*
X598981Y650700D01*
G01X598996Y650698D02*
X598989D01*
G01X598957Y653877D02*
Y653884D01*
G01X598960Y653870D02*
X598957Y653877D01*
G01X598963Y653864D02*
X598960Y653870D01*
G01X598968Y653858D02*
X598963Y653864D01*
G01X598974Y653853D02*
X598968Y653858D01*
G01X598981Y653850D02*
X598974Y653853D01*
G01X598989Y653848D02*
X598981Y653850D01*
G01X598996Y653847D02*
X598989Y653848D01*
G01X598957Y657026D02*
Y657034D01*
G01X598960Y657020D02*
X598957Y657026D01*
G01X598963Y657013D02*
X598960Y657020D01*
G01X598968Y657007D02*
X598963Y657013D01*
G01X598974Y657003D02*
X598968Y657007D01*
G01X598981Y657000D02*
X598974Y657003D01*
G01X598989Y656998D02*
X598981Y657000D01*
G01X598996Y656997D02*
X598989Y656998D01*
G01X598957Y660176D02*
Y660183D01*
G01X598960Y660169D02*
X598957Y660176D01*
G01X598963Y660163D02*
X598960Y660169D01*
G01X598968Y660157D02*
X598963Y660163D01*
G01X598974Y660152D02*
X598968Y660157D01*
G01X598981Y660149D02*
X598974Y660152D01*
G01X598989Y660147D02*
X598981Y660149D01*
G01X598996Y660146D02*
X598989Y660147D01*
G01X598957Y663326D02*
Y663333D01*
G01X598960Y663319D02*
X598957Y663326D01*
G01X598963Y663313D02*
X598960Y663319D01*
G01X598968Y663307D02*
X598963Y663313D01*
G01X598974Y663302D02*
X598968Y663307D01*
G01X598981Y663299D02*
X598974Y663302D01*
G01X598989Y663297D02*
X598981Y663299D01*
G01X598996Y663296D02*
X598989Y663297D01*
G01X598957Y666475D02*
Y666483D01*
G01X598960Y666469D02*
X598957Y666475D01*
G01X598963Y666462D02*
X598960Y666469D01*
G01X598968Y666456D02*
X598963Y666462D01*
G01X598974Y666452D02*
X598968Y666456D01*
G01X598981Y666448D02*
X598974Y666452D01*
G01X598989Y666446D02*
X598981Y666448D01*
G01X598996Y666446D02*
X598989D01*
G01X598957Y669625D02*
Y669632D01*
G01X598960Y669618D02*
X598957Y669625D01*
G01X598963Y669612D02*
X598960Y669618D01*
G01X598968Y669606D02*
X598963Y669612D01*
G01X598974Y669601D02*
X598968Y669606D01*
G01X598981Y669598D02*
X598974Y669601D01*
G01X598989Y669596D02*
X598981Y669598D01*
G01X598996Y669595D02*
X598989Y669596D01*
G01X599911Y667637D02*
X599920Y667632D01*
G01X599900Y667638D02*
X599911Y667637D01*
G01Y670786D02*
X599920Y670782D01*
G01X599900Y670787D02*
X599911Y670786D01*
G01X599912Y669608D02*
X599900Y669606D01*
G01X599922Y669613D02*
X599912Y669608D01*
G01Y666459D02*
X599900Y666457D01*
G01X599922Y666464D02*
X599912Y666459D01*
G01Y663309D02*
X599900Y663307D01*
G01X599922Y663314D02*
X599912Y663309D01*
G01Y660159D02*
X599900Y660157D01*
G01X599922Y660165D02*
X599912Y660159D01*
G01Y657010D02*
X599900Y657008D01*
G01X599922Y657015D02*
X599912Y657010D01*
G01Y653860D02*
X599900Y653858D01*
G01X599922Y653865D02*
X599912Y653860D01*
G01Y650711D02*
X599900Y650709D01*
G01X599922Y650716D02*
X599912Y650711D01*
G01X598959Y651870D02*
X598954Y651850D01*
G01X598974Y651885D02*
X598959Y651870D01*
G01X598994Y651890D02*
X598974Y651885D01*
G01X598959Y655020D02*
X598954Y655000D01*
G01X598974Y655034D02*
X598959Y655020D01*
G01X598994Y655039D02*
X598974Y655034D01*
G01X598959Y658169D02*
X598954Y658150D01*
G01X598974Y658184D02*
X598959Y658169D01*
G01X598994Y658189D02*
X598974Y658184D01*
G01X598959Y661319D02*
X598954Y661299D01*
G01X598974Y661333D02*
X598959Y661319D01*
G01X598994Y661339D02*
X598974Y661333D01*
G01X598959Y664469D02*
X598954Y664449D01*
G01X598974Y664483D02*
X598959Y664469D01*
G01X598994Y664488D02*
X598974Y664483D01*
G01X598959Y667618D02*
X598954Y667598D01*
G01X598974Y667633D02*
X598959Y667618D01*
G01X598994Y667638D02*
X598974Y667633D01*
G01X598959Y670768D02*
X598954Y670748D01*
G01X598974Y670782D02*
X598959Y670768D01*
G01X598994Y670787D02*
X598974Y670782D01*
G01X599934Y650728D02*
X599939Y650748D01*
G01X599920Y650714D02*
X599934Y650728D01*
G01X599900Y650709D02*
X599920Y650714D01*
G01X599934Y653878D02*
X599939Y653898D01*
G01X599920Y653864D02*
X599934Y653878D01*
G01X599900Y653858D02*
X599920Y653864D01*
G01X599934Y657028D02*
X599939Y657047D01*
G01X599920Y657013D02*
X599934Y657028D01*
G01X599900Y657008D02*
X599920Y657013D01*
G01X599934Y660177D02*
X599939Y660197D01*
G01X599920Y660163D02*
X599934Y660177D01*
G01X599900Y660157D02*
X599920Y660163D01*
G01X599934Y663327D02*
X599939Y663346D01*
G01X599920Y663313D02*
X599934Y663327D01*
G01X599900Y663307D02*
X599920Y663313D01*
G01X599934Y666476D02*
X599939Y666496D01*
G01X599920Y666462D02*
X599934Y666476D01*
G01X599900Y666457D02*
X599920Y666462D01*
G01X599934Y669626D02*
X599939Y669646D01*
G01X599920Y669612D02*
X599934Y669626D01*
G01X599900Y669606D02*
X599920Y669612D01*
G01X598843Y669646D02*
X598955Y669637D01*
G01X598954Y660193D02*
X598843Y660197D01*
G01X598954Y653894D02*
X598843Y653898D01*
G01X598954Y663343D02*
X598843Y663346D01*
G01X600394Y672953D02*
X597047D01*
G01X599902Y670984D02*
X598996D01*
G01X599941Y670945D02*
X598957D01*
G01X599900Y670787D02*
X594016D01*
G01Y670748D02*
X599940D01*
G01X599939Y669646D02*
X594016D01*
G01X599900Y669606D02*
X594016D01*
G01X598957Y669449D02*
X599941D01*
G01X598996Y669409D02*
X599902D01*
G01Y667835D02*
X598996D01*
G01X599941Y667795D02*
X598957D01*
G01X599900Y667638D02*
X594016D01*
G01Y667598D02*
X599940D01*
G01X599939Y666496D02*
X594016D01*
G01X599900Y666457D02*
X594016D01*
G01X598957Y666299D02*
X599941D01*
G01X598996Y666260D02*
X599902D01*
G01Y664685D02*
X598996D01*
G01X599941Y664646D02*
X598957D01*
G01X599900Y664488D02*
X594016D01*
G01Y664449D02*
X599940D01*
G01X599939Y663346D02*
X594016D01*
G01X599900Y663307D02*
X594016D01*
G01X598957Y663150D02*
X599941D01*
G01X598996Y663110D02*
X599902D01*
G01Y661535D02*
X598996D01*
G01X599941Y661496D02*
X598957D01*
G01X599900Y661339D02*
X594016D01*
G01Y661299D02*
X599940D01*
G01X599939Y660197D02*
X594016D01*
G01X599900Y660157D02*
X594016D01*
G01X598957Y660000D02*
X599941D01*
G01X598996Y659961D02*
X599902D01*
G01Y658386D02*
X598996D01*
G01X599941Y658346D02*
X598957D01*
G01X599900Y658189D02*
X594016D01*
G01Y658150D02*
X599940D01*
G01X599939Y657047D02*
X594016D01*
G01X599900Y657008D02*
X594016D01*
G01X598957Y656850D02*
X599941D01*
G01X598996Y656811D02*
X599902D01*
G01Y655236D02*
X598996D01*
G01X599941Y655197D02*
X598957D01*
G01X599900Y655039D02*
X594016D01*
G01Y655000D02*
X599940D01*
G01X599939Y653898D02*
X594016D01*
G01X599900Y653858D02*
X594016D01*
G01X598957Y653701D02*
X599941D01*
G01X598996Y653661D02*
X599902D01*
G01Y652087D02*
X598996D01*
G01X599941Y652047D02*
X598957D01*
G01X599900Y651890D02*
X594016D01*
G01Y651850D02*
X599940D01*
G01X599939Y650748D02*
X594016D01*
G01X599900Y650709D02*
X594016D01*
G01X598957Y650551D02*
X599941D01*
G01X598996Y650512D02*
X599902D01*
G01X600394Y648543D02*
X597047D01*
G01X599900Y666457D02*
X599904Y666446D01*
G01X599941Y651853D02*
Y651864D01*
G01Y655002D02*
Y655013D01*
G01Y658152D02*
Y658163D01*
G01Y661302D02*
Y661313D01*
G01Y664451D02*
Y664462D01*
G01Y667601D02*
Y667612D01*
G01Y670750D02*
Y670761D01*
G01X600394Y751988D02*
Y672953D01*
G01X599941Y669449D02*
Y670945D01*
G01Y666299D02*
Y667795D01*
G01Y663150D02*
Y664646D01*
G01Y660000D02*
Y661496D01*
G01Y656850D02*
Y658346D01*
G01Y653701D02*
Y655197D01*
G01Y650551D02*
Y652047D01*
G01X599902Y650698D02*
Y650551D01*
G01Y652048D02*
Y651901D01*
G01Y656997D02*
Y656850D01*
G01Y653847D02*
Y653700D01*
G01Y655197D02*
Y655051D01*
G01Y660146D02*
Y660000D01*
G01Y661496D02*
Y661350D01*
G01Y658347D02*
Y658200D01*
G01Y666446D02*
Y666299D01*
G01Y663296D02*
Y663149D01*
G01Y664646D02*
Y664500D01*
G01Y669595D02*
Y669448D01*
G01Y670945D02*
Y670799D01*
G01Y667796D02*
Y667649D01*
G01X598996Y669448D02*
Y669595D01*
G01Y670799D02*
Y670946D01*
G01Y667649D02*
Y667796D01*
G01Y666298D02*
Y666446D01*
G01Y663149D02*
Y663296D01*
G01Y664500D02*
Y664646D01*
G01Y659999D02*
Y660146D01*
G01Y661350D02*
Y661497D01*
G01Y658200D02*
Y658347D01*
G01Y656850D02*
Y656997D01*
G01Y653700D02*
Y653847D01*
G01Y655051D02*
Y655198D01*
G01Y650550D02*
Y650698D01*
G01Y651901D02*
Y652048D01*
G01X598957Y652047D02*
Y650551D01*
G01Y655197D02*
Y653701D01*
G01Y661496D02*
Y660000D01*
G01Y658346D02*
Y656850D01*
G01Y664646D02*
Y663150D01*
G01Y670945D02*
Y669449D01*
G01Y667795D02*
Y666299D01*
G01X597776Y651890D02*
Y650709D01*
G01Y658189D02*
Y657008D01*
G01Y655039D02*
Y653858D01*
G01Y661339D02*
Y660157D01*
G01Y667638D02*
Y666457D01*
G01Y664488D02*
Y663307D01*
G01Y670787D02*
Y669606D01*
G01X597441Y672953D02*
Y648543D01*
G01X597047D02*
Y672953D01*
G01X594016Y669606D02*
Y670787D01*
G01Y666457D02*
Y667638D01*
G01Y663307D02*
Y664488D01*
G01Y660157D02*
Y661339D01*
G01Y657008D02*
Y658189D01*
G01Y653858D02*
Y655039D01*
G01Y650709D02*
Y651890D01*
G01X599941Y669632D02*
Y669643D01*
G01Y666483D02*
Y666494D01*
G01Y663333D02*
Y663344D01*
G01Y660183D02*
Y660194D01*
G01Y657034D02*
Y657045D01*
G01Y653884D02*
Y653895D01*
G01Y650735D02*
Y650746D01*
G01X604528Y770020D02*
G03X603937Y769429I0J-591D01*
G01X599016Y770807D02*
G03X597047Y768839I0J-1969D01*
G01X605315Y760335D02*
G03X604134Y759154I0J-1181D01*
G01X616732Y770807D02*
X599016D01*
G01X611811Y764902D02*
X603937D01*
G01Y763327D02*
X611811D01*
G01X618701Y760374D02*
X597047D01*
G01X600394Y751988D02*
X614764D01*
G01X600394Y750610D02*
X604134D01*
G01X600394Y749744D02*
X615354D01*
G01X602165Y748248D02*
X610039D01*
G01X603346Y747067D02*
X608858D01*
G01X606693Y755650D02*
X604383Y759879D01*
G01X602165Y748248D02*
X603346Y747067D01*
G01X597047Y753091D02*
X600394Y749744D01*
G01X604134Y750610D02*
Y759154D01*
G01X603937Y763327D02*
Y769429D01*
G01X597047Y768839D02*
Y753091D01*
G01X567913Y827559D02*
G03X569094I591J0D01*
G01Y821260D02*
G03X567913I-590J0D01*
G01X565945D02*
G03X564764I-590J0D01*
G01Y827559D02*
G03X565945I590J0D01*
G01X567913D02*
G03X569094I591J0D01*
G01Y821260D02*
G03X567913I-590J0D01*
G01X565945D02*
G03X564764I-590J0D01*
G01Y827559D02*
G03X565945I590J0D01*
G01X567913D02*
X565945D01*
G01X564764D02*
X563976D01*
G01X567913D02*
X565945D01*
G01X564764D02*
X563976D01*
G01X569882D02*
X569094D01*
G01X569882D02*
X569094D01*
G01X569882Y826575D02*
X563976D01*
G01Y826378D02*
X569882D01*
G01X563976Y822441D02*
X569882D01*
G01Y822244D02*
X563976D01*
G01X569094Y821260D02*
X569882D01*
G01X569094D02*
X569882D01*
G01X565945D02*
X567913D01*
G01X563976D02*
X564764D01*
G01X565945D02*
X567913D01*
G01X563976D02*
X564764D01*
G01X569882D02*
Y827559D01*
G01Y821260D02*
Y827559D01*
G01X563976Y821260D02*
Y827559D01*
G01D02*
Y821260D01*
G01X603937Y1044823D02*
G03X604528Y1044232I591J0D01*
G01X604134Y1055098D02*
G03X605315Y1053917I1181J0D01*
G01X597047Y1045413D02*
G03X599016Y1043445I1969J1D01*
G01X608858Y1067185D02*
X603346D01*
G01X610039Y1066004D02*
X602165D01*
G01X615354Y1064508D02*
X600394D01*
G01X604134Y1063642D02*
X600394D01*
G01Y1062264D02*
X614764D01*
G01X618701Y1053878D02*
X597047D01*
G01X611811Y1050925D02*
X603937D01*
G01Y1049350D02*
X611811D01*
G01X616732Y1043445D02*
X599016D01*
G01X604134Y1055098D02*
Y1063642D01*
G01X603937Y1050925D02*
Y1044823D01*
G01X603346Y1067185D02*
Y1199823D01*
G01X602165Y1066004D02*
Y1201004D01*
G01X600394Y1101299D02*
Y1062264D01*
G01X597047Y1061161D02*
Y1045413D01*
G01X603346Y1067185D02*
X602165Y1066004D01*
G01X600394Y1064508D02*
X597047Y1061161D01*
G01X604383Y1054373D02*
X606693Y1058602D01*
G01X598970Y1123535D02*
X598994Y1123543D01*
G01X598958Y1123520D02*
X598970Y1123535D01*
G01X598957Y1123514D02*
X598958Y1123520D01*
G01X598970Y1120385D02*
X598994Y1120394D01*
G01X598958Y1120371D02*
X598970Y1120385D01*
G01X598957Y1120364D02*
X598958Y1120371D01*
G01X598970Y1117236D02*
X598994Y1117244D01*
G01X598958Y1117221D02*
X598970Y1117236D01*
G01X598957Y1117215D02*
X598958Y1117221D01*
G01X598970Y1114086D02*
X598994Y1114094D01*
G01X598958Y1114072D02*
X598970Y1114086D01*
G01X598957Y1114065D02*
X598958Y1114072D01*
G01X598970Y1110937D02*
X598994Y1110945D01*
G01X598958Y1110922D02*
X598970Y1110937D01*
G01X598957Y1110915D02*
X598958Y1110922D01*
G01X598970Y1107787D02*
X598994Y1107795D01*
G01X598958Y1107772D02*
X598970Y1107787D01*
G01X598957Y1107766D02*
X598958Y1107772D01*
G01X598970Y1104637D02*
X598994Y1104646D01*
G01X598958Y1104623D02*
X598970Y1104637D01*
G01X598957Y1104616D02*
X598958Y1104623D01*
G01X599941Y1123510D02*
Y1123517D01*
G01Y1123506D02*
Y1123510D01*
G01X599940Y1123504D02*
X599941Y1123506D01*
G01Y1120361D02*
Y1120368D01*
G01Y1120356D02*
Y1120361D01*
G01X599940Y1120354D02*
X599941Y1120356D01*
G01Y1117211D02*
Y1117218D01*
G01Y1117207D02*
Y1117211D01*
G01X599940Y1117205D02*
X599941Y1117207D01*
G01Y1114061D02*
Y1114069D01*
G01Y1114057D02*
Y1114061D01*
G01X599940Y1114055D02*
X599941Y1114057D01*
G01Y1110912D02*
Y1110919D01*
G01Y1110907D02*
Y1110912D01*
G01X599940Y1110906D02*
X599941Y1110907D01*
G01Y1107762D02*
Y1107769D01*
G01Y1107758D02*
Y1107762D01*
G01X599940Y1107756D02*
X599941Y1107758D01*
G01Y1104613D02*
Y1104620D01*
G01Y1104608D02*
Y1104613D01*
G01X599940Y1104606D02*
X599941Y1104608D01*
G01X598956Y1112947D02*
X598957Y1112939D01*
G01X598956Y1112952D02*
Y1112947D01*
G01X598954Y1112949D02*
X598956Y1112952D01*
G01Y1106648D02*
X598957Y1106640D01*
G01X598956Y1106652D02*
Y1106648D01*
G01X598954Y1106650D02*
X598956Y1106652D01*
G01X599902Y1123548D02*
Y1123555D01*
G01X599901Y1123545D02*
X599902Y1123548D01*
G01X599900Y1123543D02*
X599901Y1123545D01*
G01X599902Y1120399D02*
Y1120405D01*
G01X599901Y1120395D02*
X599902Y1120399D01*
G01X599900Y1120394D02*
X599901Y1120395D01*
G01X599902Y1117249D02*
Y1117256D01*
G01X599901Y1117246D02*
X599902Y1117249D01*
G01X599900Y1117244D02*
X599901Y1117246D01*
G01X599902Y1114100D02*
Y1114106D01*
G01X599901Y1114096D02*
X599902Y1114100D01*
G01X599900Y1114094D02*
X599901Y1114096D01*
G01X599902Y1110950D02*
Y1110956D01*
G01X599901Y1110946D02*
X599902Y1110950D01*
G01X599900Y1110945D02*
X599901Y1110946D01*
G01X599902Y1107800D02*
Y1107807D01*
G01X599901Y1107797D02*
X599902Y1107800D01*
G01X599900Y1107795D02*
X599901Y1107797D01*
G01X599902Y1104651D02*
Y1104657D01*
G01X599901Y1104647D02*
X599902Y1104651D01*
G01X599900Y1104646D02*
X599901Y1104647D01*
G01X598956Y1123510D02*
X598957Y1123518D01*
G01X598956Y1123506D02*
Y1123510D01*
G01X598954Y1123504D02*
X598956Y1123506D01*
G01Y1120361D02*
X598957Y1120368D01*
G01X598956Y1120356D02*
Y1120361D01*
G01X598954Y1120354D02*
X598956Y1120356D01*
G01Y1117211D02*
X598957Y1117219D01*
G01X598956Y1117206D02*
Y1117211D01*
G01X598954Y1117205D02*
X598956Y1117206D01*
G01Y1114061D02*
X598957Y1114069D01*
G01X598956Y1114057D02*
Y1114061D01*
G01X598954Y1114055D02*
X598956Y1114057D01*
G01Y1110912D02*
X598957Y1110919D01*
G01X598956Y1110907D02*
Y1110912D01*
G01X598954Y1110906D02*
X598956Y1110907D01*
G01Y1107762D02*
X598957Y1107770D01*
G01X598956Y1107757D02*
Y1107762D01*
G01X598954Y1107756D02*
X598956Y1107757D01*
G01Y1104613D02*
X598957Y1104620D01*
G01X598956Y1104608D02*
Y1104613D01*
G01X598954Y1104606D02*
X598956Y1104608D01*
G01X599939Y1122376D02*
X599941Y1122388D01*
G01X599932Y1122365D02*
X599939Y1122376D01*
G01X599922Y1122356D02*
X599932Y1122365D01*
G01X599939Y1116076D02*
X599941Y1116089D01*
G01X599932Y1116065D02*
X599939Y1116076D01*
G01X599922Y1116057D02*
X599932Y1116065D01*
G01X599939Y1112927D02*
X599941Y1112939D01*
G01X599932Y1112916D02*
X599939Y1112927D01*
G01X599922Y1112907D02*
X599932Y1112916D01*
G01X599939Y1109777D02*
X599941Y1109790D01*
G01X599932Y1109766D02*
X599939Y1109777D01*
G01X599922Y1109758D02*
X599932Y1109766D01*
G01X599939Y1106628D02*
X599941Y1106640D01*
G01X599932Y1106617D02*
X599939Y1106628D01*
G01X599922Y1106608D02*
X599932Y1106617D01*
G01X599939Y1103478D02*
X599941Y1103491D01*
G01X599932Y1103467D02*
X599939Y1103478D01*
G01X599922Y1103459D02*
X599932Y1103467D01*
G01X598995Y1123548D02*
Y1123555D01*
G01Y1123544D02*
Y1123548D01*
G01X598993Y1123543D02*
X598995Y1123544D01*
G01Y1120399D02*
Y1120405D01*
G01Y1120395D02*
Y1120399D01*
G01X598993Y1120394D02*
X598995Y1120395D01*
G01Y1117249D02*
Y1117256D01*
G01Y1117245D02*
Y1117249D01*
G01X598993Y1117244D02*
X598995Y1117245D01*
G01Y1114100D02*
Y1114106D01*
G01Y1114096D02*
Y1114100D01*
G01X598993Y1114094D02*
X598995Y1114096D01*
G01Y1110950D02*
Y1110956D01*
G01Y1110946D02*
Y1110950D01*
G01X598993Y1110945D02*
X598995Y1110946D01*
G01Y1107800D02*
Y1107807D01*
G01Y1107796D02*
Y1107800D01*
G01X598993Y1107795D02*
X598995Y1107796D01*
G01Y1104651D02*
Y1104657D01*
G01Y1104647D02*
Y1104651D01*
G01X598993Y1104646D02*
X598995Y1104647D01*
G01X598957Y1123524D02*
Y1123518D01*
G01X598959Y1123530D02*
X598957Y1123524D01*
G01X598962Y1123536D02*
X598959Y1123530D01*
G01X598966Y1123541D02*
X598962Y1123536D01*
G01X598970Y1123546D02*
X598966Y1123541D01*
G01X598976Y1123550D02*
X598970Y1123546D01*
G01X598957Y1120374D02*
Y1120368D01*
G01X598959Y1120381D02*
X598957Y1120374D01*
G01X598962Y1120386D02*
X598959Y1120381D01*
G01X598966Y1120392D02*
X598962Y1120386D01*
G01X598970Y1120396D02*
X598966Y1120392D01*
G01X598976Y1120400D02*
X598970Y1120396D01*
G01X598957Y1117225D02*
Y1117219D01*
G01X598959Y1117231D02*
X598957Y1117225D01*
G01X598962Y1117237D02*
X598959Y1117231D01*
G01X598966Y1117242D02*
X598962Y1117237D01*
G01X598970Y1117246D02*
X598966Y1117242D01*
G01X598976Y1117250D02*
X598970Y1117246D01*
G01X598957Y1114075D02*
Y1114069D01*
G01X598959Y1114081D02*
X598957Y1114075D01*
G01X598962Y1114087D02*
X598959Y1114081D01*
G01X598966Y1114093D02*
X598962Y1114087D01*
G01X598970Y1114097D02*
X598966Y1114093D01*
G01X598976Y1114101D02*
X598970Y1114097D01*
G01X598957Y1110926D02*
Y1110919D01*
G01X598959Y1110932D02*
X598957Y1110926D01*
G01X598962Y1110937D02*
X598959Y1110932D01*
G01X598966Y1110943D02*
X598962Y1110937D01*
G01X598970Y1110947D02*
X598966Y1110943D01*
G01X598976Y1110951D02*
X598970Y1110947D01*
G01X598957Y1107776D02*
Y1107770D01*
G01X598959Y1107782D02*
X598957Y1107776D01*
G01X598962Y1107788D02*
X598959Y1107782D01*
G01X598966Y1107793D02*
X598962Y1107788D01*
G01X598970Y1107798D02*
X598966Y1107793D01*
G01X598976Y1107802D02*
X598970Y1107798D01*
G01X598957Y1104626D02*
Y1104620D01*
G01X598959Y1104633D02*
X598957Y1104626D01*
G01X598962Y1104638D02*
X598959Y1104633D01*
G01X598966Y1104644D02*
X598962Y1104638D01*
G01X598970Y1104648D02*
X598966Y1104644D01*
G01X598976Y1104652D02*
X598970Y1104648D01*
G01X599912Y1122364D02*
X599900Y1122362D01*
G01X599922Y1122369D02*
X599912Y1122364D01*
G01Y1119215D02*
X599900Y1119213D01*
G01X599922Y1119220D02*
X599912Y1119215D01*
G01Y1116065D02*
X599900Y1116063D01*
G01X599922Y1116070D02*
X599912Y1116065D01*
G01Y1112915D02*
X599900Y1112913D01*
G01X599922Y1112920D02*
X599912Y1112915D01*
G01Y1109766D02*
X599900Y1109764D01*
G01X599922Y1109771D02*
X599912Y1109766D01*
G01Y1106616D02*
X599900Y1106614D01*
G01X599922Y1106621D02*
X599912Y1106616D01*
G01Y1103467D02*
X599900Y1103465D01*
G01X599922Y1103472D02*
X599912Y1103467D01*
G01X598956Y1116096D02*
X598957Y1116089D01*
G01X598956Y1116101D02*
Y1116096D01*
G01Y1116092D02*
Y1116101D01*
G01X598997Y1123728D02*
X598996Y1123740D01*
G01X598994Y1123715D02*
X598997Y1123728D01*
G01X598994Y1123701D02*
Y1123715D01*
G01X598997Y1120578D02*
X598996Y1120591D01*
G01X598994Y1120565D02*
X598997Y1120578D01*
G01X598994Y1120552D02*
Y1120565D01*
G01X598997Y1117429D02*
X598996Y1117441D01*
G01X598994Y1117416D02*
X598997Y1117429D01*
G01X598994Y1117402D02*
Y1117416D01*
G01X598997Y1114279D02*
X598996Y1114291D01*
G01X598994Y1114266D02*
X598997Y1114279D01*
G01X598994Y1114252D02*
Y1114266D01*
G01X598997Y1111130D02*
X598996Y1111142D01*
G01X598994Y1111117D02*
X598997Y1111130D01*
G01X598994Y1111103D02*
Y1111117D01*
G01X598997Y1107980D02*
X598996Y1107992D01*
G01X598994Y1107967D02*
X598997Y1107980D01*
G01X598994Y1107953D02*
Y1107967D01*
G01X598997Y1104830D02*
X598996Y1104843D01*
G01X598994Y1104817D02*
X598997Y1104830D01*
G01X598994Y1104804D02*
Y1104817D01*
G01X598956Y1122396D02*
X598957Y1122388D01*
G01X598956Y1122400D02*
Y1122396D01*
G01Y1122393D02*
Y1122400D01*
G01X598994Y1122191D02*
X598993Y1122204D01*
G01X598997Y1122178D02*
X598994Y1122191D01*
G01X598996Y1122165D02*
X598997Y1122178D01*
G01X598994Y1119041D02*
X598993Y1119055D01*
G01X598997Y1119028D02*
X598994Y1119041D01*
G01X598996Y1119016D02*
X598997Y1119028D01*
G01X598994Y1115892D02*
X598993Y1115905D01*
G01X598997Y1115879D02*
X598994Y1115892D01*
G01X598996Y1115866D02*
X598997Y1115879D01*
G01X598994Y1112742D02*
X598993Y1112756D01*
G01X598997Y1112729D02*
X598994Y1112742D01*
G01X598996Y1112717D02*
X598997Y1112729D01*
G01X598994Y1109593D02*
X598993Y1109606D01*
G01X598997Y1109580D02*
X598994Y1109593D01*
G01X598996Y1109567D02*
X598997Y1109580D01*
G01X598994Y1106443D02*
X598993Y1106456D01*
G01X598997Y1106430D02*
X598994Y1106443D01*
G01X598996Y1106417D02*
X598997Y1106430D01*
G01X598994Y1103293D02*
X598993Y1103307D01*
G01X598997Y1103280D02*
X598994Y1103293D01*
G01X598996Y1103268D02*
X598997Y1103280D01*
G01X599904Y1123715D02*
X599905Y1123701D01*
G01X599901Y1123728D02*
X599904Y1123715D01*
G01X599902Y1123740D02*
X599901Y1123728D01*
G01X599904Y1120565D02*
X599905Y1120552D01*
G01X599901Y1120578D02*
X599904Y1120565D01*
G01X599902Y1120591D02*
X599901Y1120578D01*
G01X599904Y1117415D02*
X599905Y1117402D01*
G01X599901Y1117428D02*
X599904Y1117415D01*
G01X599902Y1117441D02*
X599901Y1117428D01*
G01X599904Y1114266D02*
X599905Y1114252D01*
G01X599901Y1114279D02*
X599904Y1114266D01*
G01X599902Y1114291D02*
X599901Y1114279D01*
G01X599904Y1111116D02*
X599905Y1111103D01*
G01X599901Y1111129D02*
X599904Y1111116D01*
G01X599902Y1111142D02*
X599901Y1111129D01*
G01X599904Y1107967D02*
X599905Y1107953D01*
G01X599901Y1107980D02*
X599904Y1107967D01*
G01X599902Y1107992D02*
X599901Y1107980D01*
G01X599904Y1104817D02*
X599905Y1104804D01*
G01X599901Y1104830D02*
X599904Y1104817D01*
G01X599902Y1104843D02*
X599901Y1104830D01*
G01X598956Y1109797D02*
X598957Y1109790D01*
G01X598956Y1109802D02*
Y1109797D01*
G01X598955Y1109795D02*
X598956Y1109802D01*
G01Y1119246D02*
X598957Y1119239D01*
G01X598956Y1119251D02*
Y1119246D01*
G01X598955Y1119244D02*
X598956Y1119251D01*
G01X599901Y1122178D02*
X599902Y1122165D01*
G01X599904Y1122191D02*
X599901Y1122178D01*
G01X599905Y1122204D02*
X599904Y1122191D01*
G01X599901Y1119028D02*
X599902Y1119016D01*
G01X599904Y1119041D02*
X599901Y1119028D01*
G01X599905Y1119055D02*
X599904Y1119041D01*
G01X599901Y1115879D02*
X599902Y1115866D01*
G01X599904Y1115892D02*
X599901Y1115879D01*
G01X599905Y1115905D02*
X599904Y1115892D01*
G01X599901Y1112729D02*
X599902Y1112717D01*
G01X599904Y1112742D02*
X599901Y1112729D01*
G01X599905Y1112756D02*
X599904Y1112742D01*
G01X599901Y1109580D02*
X599902Y1109567D01*
G01X599904Y1109593D02*
X599901Y1109580D01*
G01X599905Y1109606D02*
X599904Y1109593D01*
G01X599901Y1106430D02*
X599902Y1106417D01*
G01X599904Y1106443D02*
X599901Y1106430D01*
G01X599905Y1106456D02*
X599904Y1106443D01*
G01X599901Y1103280D02*
X599902Y1103268D01*
G01X599904Y1103293D02*
X599901Y1103280D01*
G01X599905Y1103307D02*
X599904Y1103293D01*
G01X598956Y1103498D02*
X598957Y1103491D01*
G01X598956Y1103503D02*
Y1103498D01*
G01X598955Y1103496D02*
X598956Y1103503D01*
G01X599933Y1110927D02*
X599926Y1110935D01*
G01X599938Y1110917D02*
X599933Y1110927D01*
G01X599940Y1110906D02*
X599938Y1110917D01*
G01X599933Y1104628D02*
X599926Y1104636D01*
G01X599938Y1104617D02*
X599933Y1104628D01*
G01X599940Y1104606D02*
X599938Y1104617D01*
G01X599933Y1107777D02*
X599926Y1107786D01*
G01X599938Y1107767D02*
X599933Y1107777D01*
G01X599940Y1107756D02*
X599938Y1107767D01*
G01X599933Y1114076D02*
X599926Y1114085D01*
G01X599938Y1114066D02*
X599933Y1114076D01*
G01X599940Y1114055D02*
X599938Y1114066D01*
G01X599933Y1117226D02*
X599926Y1117235D01*
G01X599938Y1117216D02*
X599933Y1117226D01*
G01X599940Y1117205D02*
X599938Y1117216D01*
G01X599933Y1120376D02*
X599926Y1120384D01*
G01X599938Y1120365D02*
X599933Y1120376D01*
G01X599940Y1120354D02*
X599938Y1120365D01*
G01X599933Y1123525D02*
X599926Y1123534D01*
G01X599938Y1123515D02*
X599933Y1123525D01*
G01X599940Y1123504D02*
X599938Y1123515D01*
G01X598979Y1103468D02*
X598994Y1103465D01*
G01X598966Y1103476D02*
X598979Y1103468D01*
G01X598955Y1103496D02*
X598966Y1103476D01*
G01X599940Y1104627D02*
X599941Y1104620D01*
G01X599939Y1104633D02*
X599940Y1104627D01*
G01X599935Y1104639D02*
X599939Y1104633D01*
G01X599940Y1107776D02*
X599941Y1107770D01*
G01X599939Y1107783D02*
X599940Y1107776D01*
G01X599935Y1107789D02*
X599939Y1107783D01*
G01X599940Y1110926D02*
X599941Y1110919D01*
G01X599939Y1110932D02*
X599940Y1110926D01*
G01X599935Y1110938D02*
X599939Y1110932D01*
G01X599940Y1114076D02*
X599941Y1114069D01*
G01X599939Y1114082D02*
X599940Y1114076D01*
G01X599935Y1114088D02*
X599939Y1114082D01*
G01X599940Y1117225D02*
X599941Y1117219D01*
G01X599939Y1117231D02*
X599940Y1117225D01*
G01X599935Y1117237D02*
X599939Y1117231D01*
G01X599940Y1120375D02*
X599941Y1120368D01*
G01X599939Y1120381D02*
X599940Y1120375D01*
G01X599935Y1120387D02*
X599939Y1120381D01*
G01X599940Y1123524D02*
X599941Y1123518D01*
G01X599939Y1123531D02*
X599940Y1123524D01*
G01X599935Y1123537D02*
X599939Y1123531D01*
G01X599902Y1103459D02*
Y1103454D01*
G01X599901Y1103463D02*
X599902Y1103459D01*
G01X599900Y1103465D02*
X599901Y1103463D01*
G01X599902Y1106609D02*
Y1106603D01*
G01X599901Y1106613D02*
X599902Y1106609D01*
G01X599900Y1106614D02*
X599901Y1106613D01*
G01X599902Y1109759D02*
Y1109753D01*
G01X599901Y1109763D02*
X599902Y1109759D01*
G01X599900Y1109764D02*
X599901Y1109763D01*
G01X599902Y1112908D02*
Y1112902D01*
G01X599901Y1112912D02*
X599902Y1112908D01*
G01X599900Y1112913D02*
X599901Y1112912D01*
G01X599902Y1116058D02*
Y1116052D01*
G01X599901Y1116062D02*
X599902Y1116058D01*
G01X599900Y1116063D02*
X599901Y1116062D01*
G01X599902Y1122357D02*
Y1122351D01*
G01X599901Y1122361D02*
X599902Y1122357D01*
G01X599900Y1122362D02*
X599901Y1122361D01*
G01X598974Y1112919D02*
X598994Y1112913D01*
G01X598961Y1112931D02*
X598974Y1112919D01*
G01X598954Y1112949D02*
X598961Y1112931D01*
G01X598980Y1106617D02*
X598994Y1106614D01*
G01X598968Y1106624D02*
X598980Y1106617D01*
G01X598956Y1106643D02*
X598968Y1106624D01*
G01X598980Y1116066D02*
X598994Y1116063D01*
G01X598968Y1116073D02*
X598980Y1116066D01*
G01X598956Y1116091D02*
X598968Y1116073D01*
G01X598979Y1109767D02*
X598994Y1109764D01*
G01X598967Y1109774D02*
X598979Y1109767D01*
G01X598955Y1109794D02*
X598967Y1109774D01*
G01X598979Y1119215D02*
X598994Y1119213D01*
G01X598967Y1119223D02*
X598979Y1119215D01*
G01X598955Y1119243D02*
X598967Y1119223D01*
G01X599941Y1103498D02*
Y1103491D01*
G01X599940Y1103503D02*
X599941Y1103498D01*
G01X599939Y1103504D02*
X599940Y1103503D01*
G01X599941Y1106648D02*
Y1106640D01*
G01X599940Y1106652D02*
X599941Y1106648D01*
G01X599939Y1106654D02*
X599940Y1106652D01*
G01X599941Y1109797D02*
Y1109790D01*
G01X599940Y1109802D02*
X599941Y1109797D01*
G01X599939Y1109803D02*
X599940Y1109802D01*
G01X599941Y1112947D02*
Y1112939D01*
G01X599940Y1112952D02*
X599941Y1112947D01*
G01X599939Y1112953D02*
X599940Y1112952D01*
G01X599941Y1116096D02*
Y1116089D01*
G01X599940Y1116101D02*
X599941Y1116096D01*
G01X599939Y1116102D02*
X599940Y1116101D01*
G01X599941Y1119246D02*
Y1119239D01*
G01X599940Y1119251D02*
X599941Y1119246D01*
G01X599939Y1119252D02*
X599940Y1119251D01*
G01X599941Y1122396D02*
Y1122388D01*
G01X599940Y1122400D02*
X599941Y1122396D01*
G01X599939Y1122402D02*
X599940Y1122400D01*
G01X598979Y1122365D02*
X598994Y1122362D01*
G01X598967Y1122373D02*
X598979Y1122365D01*
G01X598955Y1122393D02*
X598967Y1122373D01*
G01X598996Y1103460D02*
Y1103454D01*
G01X598995Y1103463D02*
X598996Y1103460D01*
G01X598994Y1103465D02*
X598995Y1103463D01*
G01X598996Y1106609D02*
Y1106603D01*
G01X598995Y1106613D02*
X598996Y1106609D01*
G01X598994Y1106614D02*
X598995Y1106613D01*
G01X598996Y1109759D02*
Y1109753D01*
G01X598995Y1109763D02*
X598996Y1109759D01*
G01X598994Y1109764D02*
X598995Y1109763D01*
G01X598996Y1112909D02*
Y1112902D01*
G01X598995Y1112912D02*
X598996Y1112909D01*
G01X598994Y1112913D02*
X598995Y1112912D01*
G01X598996Y1116058D02*
Y1116052D01*
G01X598995Y1116062D02*
X598996Y1116058D01*
G01X598994Y1116063D02*
X598995Y1116062D01*
G01X598996Y1119208D02*
Y1119202D01*
G01X598995Y1119211D02*
X598996Y1119208D01*
G01X598994Y1119213D02*
X598995Y1119211D01*
G01X599909Y1110944D02*
X599900Y1110945D01*
G01X599918Y1110941D02*
X599909Y1110944D01*
G01X599926Y1110935D02*
X599918Y1110941D01*
G01X599909Y1104644D02*
X599900Y1104646D01*
G01X599919Y1104641D02*
X599909Y1104644D01*
G01X599926Y1104636D02*
X599919Y1104641D01*
G01X599909Y1107794D02*
X599900Y1107795D01*
G01X599919Y1107791D02*
X599909Y1107794D01*
G01X599926Y1107786D02*
X599919Y1107791D01*
G01X599909Y1114093D02*
X599900Y1114094D01*
G01X599919Y1114090D02*
X599909Y1114093D01*
G01X599926Y1114085D02*
X599919Y1114090D01*
G01X599909Y1117243D02*
X599900Y1117244D01*
G01X599919Y1117240D02*
X599909Y1117243D01*
G01X599926Y1117235D02*
X599919Y1117240D01*
G01X599909Y1120393D02*
X599900Y1120394D01*
G01X599919Y1120389D02*
X599909Y1120393D01*
G01X599926Y1120384D02*
X599919Y1120389D01*
G01X599909Y1123542D02*
X599900Y1123543D01*
G01X599919Y1123539D02*
X599909Y1123542D01*
G01X599926Y1123534D02*
X599919Y1123539D01*
G01X598996Y1122357D02*
Y1122351D01*
G01X598995Y1122361D02*
X598996Y1122357D01*
G01X598994Y1122362D02*
X598995Y1122361D01*
G01X598957Y1103494D02*
Y1103491D01*
G01X598958Y1103488D02*
X598957Y1103494D01*
G01X598970Y1103473D02*
X598958Y1103488D01*
G01X598994Y1103465D02*
X598970Y1103473D01*
G01X598957Y1112943D02*
Y1112939D01*
G01X598958Y1112938D02*
X598957Y1112943D01*
G01X598968Y1112923D02*
X598958Y1112938D01*
G01X598991Y1112914D02*
X598968Y1112923D01*
G01X599911Y1104644D02*
X599920Y1104640D01*
G01X599900Y1104646D02*
X599911Y1104644D01*
G01Y1107794D02*
X599920Y1107790D01*
G01X599900Y1107795D02*
X599911Y1107794D01*
G01Y1110944D02*
X599920Y1110939D01*
G01X599900Y1110945D02*
X599911Y1110944D01*
G01Y1114093D02*
X599920Y1114089D01*
G01X599900Y1114094D02*
X599911Y1114093D01*
G01Y1117243D02*
X599920Y1117239D01*
G01X599900Y1117244D02*
X599911Y1117243D01*
G01X598957Y1106644D02*
Y1106640D01*
G01X598958Y1106638D02*
X598957Y1106644D01*
G01X598970Y1106622D02*
X598958Y1106638D01*
G01X598995Y1106614D02*
X598970Y1106622D01*
G01X598957Y1109794D02*
Y1109790D01*
G01X598958Y1109787D02*
X598957Y1109794D01*
G01X598970Y1109772D02*
X598958Y1109787D01*
G01X598994Y1109764D02*
X598970Y1109772D01*
G01X598957Y1116093D02*
Y1116089D01*
G01X598958Y1116087D02*
X598957Y1116093D01*
G01X598970Y1116071D02*
X598958Y1116087D01*
G01X598994Y1116063D02*
X598970Y1116071D01*
G01X598957Y1119243D02*
Y1119239D01*
G01X598958Y1119236D02*
X598957Y1119243D01*
G01X598970Y1119221D02*
X598958Y1119236D01*
G01X598994Y1119213D02*
X598970Y1119221D01*
G01X598957Y1122392D02*
Y1122388D01*
G01X598958Y1122386D02*
X598957Y1122392D01*
G01X598970Y1122370D02*
X598958Y1122386D01*
G01X598994Y1122362D02*
X598970Y1122370D01*
G01X599940Y1119231D02*
X599941Y1119239D01*
G01X599938Y1119224D02*
X599940Y1119231D01*
G01X599934Y1119218D02*
X599938Y1119224D01*
G01X599930Y1119212D02*
X599934Y1119218D01*
G01X599923Y1119207D02*
X599930Y1119212D01*
G01X599917Y1119204D02*
X599923Y1119207D01*
G01X599909Y1119202D02*
X599917Y1119204D01*
G01X599902Y1119202D02*
X599909D01*
G01X599919Y1103457D02*
X599922Y1103459D01*
G01X599915Y1103456D02*
X599919Y1103457D01*
G01X599912Y1103455D02*
X599915Y1103456D01*
G01X599909Y1103454D02*
X599912Y1103455D01*
G01X599905Y1103454D02*
X599909D01*
G01X599902D02*
X599905D01*
G01X598979Y1104654D02*
X598976Y1104652D01*
G01X598982Y1104655D02*
X598979Y1104654D01*
G01X598985Y1104656D02*
X598982Y1104655D01*
G01X598989Y1104656D02*
X598985D01*
G01X598993Y1104657D02*
X598989Y1104656D01*
G01X598996Y1104657D02*
X598993D01*
G01X599919Y1106607D02*
X599922Y1106608D01*
G01X599915Y1106606D02*
X599919Y1106607D01*
G01X599912Y1106604D02*
X599915Y1106606D01*
G01X599909Y1106604D02*
X599912D01*
G01X599905Y1106603D02*
X599909Y1106604D01*
G01X599902Y1106603D02*
X599905D01*
G01X598979Y1107803D02*
X598976Y1107802D01*
G01X598982Y1107804D02*
X598979Y1107803D01*
G01X598985Y1107806D02*
X598982Y1107804D01*
G01X598989Y1107806D02*
X598985D01*
G01X598993Y1107807D02*
X598989Y1107806D01*
G01X598996Y1107807D02*
X598993D01*
G01X599919Y1109756D02*
X599922Y1109758D01*
G01X599915Y1109755D02*
X599919Y1109756D01*
G01X599912Y1109754D02*
X599915Y1109755D01*
G01X599909Y1109753D02*
X599912Y1109754D01*
G01X599905Y1109753D02*
X599909D01*
G01X599902D02*
X599905D01*
G01X598979Y1110953D02*
X598976Y1110951D01*
G01X598982Y1110954D02*
X598979Y1110953D01*
G01X598985Y1110955D02*
X598982Y1110954D01*
G01X598989Y1110956D02*
X598985Y1110955D01*
G01X598993Y1110956D02*
X598989D01*
G01X598996D02*
X598993D01*
G01X599919Y1112906D02*
X599922Y1112907D01*
G01X599915Y1112905D02*
X599919Y1112906D01*
G01X599912Y1112904D02*
X599915Y1112905D01*
G01X599909Y1112903D02*
X599912Y1112904D01*
G01X599905Y1112902D02*
X599909Y1112903D01*
G01X599902Y1112902D02*
X599905D01*
G01X598979Y1114102D02*
X598976Y1114101D01*
G01X598982Y1114104D02*
X598979Y1114102D01*
G01X598985Y1114105D02*
X598982Y1114104D01*
G01X598989Y1114105D02*
X598985D01*
G01X598993Y1114106D02*
X598989Y1114105D01*
G01X598996Y1114106D02*
X598993D01*
G01X599919Y1116056D02*
X599922Y1116057D01*
G01X599915Y1116054D02*
X599919Y1116056D01*
G01X599912Y1116053D02*
X599915Y1116054D01*
G01X599909Y1116052D02*
X599912Y1116053D01*
G01X599905Y1116052D02*
X599909D01*
G01X599902D02*
X599905D01*
G01X598979Y1117252D02*
X598976Y1117250D01*
G01X598982Y1117253D02*
X598979Y1117252D01*
G01X598985Y1117254D02*
X598982Y1117253D01*
G01X598989Y1117255D02*
X598985Y1117254D01*
G01X598993Y1117256D02*
X598989Y1117255D01*
G01X598996Y1117256D02*
X598993D01*
G01X598979Y1120402D02*
X598976Y1120400D01*
G01X598982Y1120403D02*
X598979Y1120402D01*
G01X598985Y1120404D02*
X598982Y1120403D01*
G01X598989Y1120404D02*
X598985D01*
G01X598993Y1120405D02*
X598989Y1120404D01*
G01X598996Y1120405D02*
X598993D01*
G01X599919Y1122355D02*
X599922Y1122356D01*
G01X599915Y1122354D02*
X599919Y1122355D01*
G01X599912Y1122352D02*
X599915Y1122354D01*
G01X599909Y1122352D02*
X599912D01*
G01X599905Y1122351D02*
X599909Y1122352D01*
G01X599902Y1122351D02*
X599905D01*
G01X598979Y1123551D02*
X598976Y1123550D01*
G01X598982Y1123552D02*
X598979Y1123551D01*
G01X598985Y1123554D02*
X598982Y1123552D01*
G01X598989Y1123554D02*
X598985D01*
G01X598993Y1123555D02*
X598989Y1123554D01*
G01X598996Y1123555D02*
X598993D01*
G01X598209Y1106654D02*
X597776D01*
G01X598583D02*
X598209D01*
G01Y1112953D02*
X597776D01*
G01X598583D02*
X598209D01*
G01Y1116102D02*
X597776D01*
G01X598583D02*
X598209D01*
G01X599931Y1104644D02*
X599935Y1104639D01*
G01X599927Y1104648D02*
X599931Y1104644D01*
G01X599921Y1104652D02*
X599927Y1104648D01*
G01X599915Y1104655D02*
X599921Y1104652D01*
G01X599908Y1104657D02*
X599915Y1104655D01*
G01X599902Y1104657D02*
X599908D01*
G01X599931Y1107794D02*
X599935Y1107789D01*
G01X599927Y1107798D02*
X599931Y1107794D01*
G01X599921Y1107802D02*
X599927Y1107798D01*
G01X599915Y1107804D02*
X599921Y1107802D01*
G01X599908Y1107806D02*
X599915Y1107804D01*
G01X599902Y1107807D02*
X599908Y1107806D01*
G01X599931Y1110943D02*
X599935Y1110938D01*
G01X599927Y1110948D02*
X599931Y1110943D01*
G01X599921Y1110952D02*
X599927Y1110948D01*
G01X599915Y1110954D02*
X599921Y1110952D01*
G01X599908Y1110956D02*
X599915Y1110954D01*
G01X599902Y1110956D02*
X599908D01*
G01X599931Y1114093D02*
X599935Y1114088D01*
G01X599927Y1114097D02*
X599931Y1114093D01*
G01X599921Y1114101D02*
X599927Y1114097D01*
G01X599915Y1114104D02*
X599921Y1114101D01*
G01X599908Y1114106D02*
X599915Y1114104D01*
G01X599902Y1114106D02*
X599908D01*
G01X599931Y1117243D02*
X599935Y1117237D01*
G01X599927Y1117247D02*
X599931Y1117243D01*
G01X599921Y1117251D02*
X599927Y1117247D01*
G01X599915Y1117253D02*
X599921Y1117251D01*
G01X599908Y1117255D02*
X599915Y1117253D01*
G01X599902Y1117256D02*
X599908Y1117255D01*
G01X599931Y1120392D02*
X599935Y1120387D01*
G01X599927Y1120396D02*
X599931Y1120392D01*
G01X599921Y1120400D02*
X599927Y1120396D01*
G01X599915Y1120403D02*
X599921Y1120400D01*
G01X599908Y1120405D02*
X599915Y1120403D01*
G01X599902Y1120405D02*
X599908D01*
G01X599931Y1123542D02*
X599935Y1123537D01*
G01X599927Y1123546D02*
X599931Y1123542D01*
G01X599921Y1123550D02*
X599927Y1123546D01*
G01X599915Y1123552D02*
X599921Y1123550D01*
G01X599908Y1123554D02*
X599915Y1123552D01*
G01X599902Y1123555D02*
X599908Y1123554D01*
G01X598957Y1103483D02*
Y1103491D01*
G01X598960Y1103476D02*
X598957Y1103483D01*
G01X598963Y1103470D02*
X598960Y1103476D01*
G01X598968Y1103464D02*
X598963Y1103470D01*
G01X598974Y1103459D02*
X598968Y1103464D01*
G01X598981Y1103456D02*
X598974Y1103459D01*
G01X598989Y1103454D02*
X598981Y1103456D01*
G01X598996Y1103454D02*
X598989D01*
G01X598957Y1106633D02*
Y1106640D01*
G01X598960Y1106626D02*
X598957Y1106633D01*
G01X598963Y1106620D02*
X598960Y1106626D01*
G01X598968Y1106614D02*
X598963Y1106620D01*
G01X598974Y1106609D02*
X598968Y1106614D01*
G01X598981Y1106606D02*
X598974Y1106609D01*
G01X598989Y1106604D02*
X598981Y1106606D01*
G01X598996Y1106603D02*
X598989Y1106604D01*
G01X598957Y1109782D02*
Y1109790D01*
G01X598960Y1109776D02*
X598957Y1109782D01*
G01X598963Y1109769D02*
X598960Y1109776D01*
G01X598968Y1109763D02*
X598963Y1109769D01*
G01X598974Y1109759D02*
X598968Y1109763D01*
G01X598981Y1109756D02*
X598974Y1109759D01*
G01X598989Y1109754D02*
X598981Y1109756D01*
G01X598996Y1109753D02*
X598989Y1109754D01*
G01X598957Y1112932D02*
Y1112939D01*
G01X598960Y1112925D02*
X598957Y1112932D01*
G01X598963Y1112919D02*
X598960Y1112925D01*
G01X598968Y1112913D02*
X598963Y1112919D01*
G01X598974Y1112908D02*
X598968Y1112913D01*
G01X598981Y1112905D02*
X598974Y1112908D01*
G01X598989Y1112903D02*
X598981Y1112905D01*
G01X598996Y1112902D02*
X598989Y1112903D01*
G01X598957Y1116081D02*
Y1116089D01*
G01X598960Y1116075D02*
X598957Y1116081D01*
G01X598963Y1116069D02*
X598960Y1116075D01*
G01X598968Y1116063D02*
X598963Y1116069D01*
G01X598974Y1116058D02*
X598968Y1116063D01*
G01X598981Y1116055D02*
X598974Y1116058D01*
G01X598989Y1116053D02*
X598981Y1116055D01*
G01X598996Y1116052D02*
X598989Y1116053D01*
G01X598957Y1119231D02*
Y1119239D01*
G01X598960Y1119224D02*
X598957Y1119231D01*
G01X598963Y1119218D02*
X598960Y1119224D01*
G01X598968Y1119212D02*
X598963Y1119218D01*
G01X598974Y1119207D02*
X598968Y1119212D01*
G01X598981Y1119204D02*
X598974Y1119207D01*
G01X598989Y1119202D02*
X598981Y1119204D01*
G01X598996Y1119202D02*
X598989D01*
G01X598957Y1122381D02*
Y1122388D01*
G01X598960Y1122374D02*
X598957Y1122381D01*
G01X598963Y1122368D02*
X598960Y1122374D01*
G01X598968Y1122362D02*
X598963Y1122368D01*
G01X598974Y1122357D02*
X598968Y1122362D01*
G01X598981Y1122354D02*
X598974Y1122357D01*
G01X598989Y1122352D02*
X598981Y1122354D01*
G01X598996Y1122351D02*
X598989Y1122352D01*
G01X599911Y1120393D02*
X599920Y1120388D01*
G01X599900Y1120394D02*
X599911Y1120393D01*
G01Y1123542D02*
X599920Y1123538D01*
G01X599900Y1123543D02*
X599911Y1123542D01*
G01X598959Y1104626D02*
X598954Y1104606D01*
G01X598974Y1104641D02*
X598959Y1104626D01*
G01X598994Y1104646D02*
X598974Y1104641D01*
G01X598959Y1107776D02*
X598954Y1107756D01*
G01X598974Y1107790D02*
X598959Y1107776D01*
G01X598994Y1107795D02*
X598974Y1107790D01*
G01X598959Y1110925D02*
X598954Y1110906D01*
G01X598974Y1110940D02*
X598959Y1110925D01*
G01X598994Y1110945D02*
X598974Y1110940D01*
G01X598959Y1114075D02*
X598954Y1114055D01*
G01X598974Y1114089D02*
X598959Y1114075D01*
G01X598994Y1114094D02*
X598974Y1114089D01*
G01X598959Y1117224D02*
X598954Y1117205D01*
G01X598974Y1117239D02*
X598959Y1117224D01*
G01X598994Y1117244D02*
X598974Y1117239D01*
G01X598959Y1120374D02*
X598954Y1120354D01*
G01X598974Y1120389D02*
X598959Y1120374D01*
G01X598994Y1120394D02*
X598974Y1120389D01*
G01X598959Y1123524D02*
X598954Y1123504D01*
G01X598974Y1123538D02*
X598959Y1123524D01*
G01X598994Y1123543D02*
X598974Y1123538D01*
G01X599934Y1103484D02*
X599939Y1103504D01*
G01X599920Y1103470D02*
X599934Y1103484D01*
G01X599900Y1103465D02*
X599920Y1103470D01*
G01X599934Y1106634D02*
X599939Y1106654D01*
G01X599920Y1106620D02*
X599934Y1106634D01*
G01X599900Y1106614D02*
X599920Y1106620D01*
G01X599934Y1109783D02*
X599939Y1109803D01*
G01X599920Y1109769D02*
X599934Y1109783D01*
G01X599900Y1109764D02*
X599920Y1109769D01*
G01X599934Y1112933D02*
X599939Y1112953D01*
G01X599920Y1112919D02*
X599934Y1112933D01*
G01X599900Y1112913D02*
X599920Y1112919D01*
G01X599934Y1116083D02*
X599939Y1116102D01*
G01X599920Y1116069D02*
X599934Y1116083D01*
G01X599900Y1116063D02*
X599920Y1116069D01*
G01X599934Y1119232D02*
X599939Y1119252D01*
G01X599920Y1119218D02*
X599934Y1119232D01*
G01X599900Y1119213D02*
X599920Y1119218D01*
G01X599934Y1122382D02*
X599939Y1122402D01*
G01X599920Y1122368D02*
X599934Y1122382D01*
G01X599900Y1122362D02*
X599920Y1122368D01*
G01X598843Y1122402D02*
X598955Y1122393D01*
G01X598954Y1112949D02*
X598843Y1112953D01*
G01X598954Y1106650D02*
X598843Y1106654D01*
G01X598954Y1116099D02*
X598843Y1116102D01*
G01X600394Y1125709D02*
X597047D01*
G01X599902Y1123740D02*
X598996D01*
G01X599941Y1123701D02*
X598957D01*
G01X599900Y1123543D02*
X594016D01*
G01Y1123504D02*
X599940D01*
G01X599939Y1122402D02*
X594016D01*
G01X599900Y1122362D02*
X594016D01*
G01X598957Y1122205D02*
X599941D01*
G01X598996Y1122165D02*
X599902D01*
G01Y1120591D02*
X598996D01*
G01X599941Y1120551D02*
X598957D01*
G01X599900Y1120394D02*
X594016D01*
G01Y1120354D02*
X599940D01*
G01X599939Y1119252D02*
X594016D01*
G01X599900Y1119213D02*
X594016D01*
G01X598957Y1119055D02*
X599941D01*
G01X598996Y1119016D02*
X599902D01*
G01Y1117441D02*
X598996D01*
G01X599941Y1117402D02*
X598957D01*
G01X599900Y1117244D02*
X594016D01*
G01Y1117205D02*
X599940D01*
G01X599939Y1116102D02*
X594016D01*
G01X599900Y1116063D02*
X594016D01*
G01X598957Y1115906D02*
X599941D01*
G01X598996Y1115866D02*
X599902D01*
G01Y1114291D02*
X598996D01*
G01X599941Y1114252D02*
X598957D01*
G01X599900Y1114094D02*
X594016D01*
G01Y1114055D02*
X599940D01*
G01X599939Y1112953D02*
X594016D01*
G01X599900Y1112913D02*
X594016D01*
G01X598957Y1112756D02*
X599941D01*
G01X598996Y1112717D02*
X599902D01*
G01Y1111142D02*
X598996D01*
G01X599941Y1111102D02*
X598957D01*
G01X599900Y1110945D02*
X594016D01*
G01Y1110906D02*
X599940D01*
G01X599939Y1109803D02*
X594016D01*
G01X599900Y1109764D02*
X594016D01*
G01X598957Y1109606D02*
X599941D01*
G01X598996Y1109567D02*
X599902D01*
G01Y1107992D02*
X598996D01*
G01X599941Y1107953D02*
X598957D01*
G01X599900Y1107795D02*
X594016D01*
G01Y1107756D02*
X599940D01*
G01X599939Y1106654D02*
X594016D01*
G01X599900Y1106614D02*
X594016D01*
G01X598957Y1106457D02*
X599941D01*
G01X598996Y1106417D02*
X599902D01*
G01Y1104843D02*
X598996D01*
G01X599941Y1104803D02*
X598957D01*
G01X599900Y1104646D02*
X594016D01*
G01Y1104606D02*
X599940D01*
G01X599939Y1103504D02*
X594016D01*
G01X599900Y1103465D02*
X594016D01*
G01X598957Y1103307D02*
X599941D01*
G01X598996Y1103268D02*
X599902D01*
G01X600394Y1101299D02*
X597047D01*
G01X599900Y1119213D02*
X599904Y1119202D01*
G01X599941Y1104609D02*
Y1104620D01*
G01Y1107758D02*
Y1107769D01*
G01Y1110908D02*
Y1110919D01*
G01Y1114057D02*
Y1114069D01*
G01Y1117207D02*
Y1117218D01*
G01Y1120357D02*
Y1120368D01*
G01Y1123506D02*
Y1123517D01*
G01X600394Y1204744D02*
Y1125709D01*
G01X599941Y1122205D02*
Y1123701D01*
G01Y1119055D02*
Y1120551D01*
G01Y1115906D02*
Y1117402D01*
G01Y1112756D02*
Y1114252D01*
G01Y1109606D02*
Y1111102D01*
G01Y1106457D02*
Y1107953D01*
G01Y1103307D02*
Y1104803D01*
G01X599902Y1106603D02*
Y1106456D01*
G01Y1103454D02*
Y1103307D01*
G01Y1104804D02*
Y1104657D01*
G01Y1109753D02*
Y1109606D01*
G01Y1111103D02*
Y1110956D01*
G01Y1107953D02*
Y1107807D01*
G01Y1116052D02*
Y1115905D01*
G01Y1112902D02*
Y1112756D01*
G01Y1114252D02*
Y1114106D01*
G01Y1119202D02*
Y1119055D01*
G01Y1120552D02*
Y1120405D01*
G01Y1117402D02*
Y1117256D01*
G01Y1122351D02*
Y1122204D01*
G01Y1123701D02*
Y1123555D01*
G01X598996Y1122204D02*
Y1122351D01*
G01Y1123555D02*
Y1123702D01*
G01Y1119054D02*
Y1119202D01*
G01Y1120405D02*
Y1120552D01*
G01Y1117256D02*
Y1117402D01*
G01Y1115905D02*
Y1116052D01*
G01Y1112755D02*
Y1112902D01*
G01Y1114106D02*
Y1114253D01*
G01Y1109606D02*
Y1109753D01*
G01Y1110956D02*
Y1111103D01*
G01Y1107807D02*
Y1107954D01*
G01Y1106456D02*
Y1106603D01*
G01Y1103306D02*
Y1103454D01*
G01Y1104657D02*
Y1104804D01*
G01X598957Y1104803D02*
Y1103307D01*
G01Y1111102D02*
Y1109606D01*
G01Y1107953D02*
Y1106457D01*
G01Y1114252D02*
Y1112756D01*
G01Y1120551D02*
Y1119055D01*
G01Y1117402D02*
Y1115906D01*
G01Y1123701D02*
Y1122205D01*
G01X597776Y1107795D02*
Y1106614D01*
G01Y1104646D02*
Y1103465D01*
G01Y1110945D02*
Y1109764D01*
G01Y1117244D02*
Y1116063D01*
G01Y1114094D02*
Y1112913D01*
G01Y1120394D02*
Y1119213D01*
G01Y1123543D02*
Y1122362D01*
G01X597441Y1125709D02*
Y1101299D01*
G01X597047D02*
Y1125709D01*
G01X594016Y1122362D02*
Y1123543D01*
G01Y1119213D02*
Y1120394D01*
G01Y1116063D02*
Y1117244D01*
G01Y1112913D02*
Y1114094D01*
G01Y1109764D02*
Y1110945D01*
G01Y1106614D02*
Y1107795D01*
G01Y1103465D02*
Y1104646D01*
G01X599941Y1122388D02*
Y1122399D01*
G01Y1119239D02*
Y1119250D01*
G01Y1116089D02*
Y1116100D01*
G01Y1112939D02*
Y1112950D01*
G01Y1109790D02*
Y1109801D01*
G01Y1106640D02*
Y1106651D01*
G01Y1103491D02*
Y1103502D01*
G01X604528Y1222776D02*
G03X603937Y1222185I0J-591D01*
G01X599016Y1223563D02*
G03X597047Y1221594I0J-1969D01*
G01X605315Y1213091D02*
G03X604134Y1211909I0J-1181D01*
G01X616732Y1223563D02*
X599016D01*
G01X611811Y1217657D02*
X603937D01*
G01Y1216083D02*
X611811D01*
G01X618701Y1213130D02*
X597047D01*
G01X600394Y1204744D02*
X614764D01*
G01X600394Y1203366D02*
X604134D01*
G01X600394Y1202500D02*
X615354D01*
G01X602165Y1201004D02*
X610039D01*
G01X603346Y1199823D02*
X608858D01*
G01X602165Y1201004D02*
X603346Y1199823D01*
G01X597047Y1205846D02*
X600394Y1202500D01*
G01X606693Y1208406D02*
X604383Y1212635D01*
G01X604134Y1203366D02*
Y1211909D01*
G01X603937Y1216083D02*
Y1222185D01*
G01X597047Y1221594D02*
Y1205846D01*
G01X569094Y1274016D02*
G03X567913I-590J0D01*
G01X565945D02*
G03X564764I-590J0D01*
G01X569094D02*
G03X567913I-590J0D01*
G01X565945D02*
G03X564764I-590J0D01*
G01X563976Y1275197D02*
X569882D01*
G01Y1275000D02*
X563976D01*
G01X569094Y1274016D02*
X569882D01*
G01X569094D02*
X569882D01*
G01X565945D02*
X567913D01*
G01X563976D02*
X564764D01*
G01X565945D02*
X567913D01*
G01X563976D02*
X564764D01*
G01X569882D02*
Y1280315D01*
G01Y1274016D02*
Y1280315D01*
G01X563976Y1274016D02*
Y1280315D01*
G01D02*
Y1274016D01*
G01X567913Y1280315D02*
G03X569094I591J0D01*
G01X564764D02*
G03X565945I590J0D01*
G01X567913D02*
G03X569094I591J0D01*
G01X564764D02*
G03X565945I590J0D01*
G01X567913D02*
X565945D01*
G01X564764D02*
X563976D01*
G01X567913D02*
X565945D01*
G01X564764D02*
X563976D01*
G01X569882D02*
X569094D01*
G01X569882D02*
X569094D01*
G01X569882Y1279331D02*
X563976D01*
G01Y1279134D02*
X569882D01*
G01X628765Y-7874D02*
G03Y0I0J3937D01*
G01Y-7874D02*
G03Y0I0J3937D01*
G01X626870Y51969D02*
G03X635531I4331J0D01*
G01D02*
G03X626870I-4331J0D01*
G01X643602Y36220D02*
G03X666043I11220J0D01*
G01D02*
G03X643602I-11221J0D01*
G01X635531Y51969D02*
G03I-4330J0D01*
G01X666043Y36221D02*
G03I-11220J0D01*
G01X611220Y138720D02*
G03X611811Y139311I0J591D01*
G01X609055Y140492D02*
G03Y142461I0J984D01*
G01X606693D02*
G03Y140492I0J-984D01*
G01X608976Y153681D02*
G03I-1102J0D01*
G01X610433Y148406D02*
G03X611614Y149587I0J1181D01*
G01X609449Y153681D02*
G03I-1575J0D01*
G01X616732Y137933D02*
G03X618701Y139902I0J1969D01*
G01X610359Y156752D02*
X609055Y154783D01*
G01X618701Y139902D02*
Y155650D01*
G01X615354Y296988D02*
Y158996D01*
G01X614764Y299232D02*
Y156752D01*
G01X611811Y145413D02*
Y139311D01*
G01X611614Y158130D02*
Y149587D01*
G01X610039Y196949D02*
Y160492D01*
G01X609055Y154783D02*
Y153091D01*
G01X608858Y198130D02*
Y161673D01*
G01X606693Y153091D02*
Y154783D01*
G01X609055Y153091D02*
X611365Y148861D01*
G01X606693Y154783D02*
X605389Y156752D01*
G01X615354Y158996D02*
X618701Y155650D01*
G01X608858Y161673D02*
X610039Y160492D01*
G01X611614Y158130D02*
X614764D01*
G01X609055Y154783D02*
X606693D01*
G01X609055Y153091D02*
X606693D01*
G01X610433Y148406D02*
X605315D01*
G01X609055Y142461D02*
X606693D01*
G01Y140492D02*
X609055D01*
G01X611220Y138720D02*
X604528D01*
G01X613354Y166173D02*
X613365Y166157D01*
G01X613329Y166181D02*
X613354Y166173D01*
G01Y171173D02*
X613365Y171157D01*
G01X613329Y171181D02*
X613354Y171173D01*
G01Y176173D02*
X613365Y176157D01*
G01X613329Y176181D02*
X613354Y176173D01*
G01Y181173D02*
X613365Y181157D01*
G01X613329Y181181D02*
X613354Y181173D01*
G01Y186173D02*
X613365Y186157D01*
G01X613329Y186181D02*
X613354Y186173D01*
G01Y191173D02*
X613365Y191157D01*
G01X613329Y191181D02*
X613354Y191173D01*
G01Y196173D02*
X613365Y196157D01*
G01X613329Y196181D02*
X613354Y196173D01*
G01X613367Y166148D02*
X613366Y166156D01*
G01X613367Y166144D02*
Y166148D01*
G01X613369Y166142D02*
X613367Y166144D01*
G01Y171148D02*
X613366Y171156D01*
G01X613367Y171144D02*
Y171148D01*
G01X613369Y171142D02*
X613367Y171144D01*
G01Y176148D02*
X613366Y176156D01*
G01X613367Y176144D02*
Y176148D01*
G01X613369Y176142D02*
X613367Y176144D01*
G01Y181148D02*
X613366Y181156D01*
G01X613367Y181144D02*
Y181148D01*
G01X613369Y181142D02*
X613367Y181144D01*
G01Y186148D02*
X613366Y186156D01*
G01X613367Y186144D02*
Y186148D01*
G01X613369Y186142D02*
X613367Y186144D01*
G01Y191148D02*
X613366Y191156D01*
G01X613367Y191144D02*
Y191148D01*
G01X613369Y191142D02*
X613367Y191144D01*
G01Y196148D02*
X613366Y196156D01*
G01X613367Y196144D02*
Y196148D01*
G01X613369Y196142D02*
X613367Y196144D01*
G01X612382Y166189D02*
Y166198D01*
G01X612383Y166183D02*
X612382Y166189D01*
G01X612383Y166181D02*
Y166183D01*
G01X612382Y171189D02*
Y171198D01*
G01X612383Y171183D02*
X612382Y171189D01*
G01X612383Y171181D02*
Y171183D01*
G01X612382Y176189D02*
Y176198D01*
G01X612383Y176183D02*
X612382Y176189D01*
G01X612383Y176181D02*
Y176183D01*
G01X612382Y181189D02*
Y181198D01*
G01X612383Y181183D02*
X612382Y181189D01*
G01X612383Y181181D02*
Y181183D01*
G01X612382Y186189D02*
Y186198D01*
G01X612383Y186183D02*
X612382Y186189D01*
G01X612383Y186181D02*
Y186183D01*
G01X612382Y191189D02*
Y191198D01*
G01X612383Y191183D02*
X612382Y191189D01*
G01X612383Y191181D02*
Y191183D01*
G01X612382Y196189D02*
Y196198D01*
G01X612383Y196183D02*
X612382Y196189D01*
G01X612383Y196181D02*
Y196183D01*
G01X613358Y166325D02*
X613366Y166299D01*
G01X613348Y166352D02*
X613358Y166325D01*
G01X613337Y166378D02*
X613348Y166352D01*
G01X613358Y171325D02*
X613366Y171299D01*
G01X613348Y171352D02*
X613358Y171325D01*
G01X613337Y171378D02*
X613348Y171352D01*
G01X613358Y176325D02*
X613366Y176299D01*
G01X613348Y176352D02*
X613358Y176325D01*
G01X613337Y176378D02*
X613348Y176352D01*
G01X613358Y181325D02*
X613366Y181299D01*
G01X613348Y181352D02*
X613358Y181325D01*
G01X613337Y181378D02*
X613348Y181352D01*
G01X613358Y186325D02*
X613366Y186299D01*
G01X613348Y186352D02*
X613358Y186325D01*
G01X613337Y186378D02*
X613348Y186352D01*
G01X613358Y191325D02*
X613366Y191299D01*
G01X613348Y191352D02*
X613358Y191325D01*
G01X613337Y191378D02*
X613348Y191352D01*
G01X613358Y196325D02*
X613366Y196299D01*
G01X613348Y196352D02*
X613358Y196325D01*
G01X613337Y196378D02*
X613348Y196352D01*
G01X613349Y166176D02*
X613330Y166181D01*
G01X613363Y166162D02*
X613349Y166176D01*
G01X613369Y166142D02*
X613363Y166162D01*
G01X613349Y171176D02*
X613330Y171181D01*
G01X613363Y171162D02*
X613349Y171176D01*
G01X613369Y171142D02*
X613363Y171162D01*
G01X613349Y176176D02*
X613330Y176181D01*
G01X613363Y176162D02*
X613349Y176176D01*
G01X613369Y176142D02*
X613363Y176162D01*
G01X613349Y181176D02*
X613330Y181181D01*
G01X613363Y181162D02*
X613349Y181176D01*
G01X613369Y181142D02*
X613363Y181162D01*
G01X613349Y186176D02*
X613330Y186181D01*
G01X613363Y186162D02*
X613349Y186176D01*
G01X613369Y186142D02*
X613363Y186162D01*
G01X613349Y191176D02*
X613330Y191181D01*
G01X613363Y191162D02*
X613349Y191176D01*
G01X613369Y191142D02*
X613363Y191162D01*
G01X613349Y196176D02*
X613330Y196181D01*
G01X613363Y196162D02*
X613349Y196176D01*
G01X613369Y196142D02*
X613363Y196162D01*
G01X613333Y166279D02*
X613337Y166378D01*
G01X613328Y166207D02*
X613333Y166279D01*
G01X613330Y166181D02*
X613328Y166207D01*
G01X613333Y171279D02*
X613337Y171378D01*
G01X613328Y171207D02*
X613333Y171279D01*
G01X613330Y171181D02*
X613328Y171207D01*
G01X613333Y176279D02*
X613337Y176378D01*
G01X613328Y176207D02*
X613333Y176279D01*
G01X613330Y176181D02*
X613328Y176207D01*
G01X613333Y181279D02*
X613337Y181378D01*
G01X613328Y181207D02*
X613333Y181279D01*
G01X613330Y181181D02*
X613328Y181207D01*
G01X613333Y186279D02*
X613337Y186378D01*
G01X613328Y186207D02*
X613333Y186279D01*
G01X613330Y186181D02*
X613328Y186207D01*
G01X613333Y191279D02*
X613337Y191378D01*
G01X613328Y191207D02*
X613333Y191279D01*
G01X613330Y191181D02*
X613328Y191207D01*
G01X613333Y196279D02*
X613337Y196378D01*
G01X613328Y196207D02*
X613333Y196279D01*
G01X613330Y196181D02*
X613328Y196207D01*
G01X612383Y194802D02*
Y194803D01*
G01X612382Y194796D02*
X612383Y194802D01*
G01X612382Y194787D02*
Y194796D01*
G01X612383Y189802D02*
Y189803D01*
G01X612382Y189796D02*
X612383Y189802D01*
G01X612382Y189787D02*
Y189796D01*
G01X612383Y184802D02*
Y184803D01*
G01X612382Y184796D02*
X612383Y184802D01*
G01X612382Y184787D02*
Y184796D01*
G01X612383Y179802D02*
Y179803D01*
G01X612382Y179796D02*
X612383Y179802D01*
G01X612382Y179787D02*
Y179796D01*
G01X612383Y174802D02*
Y174803D01*
G01X612382Y174796D02*
X612383Y174802D01*
G01X612382Y174787D02*
Y174796D01*
G01X612383Y169802D02*
Y169803D01*
G01X612382Y169796D02*
X612383Y169802D01*
G01X612382Y169787D02*
Y169796D01*
G01X612383Y164802D02*
Y164803D01*
G01X612382Y164796D02*
X612383Y164802D01*
G01X612382Y164787D02*
Y164796D01*
G01X613367Y194796D02*
X613366Y194787D01*
G01X613367Y194802D02*
Y194796D01*
G01X613369Y194803D02*
X613367Y194802D01*
G01Y189796D02*
X613366Y189787D01*
G01X613367Y189802D02*
Y189796D01*
G01X613369Y189803D02*
X613367Y189802D01*
G01Y184796D02*
X613366Y184787D01*
G01X613367Y184802D02*
Y184796D01*
G01X613369Y184803D02*
X613367Y184802D01*
G01Y179796D02*
X613366Y179787D01*
G01X613367Y179802D02*
Y179796D01*
G01X613369Y179803D02*
X613367Y179802D01*
G01Y174796D02*
X613366Y174787D01*
G01X613367Y174802D02*
Y174796D01*
G01X613369Y174803D02*
X613367Y174802D01*
G01Y169796D02*
X613366Y169787D01*
G01X613367Y169802D02*
Y169796D01*
G01X613369Y169803D02*
X613367Y169802D01*
G01Y164796D02*
X613366Y164787D01*
G01X613367Y164802D02*
Y164796D01*
G01X613369Y164803D02*
X613367Y164802D01*
G01X613366Y166155D02*
X613367Y166164D01*
G01X613366Y171155D02*
X613367Y171164D01*
G01X613366Y176155D02*
X613367Y176164D01*
G01X613366Y181155D02*
X613367Y181164D01*
G01X613366Y186155D02*
X613367Y186164D01*
G01X613366Y191155D02*
X613367Y191164D01*
G01X613366Y196155D02*
X613367Y196164D01*
G01X617717Y194803D02*
Y196181D01*
G01Y189803D02*
Y191181D01*
G01Y184803D02*
Y186181D01*
G01Y179803D02*
Y181181D01*
G01Y174803D02*
Y176181D01*
G01Y169803D02*
Y171181D01*
G01Y164803D02*
Y166181D01*
G01X614547D02*
Y164803D01*
G01Y171181D02*
Y169803D01*
G01Y176181D02*
Y174803D01*
G01Y181181D02*
Y179803D01*
G01Y186181D02*
Y184803D01*
G01Y191181D02*
Y189803D01*
G01Y196181D02*
Y194803D01*
G01X613976Y219035D02*
Y196949D01*
G01X613366Y166156D02*
Y166299D01*
G01Y171156D02*
Y171299D01*
G01Y176156D02*
Y176299D01*
G01Y181156D02*
Y181299D01*
G01Y186156D02*
Y186299D01*
G01Y191156D02*
Y191299D01*
G01Y196156D02*
Y196299D01*
G01Y194311D02*
Y196673D01*
G01Y189311D02*
Y191673D01*
G01Y184311D02*
Y186673D01*
G01Y179311D02*
Y181673D01*
G01Y174311D02*
Y176673D01*
G01Y169311D02*
Y171673D01*
G01Y164311D02*
Y166673D01*
G01X612795Y217854D02*
Y198130D01*
G01X612382Y166673D02*
Y164311D01*
G01Y171673D02*
Y169311D01*
G01Y176673D02*
Y174311D01*
G01Y181673D02*
Y179311D01*
G01Y186673D02*
Y184311D01*
G01Y191673D02*
Y189311D01*
G01Y196673D02*
Y194311D01*
G01X612795Y198130D02*
X608858D01*
G01X613976Y196949D02*
X610039D01*
G01X613366Y196673D02*
X612382D01*
G01X612383Y196181D02*
X617717D01*
G01Y196142D02*
X613369D01*
G01X617717Y194803D02*
X612383D01*
G01X612382Y194311D02*
X613366D01*
G01Y191673D02*
X612382D01*
G01X612383Y191181D02*
X617717D01*
G01Y191142D02*
X613369D01*
G01X617717Y189803D02*
X612383D01*
G01X612382Y189311D02*
X613366D01*
G01Y186673D02*
X612382D01*
G01X612383Y186181D02*
X617717D01*
G01Y186142D02*
X613369D01*
G01X617717Y184803D02*
X612383D01*
G01X612382Y184311D02*
X613366D01*
G01Y181673D02*
X612382D01*
G01X612383Y181181D02*
X617717D01*
G01Y181142D02*
X613369D01*
G01X617717Y179803D02*
X612383D01*
G01X612382Y179311D02*
X613366D01*
G01Y176673D02*
X612382D01*
G01X612383Y176181D02*
X617717D01*
G01Y176142D02*
X613369D01*
G01X617717Y174803D02*
X612383D01*
G01X612382Y174311D02*
X613366D01*
G01Y171673D02*
X612382D01*
G01X612383Y171181D02*
X617717D01*
G01Y171142D02*
X613369D01*
G01X617717Y169803D02*
X612383D01*
G01X612382Y169311D02*
X613366D01*
G01X612382Y196377D02*
X613337Y196378D01*
G01X613366Y194607D02*
X612382Y194606D01*
G01Y191377D02*
X613337Y191378D01*
G01X613366Y189607D02*
X612382Y189606D01*
G01Y186377D02*
X613337Y186378D01*
G01X613366Y184607D02*
X612382Y184606D01*
G01Y181377D02*
X613337Y181378D01*
G01X613366Y179607D02*
X612382Y179606D01*
G01Y176377D02*
X613337Y176378D01*
G01X613366Y174607D02*
X612382Y174606D01*
G01Y171377D02*
X613337Y171378D01*
G01X613366Y169607D02*
X612382Y169606D01*
G01X612795Y198130D02*
X613976Y196949D01*
G01X608858Y198130D02*
X610039Y196949D01*
G01X613366Y166673D02*
X612382D01*
G01X612383Y166181D02*
X617717D01*
G01Y166142D02*
X613369D01*
G01X617717Y164803D02*
X612383D01*
G01X612382Y164311D02*
X613366D01*
G01X612382Y166377D02*
X613337Y166378D01*
G01X613366Y164607D02*
X612382Y164606D01*
G01X613354Y221173D02*
X613365Y221157D01*
G01X613329Y221181D02*
X613354Y221173D01*
G01Y226173D02*
X613365Y226157D01*
G01X613329Y226181D02*
X613354Y226173D01*
G01Y231173D02*
X613365Y231157D01*
G01X613329Y231181D02*
X613354Y231173D01*
G01Y236173D02*
X613365Y236157D01*
G01X613329Y236181D02*
X613354Y236173D01*
G01Y241173D02*
X613365Y241157D01*
G01X613329Y241181D02*
X613354Y241173D01*
G01Y246173D02*
X613365Y246157D01*
G01X613329Y246181D02*
X613354Y246173D01*
G01Y251173D02*
X613365Y251157D01*
G01X613329Y251181D02*
X613354Y251173D01*
G01X613367Y221148D02*
X613366Y221156D01*
G01X613367Y221144D02*
Y221148D01*
G01X613369Y221142D02*
X613367Y221144D01*
G01Y226148D02*
X613366Y226156D01*
G01X613367Y226144D02*
Y226148D01*
G01X613369Y226142D02*
X613367Y226144D01*
G01Y231148D02*
X613366Y231156D01*
G01X613367Y231144D02*
Y231148D01*
G01X613369Y231142D02*
X613367Y231144D01*
G01X613354Y256173D02*
X613365Y256157D01*
G01X613329Y256181D02*
X613354Y256173D01*
G01X613367Y236148D02*
X613366Y236156D01*
G01X613367Y236144D02*
Y236148D01*
G01X613369Y236142D02*
X613367Y236144D01*
G01Y241148D02*
X613366Y241156D01*
G01X613367Y241144D02*
Y241148D01*
G01X613369Y241142D02*
X613367Y241144D01*
G01Y246148D02*
X613366Y246156D01*
G01X613367Y246144D02*
Y246148D01*
G01X613369Y246142D02*
X613367Y246144D01*
G01Y251148D02*
X613366Y251156D01*
G01X613367Y251144D02*
Y251148D01*
G01X613369Y251142D02*
X613367Y251144D01*
G01Y256148D02*
X613366Y256156D01*
G01X613367Y256144D02*
Y256148D01*
G01X613369Y256142D02*
X613367Y256144D01*
G01X612382Y221189D02*
Y221198D01*
G01X612383Y221183D02*
X612382Y221189D01*
G01X612383Y221181D02*
Y221183D01*
G01X612382Y226189D02*
Y226198D01*
G01X612383Y226183D02*
X612382Y226189D01*
G01X612383Y226181D02*
Y226183D01*
G01X612382Y231189D02*
Y231198D01*
G01X612383Y231183D02*
X612382Y231189D01*
G01X612383Y231181D02*
Y231183D01*
G01X612382Y236189D02*
Y236198D01*
G01X612383Y236183D02*
X612382Y236189D01*
G01X612383Y236181D02*
Y236183D01*
G01X612382Y241189D02*
Y241198D01*
G01X612383Y241183D02*
X612382Y241189D01*
G01X612383Y241181D02*
Y241183D01*
G01X612382Y246189D02*
Y246198D01*
G01X612383Y246183D02*
X612382Y246189D01*
G01X612383Y246181D02*
Y246183D01*
G01X612382Y251189D02*
Y251198D01*
G01X612383Y251183D02*
X612382Y251189D01*
G01X612383Y251181D02*
Y251183D01*
G01X612382Y256189D02*
Y256198D01*
G01X612383Y256183D02*
X612382Y256189D01*
G01X612383Y256181D02*
Y256183D01*
G01X613358Y221325D02*
X613366Y221299D01*
G01X613348Y221352D02*
X613358Y221325D01*
G01X613337Y221378D02*
X613348Y221352D01*
G01X613358Y226325D02*
X613366Y226299D01*
G01X613348Y226352D02*
X613358Y226325D01*
G01X613337Y226378D02*
X613348Y226352D01*
G01X613358Y231325D02*
X613366Y231299D01*
G01X613348Y231352D02*
X613358Y231325D01*
G01X613337Y231378D02*
X613348Y231352D01*
G01X613358Y236325D02*
X613366Y236299D01*
G01X613348Y236352D02*
X613358Y236325D01*
G01X613337Y236378D02*
X613348Y236352D01*
G01X613358Y241325D02*
X613366Y241299D01*
G01X613348Y241352D02*
X613358Y241325D01*
G01X613337Y241378D02*
X613348Y241352D01*
G01X613358Y246325D02*
X613366Y246299D01*
G01X613348Y246352D02*
X613358Y246325D01*
G01X613337Y246378D02*
X613348Y246352D01*
G01X613358Y251325D02*
X613366Y251299D01*
G01X613348Y251352D02*
X613358Y251325D01*
G01X613337Y251378D02*
X613348Y251352D01*
G01X613358Y256325D02*
X613366Y256299D01*
G01X613348Y256352D02*
X613358Y256325D01*
G01X613337Y256378D02*
X613348Y256352D01*
G01X613349Y221176D02*
X613330Y221181D01*
G01X613363Y221162D02*
X613349Y221176D01*
G01X613369Y221142D02*
X613363Y221162D01*
G01X613349Y226176D02*
X613330Y226181D01*
G01X613363Y226162D02*
X613349Y226176D01*
G01X613369Y226142D02*
X613363Y226162D01*
G01X613349Y231176D02*
X613330Y231181D01*
G01X613363Y231162D02*
X613349Y231176D01*
G01X613369Y231142D02*
X613363Y231162D01*
G01X613349Y236176D02*
X613330Y236181D01*
G01X613363Y236162D02*
X613349Y236176D01*
G01X613369Y236142D02*
X613363Y236162D01*
G01X613349Y241176D02*
X613330Y241181D01*
G01X613363Y241162D02*
X613349Y241176D01*
G01X613369Y241142D02*
X613363Y241162D01*
G01X613349Y246176D02*
X613330Y246181D01*
G01X613363Y246162D02*
X613349Y246176D01*
G01X613369Y246142D02*
X613363Y246162D01*
G01X613349Y251176D02*
X613330Y251181D01*
G01X613363Y251162D02*
X613349Y251176D01*
G01X613369Y251142D02*
X613363Y251162D01*
G01X613349Y256176D02*
X613330Y256181D01*
G01X613363Y256162D02*
X613349Y256176D01*
G01X613369Y256142D02*
X613363Y256162D01*
G01X613333Y221279D02*
X613337Y221378D01*
G01X613328Y221207D02*
X613333Y221279D01*
G01X613330Y221181D02*
X613328Y221207D01*
G01X613333Y226279D02*
X613337Y226378D01*
G01X613328Y226207D02*
X613333Y226279D01*
G01X613330Y226181D02*
X613328Y226207D01*
G01X613333Y231279D02*
X613337Y231378D01*
G01X613328Y231207D02*
X613333Y231279D01*
G01X613330Y231181D02*
X613328Y231207D01*
G01X613333Y236279D02*
X613337Y236378D01*
G01X613328Y236207D02*
X613333Y236279D01*
G01X613330Y236181D02*
X613328Y236207D01*
G01X613333Y241279D02*
X613337Y241378D01*
G01X613328Y241207D02*
X613333Y241279D01*
G01X613330Y241181D02*
X613328Y241207D01*
G01X613333Y246279D02*
X613337Y246378D01*
G01X613328Y246207D02*
X613333Y246279D01*
G01X613330Y246181D02*
X613328Y246207D01*
G01X613333Y251279D02*
X613337Y251378D01*
G01X613328Y251207D02*
X613333Y251279D01*
G01X613330Y251181D02*
X613328Y251207D01*
G01X613333Y256279D02*
X613337Y256378D01*
G01X613328Y256207D02*
X613333Y256279D01*
G01X613330Y256181D02*
X613328Y256207D01*
G01X612383Y259802D02*
Y259803D01*
G01X612382Y259796D02*
X612383Y259802D01*
G01X612382Y259787D02*
Y259796D01*
G01X612383Y254802D02*
Y254803D01*
G01X612382Y254796D02*
X612383Y254802D01*
G01X612382Y254787D02*
Y254796D01*
G01X612383Y249802D02*
Y249803D01*
G01X612382Y249796D02*
X612383Y249802D01*
G01X612382Y249787D02*
Y249796D01*
G01X612383Y244802D02*
Y244803D01*
G01X612382Y244796D02*
X612383Y244802D01*
G01X612382Y244787D02*
Y244796D01*
G01X612383Y239802D02*
Y239803D01*
G01X612382Y239796D02*
X612383Y239802D01*
G01X612382Y239787D02*
Y239796D01*
G01X612383Y234802D02*
Y234803D01*
G01X612382Y234796D02*
X612383Y234802D01*
G01X612382Y234787D02*
Y234796D01*
G01X612383Y229802D02*
Y229803D01*
G01X612382Y229796D02*
X612383Y229802D01*
G01X612382Y229787D02*
Y229796D01*
G01X612383Y224802D02*
Y224803D01*
G01X612382Y224796D02*
X612383Y224802D01*
G01X612382Y224787D02*
Y224796D01*
G01X612383Y219802D02*
Y219803D01*
G01X612382Y219796D02*
X612383Y219802D01*
G01X612382Y219787D02*
Y219796D01*
G01X613367Y259796D02*
X613366Y259787D01*
G01X613367Y259802D02*
Y259796D01*
G01X613369Y259803D02*
X613367Y259802D01*
G01Y254796D02*
X613366Y254787D01*
G01X613367Y254802D02*
Y254796D01*
G01X613369Y254803D02*
X613367Y254802D01*
G01Y249796D02*
X613366Y249787D01*
G01X613367Y249802D02*
Y249796D01*
G01X613369Y249803D02*
X613367Y249802D01*
G01Y244796D02*
X613366Y244787D01*
G01X613367Y244802D02*
Y244796D01*
G01X613369Y244803D02*
X613367Y244802D01*
G01Y239796D02*
X613366Y239787D01*
G01X613367Y239802D02*
Y239796D01*
G01X613369Y239803D02*
X613367Y239802D01*
G01Y234796D02*
X613366Y234787D01*
G01X613367Y234802D02*
Y234796D01*
G01X613369Y234803D02*
X613367Y234802D01*
G01Y229796D02*
X613366Y229787D01*
G01X613367Y229802D02*
Y229796D01*
G01X613369Y229803D02*
X613367Y229802D01*
G01Y224796D02*
X613366Y224787D01*
G01X613367Y224802D02*
Y224796D01*
G01X613369Y224803D02*
X613367Y224802D01*
G01Y219796D02*
X613366Y219787D01*
G01X613367Y219802D02*
Y219796D01*
G01X613369Y219803D02*
X613367Y219802D01*
G01X612795Y217854D02*
X613976Y219035D01*
G01X608858Y217854D02*
X610039Y219035D01*
G01X613366Y221155D02*
X613367Y221164D01*
G01X613366Y226155D02*
X613367Y226164D01*
G01X613366Y231155D02*
X613367Y231164D01*
G01X613366Y236155D02*
X613367Y236164D01*
G01X613366Y241155D02*
X613367Y241164D01*
G01X613366Y246155D02*
X613367Y246164D01*
G01X613366Y251155D02*
X613367Y251164D01*
G01X613366Y256155D02*
X613367Y256164D01*
G01X617717Y259803D02*
Y261181D01*
G01Y254803D02*
Y256181D01*
G01Y249803D02*
Y251181D01*
G01Y244803D02*
Y246181D01*
G01Y239803D02*
Y241181D01*
G01Y234803D02*
Y236181D01*
G01Y229803D02*
Y231181D01*
G01Y224803D02*
Y226181D01*
G01Y219803D02*
Y221181D01*
G01X614547D02*
Y219803D01*
G01Y226181D02*
Y224803D01*
G01Y231181D02*
Y229803D01*
G01Y236181D02*
Y234803D01*
G01Y241181D02*
Y239803D01*
G01Y246181D02*
Y244803D01*
G01Y251181D02*
Y249803D01*
G01Y256181D02*
Y254803D01*
G01Y261181D02*
Y259803D01*
G01X613366Y221156D02*
Y221299D01*
G01Y226156D02*
Y226299D01*
G01Y231156D02*
Y231299D01*
G01Y236156D02*
Y236299D01*
G01Y241156D02*
Y241299D01*
G01Y246156D02*
Y246299D01*
G01Y251156D02*
Y251299D01*
G01Y256156D02*
Y256299D01*
G01Y259311D02*
Y261673D01*
G01Y254311D02*
Y256673D01*
G01Y249311D02*
Y251673D01*
G01Y244311D02*
Y246673D01*
G01Y239311D02*
Y241673D01*
G01Y234311D02*
Y236673D01*
G01Y229311D02*
Y231673D01*
G01Y224311D02*
Y226673D01*
G01Y219311D02*
Y221673D01*
G01X612382D02*
Y219311D01*
G01Y226673D02*
Y224311D01*
G01Y231673D02*
Y229311D01*
G01Y236673D02*
Y234311D01*
G01Y241673D02*
Y239311D01*
G01Y246673D02*
Y244311D01*
G01Y251673D02*
Y249311D01*
G01Y256673D02*
Y254311D01*
G01Y261673D02*
Y259311D01*
G01X610039Y295492D02*
Y219035D01*
G01X608858Y294311D02*
Y217854D01*
G01X617717Y259803D02*
X612383D01*
G01X612382Y259311D02*
X613366D01*
G01Y256673D02*
X612382D01*
G01X613366Y259607D02*
X612382Y259606D01*
G01Y256377D02*
X613337Y256378D01*
G01X612383Y256181D02*
X617717D01*
G01Y256142D02*
X613369D01*
G01X617717Y254803D02*
X612383D01*
G01X612382Y254311D02*
X613366D01*
G01Y251673D02*
X612382D01*
G01X612383Y251181D02*
X617717D01*
G01Y251142D02*
X613369D01*
G01X617717Y249803D02*
X612383D01*
G01X612382Y249311D02*
X613366D01*
G01Y246673D02*
X612382D01*
G01X612383Y246181D02*
X617717D01*
G01Y246142D02*
X613369D01*
G01X617717Y244803D02*
X612383D01*
G01X612382Y244311D02*
X613366D01*
G01Y241673D02*
X612382D01*
G01X612383Y241181D02*
X617717D01*
G01Y241142D02*
X613369D01*
G01X617717Y239803D02*
X612383D01*
G01X612382Y239311D02*
X613366D01*
G01Y236673D02*
X612382D01*
G01X612383Y236181D02*
X617717D01*
G01Y236142D02*
X613369D01*
G01X617717Y234803D02*
X612383D01*
G01X612382Y234311D02*
X613366D01*
G01Y231673D02*
X612382D01*
G01X612383Y231181D02*
X617717D01*
G01Y231142D02*
X613369D01*
G01X617717Y229803D02*
X612383D01*
G01X612382Y229311D02*
X613366D01*
G01Y226673D02*
X612382D01*
G01X612383Y226181D02*
X617717D01*
G01Y226142D02*
X613369D01*
G01X617717Y224803D02*
X612383D01*
G01X612382Y224311D02*
X613366D01*
G01Y221673D02*
X612382D01*
G01X612383Y221181D02*
X617717D01*
G01Y221142D02*
X613369D01*
G01X617717Y219803D02*
X612383D01*
G01X612382Y219311D02*
X613366D01*
G01X610039Y219035D02*
X613976D01*
G01X608858Y217854D02*
X612795D01*
G01X613366Y254607D02*
X612382Y254606D01*
G01Y251377D02*
X613337Y251378D01*
G01X613366Y249607D02*
X612382Y249606D01*
G01Y246377D02*
X613337Y246378D01*
G01X613366Y244607D02*
X612382Y244606D01*
G01Y241377D02*
X613337Y241378D01*
G01X613366Y239607D02*
X612382Y239606D01*
G01Y236377D02*
X613337Y236378D01*
G01X613366Y234607D02*
X612382Y234606D01*
G01Y231377D02*
X613337Y231378D01*
G01X613366Y229607D02*
X612382Y229606D01*
G01Y226377D02*
X613337Y226378D01*
G01X613366Y224607D02*
X612382Y224606D01*
G01Y221377D02*
X613337Y221378D01*
G01X613366Y219607D02*
X612382Y219606D01*
G01X613354Y261173D02*
X613365Y261157D01*
G01X613329Y261181D02*
X613354Y261173D01*
G01Y266173D02*
X613365Y266157D01*
G01X613329Y266181D02*
X613354Y266173D01*
G01Y271173D02*
X613365Y271157D01*
G01X613329Y271181D02*
X613354Y271173D01*
G01Y276173D02*
X613365Y276157D01*
G01X613329Y276181D02*
X613354Y276173D01*
G01Y281173D02*
X613365Y281157D01*
G01X613329Y281181D02*
X613354Y281173D01*
G01Y286173D02*
X613365Y286157D01*
G01X613329Y286181D02*
X613354Y286173D01*
G01Y291173D02*
X613365Y291157D01*
G01X613329Y291181D02*
X613354Y291173D01*
G01X613367Y261148D02*
X613366Y261156D01*
G01X613367Y261144D02*
Y261148D01*
G01X613369Y261142D02*
X613367Y261144D01*
G01Y266148D02*
X613366Y266156D01*
G01X613367Y266144D02*
Y266148D01*
G01X613369Y266142D02*
X613367Y266144D01*
G01Y271148D02*
X613366Y271156D01*
G01X613367Y271144D02*
Y271148D01*
G01X613369Y271142D02*
X613367Y271144D01*
G01Y276148D02*
X613366Y276156D01*
G01X613367Y276144D02*
Y276148D01*
G01X613369Y276142D02*
X613367Y276144D01*
G01Y281148D02*
X613366Y281156D01*
G01X613367Y281144D02*
Y281148D01*
G01X613369Y281142D02*
X613367Y281144D01*
G01Y286148D02*
X613366Y286156D01*
G01X613367Y286144D02*
Y286148D01*
G01X613369Y286142D02*
X613367Y286144D01*
G01Y291148D02*
X613366Y291156D01*
G01X613367Y291144D02*
Y291148D01*
G01X613369Y291142D02*
X613367Y291144D01*
G01X612382Y261189D02*
Y261198D01*
G01X612383Y261183D02*
X612382Y261189D01*
G01X612383Y261181D02*
Y261183D01*
G01X612382Y266189D02*
Y266198D01*
G01X612383Y266183D02*
X612382Y266189D01*
G01X612383Y266181D02*
Y266183D01*
G01X612382Y271189D02*
Y271198D01*
G01X612383Y271183D02*
X612382Y271189D01*
G01X612383Y271181D02*
Y271183D01*
G01X612382Y276189D02*
Y276198D01*
G01X612383Y276183D02*
X612382Y276189D01*
G01X612383Y276181D02*
Y276183D01*
G01X612382Y281189D02*
Y281198D01*
G01X612383Y281183D02*
X612382Y281189D01*
G01X612383Y281181D02*
Y281183D01*
G01X613358Y261325D02*
X613366Y261299D01*
G01X613348Y261352D02*
X613358Y261325D01*
G01X613337Y261378D02*
X613348Y261352D01*
G01X613358Y266325D02*
X613366Y266299D01*
G01X613348Y266352D02*
X613358Y266325D01*
G01X613337Y266378D02*
X613348Y266352D01*
G01X613358Y271325D02*
X613366Y271299D01*
G01X613348Y271352D02*
X613358Y271325D01*
G01X613337Y271378D02*
X613348Y271352D01*
G01X612382Y286189D02*
Y286198D01*
G01X612383Y286183D02*
X612382Y286189D01*
G01X612383Y286181D02*
Y286183D01*
G01X612382Y291189D02*
Y291198D01*
G01X612383Y291183D02*
X612382Y291189D01*
G01X612383Y291181D02*
Y291183D01*
G01X613358Y276325D02*
X613366Y276299D01*
G01X613348Y276352D02*
X613358Y276325D01*
G01X613337Y276378D02*
X613348Y276352D01*
G01X613358Y281325D02*
X613366Y281299D01*
G01X613348Y281352D02*
X613358Y281325D01*
G01X613337Y281378D02*
X613348Y281352D01*
G01X613358Y286325D02*
X613366Y286299D01*
G01X613348Y286352D02*
X613358Y286325D01*
G01X613337Y286378D02*
X613348Y286352D01*
G01X613358Y291325D02*
X613366Y291299D01*
G01X613348Y291352D02*
X613358Y291325D01*
G01X613337Y291378D02*
X613348Y291352D01*
G01X613349Y261176D02*
X613330Y261181D01*
G01X613363Y261162D02*
X613349Y261176D01*
G01X613369Y261142D02*
X613363Y261162D01*
G01X613349Y266176D02*
X613330Y266181D01*
G01X613363Y266162D02*
X613349Y266176D01*
G01X613369Y266142D02*
X613363Y266162D01*
G01X613349Y271176D02*
X613330Y271181D01*
G01X613363Y271162D02*
X613349Y271176D01*
G01X613369Y271142D02*
X613363Y271162D01*
G01X613349Y276176D02*
X613330Y276181D01*
G01X613363Y276162D02*
X613349Y276176D01*
G01X613369Y276142D02*
X613363Y276162D01*
G01X613349Y281176D02*
X613330Y281181D01*
G01X613363Y281162D02*
X613349Y281176D01*
G01X613369Y281142D02*
X613363Y281162D01*
G01X613349Y286176D02*
X613330Y286181D01*
G01X613363Y286162D02*
X613349Y286176D01*
G01X613369Y286142D02*
X613363Y286162D01*
G01X613349Y291176D02*
X613330Y291181D01*
G01X613363Y291162D02*
X613349Y291176D01*
G01X613369Y291142D02*
X613363Y291162D01*
G01X613333Y261279D02*
X613337Y261378D01*
G01X613328Y261207D02*
X613333Y261279D01*
G01X613330Y261181D02*
X613328Y261207D01*
G01X613333Y266279D02*
X613337Y266378D01*
G01X613328Y266207D02*
X613333Y266279D01*
G01X613330Y266181D02*
X613328Y266207D01*
G01X613333Y271279D02*
X613337Y271378D01*
G01X613328Y271207D02*
X613333Y271279D01*
G01X613330Y271181D02*
X613328Y271207D01*
G01X613333Y276279D02*
X613337Y276378D01*
G01X613328Y276207D02*
X613333Y276279D01*
G01X613330Y276181D02*
X613328Y276207D01*
G01X613333Y281279D02*
X613337Y281378D01*
G01X613328Y281207D02*
X613333Y281279D01*
G01X613330Y281181D02*
X613328Y281207D01*
G01X613333Y286279D02*
X613337Y286378D01*
G01X613328Y286207D02*
X613333Y286279D01*
G01X613330Y286181D02*
X613328Y286207D01*
G01X613333Y291279D02*
X613337Y291378D01*
G01X613328Y291207D02*
X613333Y291279D01*
G01X613330Y291181D02*
X613328Y291207D01*
G01X612383Y289802D02*
Y289803D01*
G01X612382Y289796D02*
X612383Y289802D01*
G01X612382Y289787D02*
Y289796D01*
G01X612383Y284802D02*
Y284803D01*
G01X612382Y284796D02*
X612383Y284802D01*
G01X612382Y284787D02*
Y284796D01*
G01X612383Y279802D02*
Y279803D01*
G01X612382Y279796D02*
X612383Y279802D01*
G01X612382Y279787D02*
Y279796D01*
G01X612383Y274802D02*
Y274803D01*
G01X612382Y274796D02*
X612383Y274802D01*
G01X612382Y274787D02*
Y274796D01*
G01X612383Y269802D02*
Y269803D01*
G01X612382Y269796D02*
X612383Y269802D01*
G01X612382Y269787D02*
Y269796D01*
G01X612383Y264802D02*
Y264803D01*
G01X612382Y264796D02*
X612383Y264802D01*
G01X612382Y264787D02*
Y264796D01*
G01X613367Y289796D02*
X613366Y289787D01*
G01X613367Y289802D02*
Y289796D01*
G01X613369Y289803D02*
X613367Y289802D01*
G01Y284796D02*
X613366Y284787D01*
G01X613367Y284802D02*
Y284796D01*
G01X613369Y284803D02*
X613367Y284802D01*
G01Y279796D02*
X613366Y279787D01*
G01X613367Y279802D02*
Y279796D01*
G01X613369Y279803D02*
X613367Y279802D01*
G01Y274796D02*
X613366Y274787D01*
G01X613367Y274802D02*
Y274796D01*
G01X613369Y274803D02*
X613367Y274802D01*
G01Y269796D02*
X613366Y269787D01*
G01X613367Y269802D02*
Y269796D01*
G01X613369Y269803D02*
X613367Y269802D01*
G01Y264796D02*
X613366Y264787D01*
G01X613367Y264802D02*
Y264796D01*
G01X613369Y264803D02*
X613367Y264802D01*
G01X611614Y306398D02*
G03X610433Y307579I-1181J0D01*
G01X609764Y302303D02*
G03I-1890J0D01*
G01X610236D02*
G03I-2362J0D01*
G01X618701Y300335D02*
X615354Y296988D01*
G01X608858Y294311D02*
X610039Y295492D01*
G01X605389Y299232D02*
X606693Y301201D01*
G01X611365Y307123D02*
X609055Y302894D01*
G01X613366Y261155D02*
X613367Y261164D01*
G01X613366Y266155D02*
X613367Y266164D01*
G01X613366Y271155D02*
X613367Y271164D01*
G01X613366Y276155D02*
X613367Y276164D01*
G01X613366Y281155D02*
X613367Y281164D01*
G01X613366Y286155D02*
X613367Y286164D01*
G01X613366Y291155D02*
X613367Y291164D01*
G01X618701Y300335D02*
Y316083D01*
G01X617717Y289803D02*
Y291181D01*
G01Y284803D02*
Y286181D01*
G01Y279803D02*
Y281181D01*
G01Y274803D02*
Y276181D01*
G01Y269803D02*
Y271181D01*
G01Y264803D02*
Y266181D01*
G01X614547D02*
Y264803D01*
G01Y271181D02*
Y269803D01*
G01Y276181D02*
Y274803D01*
G01Y281181D02*
Y279803D01*
G01Y286181D02*
Y284803D01*
G01Y291181D02*
Y289803D01*
G01X613366Y261156D02*
Y261299D01*
G01Y266156D02*
Y266299D01*
G01Y271156D02*
Y271299D01*
G01Y276156D02*
Y276299D01*
G01Y281156D02*
Y281299D01*
G01Y286156D02*
Y286299D01*
G01Y291156D02*
Y291299D01*
G01Y289311D02*
Y291673D01*
G01Y284311D02*
Y286673D01*
G01Y279311D02*
Y281673D01*
G01Y274311D02*
Y276673D01*
G01Y269311D02*
Y271673D01*
G01Y264311D02*
Y266673D01*
G01X612382D02*
Y264311D01*
G01Y271673D02*
Y269311D01*
G01Y276673D02*
Y274311D01*
G01Y281673D02*
Y279311D01*
G01Y286673D02*
Y284311D01*
G01Y291673D02*
Y289311D01*
G01X611614Y306398D02*
Y297854D01*
G01X609055Y302894D02*
Y301201D01*
G01X606693D02*
Y302894D01*
G01X605315Y307579D02*
X610433D01*
G01X606693Y302894D02*
X609055D01*
G01X606693Y301201D02*
X609055D01*
G01X614764Y297854D02*
X611614D01*
G01X613366Y291673D02*
X612382D01*
G01X612383Y291181D02*
X617717D01*
G01Y291142D02*
X613369D01*
G01X617717Y289803D02*
X612383D01*
G01X612382Y289311D02*
X613366D01*
G01Y286673D02*
X612382D01*
G01X612383Y286181D02*
X617717D01*
G01Y286142D02*
X613369D01*
G01X617717Y284803D02*
X612383D01*
G01X612382Y284311D02*
X613366D01*
G01Y281673D02*
X612382D01*
G01X612383Y281181D02*
X617717D01*
G01Y281142D02*
X613369D01*
G01X617717Y279803D02*
X612383D01*
G01X612382Y279311D02*
X613366D01*
G01Y276673D02*
X612382D01*
G01X612383Y276181D02*
X617717D01*
G01Y276142D02*
X613369D01*
G01X617717Y274803D02*
X612383D01*
G01X612382Y274311D02*
X613366D01*
G01Y271673D02*
X612382D01*
G01X612383Y271181D02*
X617717D01*
G01Y271142D02*
X613369D01*
G01X617717Y269803D02*
X612383D01*
G01X612382Y269311D02*
X613366D01*
G01Y266673D02*
X612382D01*
G01X612383Y266181D02*
X617717D01*
G01Y266142D02*
X613369D01*
G01X617717Y264803D02*
X612383D01*
G01X612382Y264311D02*
X613366D01*
G01Y261673D02*
X612382D01*
G01X612383Y261181D02*
X617717D01*
G01Y261142D02*
X613369D01*
G01X612382Y291377D02*
X613337Y291378D01*
G01X613366Y289607D02*
X612382Y289606D01*
G01Y286377D02*
X613337Y286378D01*
G01X613366Y284607D02*
X612382Y284606D01*
G01Y281377D02*
X613337Y281378D01*
G01X613366Y279607D02*
X612382Y279606D01*
G01Y276377D02*
X613337Y276378D01*
G01X613366Y274607D02*
X612382Y274606D01*
G01Y271377D02*
X613337Y271378D01*
G01X613366Y269607D02*
X612382Y269606D01*
G01Y266377D02*
X613337Y266378D01*
G01X613366Y264607D02*
X612382Y264606D01*
G01Y261377D02*
X613337Y261378D01*
G01X609055Y301201D02*
X610359Y299232D01*
G01X610358Y378885D02*
G03X644169I16906J-13531D01*
G01X610358D02*
G03X644169I16906J-13531D01*
G01X611811Y316673D02*
G03X611220Y317264I-591J0D01*
G01X606693Y315492D02*
G03Y313524I0J-984D01*
G01X609055D02*
G03Y315492I0J984D01*
G01X618701Y316083D02*
G03X616732Y318051I-1968J0D01*
G01X611811Y310571D02*
Y316673D01*
G01X611220Y317264D02*
X604528D01*
G01X609055Y315492D02*
X606693D01*
G01Y313524D02*
X609055D01*
G01X637244Y392016D02*
G03X644169Y378885I37662J11471D01*
G01X637244Y392016D02*
G03X617283I-9980J-3039D01*
G01X610358Y378885D02*
G03X617283Y392016I-30737J24602D01*
G01X637244D02*
G03X617283I-9980J-3039D01*
G01X637244D02*
G03X644169Y378885I37662J11471D01*
G01X610358D02*
G03X617283Y392016I-30737J24602D01*
G01X611220Y591476D02*
G03X611811Y592067I0J591D01*
G01X609055Y593248D02*
G03Y595217I0J985D01*
G01X606693D02*
G03Y593248I0J-985D01*
G01X616732Y590689D02*
G03X618701Y592657I0J1969D01*
G01X609055Y595217D02*
X606693D01*
G01Y593248D02*
X609055D01*
G01X611220Y591476D02*
X604528D01*
G01X618701Y592657D02*
Y608406D01*
G01X611811Y598169D02*
Y592067D01*
G01X613333Y619035D02*
X613337Y619134D01*
G01X613328Y618963D02*
X613333Y619035D01*
G01X613330Y618937D02*
X613328Y618963D01*
G01X613333Y624035D02*
X613337Y624134D01*
G01X613328Y623963D02*
X613333Y624035D01*
G01X613330Y623937D02*
X613328Y623963D01*
G01X613333Y629035D02*
X613337Y629134D01*
G01X613328Y628963D02*
X613333Y629035D01*
G01X613330Y628937D02*
X613328Y628963D01*
G01X613333Y634035D02*
X613337Y634134D01*
G01X613328Y633963D02*
X613333Y634035D01*
G01X613330Y633937D02*
X613328Y633963D01*
G01X613333Y639035D02*
X613337Y639134D01*
G01X613328Y638963D02*
X613333Y639035D01*
G01X613330Y638937D02*
X613328Y638963D01*
G01X613333Y644035D02*
X613337Y644134D01*
G01X613328Y643963D02*
X613333Y644035D01*
G01X613330Y643937D02*
X613328Y643963D01*
G01X612383Y647557D02*
Y647559D01*
G01X612382Y647552D02*
X612383Y647557D01*
G01X612382Y647543D02*
Y647552D01*
G01X612383Y642557D02*
Y642559D01*
G01X612382Y642552D02*
X612383Y642557D01*
G01X612382Y642543D02*
Y642552D01*
G01X612383Y637557D02*
Y637559D01*
G01X612382Y637552D02*
X612383Y637557D01*
G01X612382Y637543D02*
Y637552D01*
G01X612383Y632557D02*
Y632559D01*
G01X612382Y632552D02*
X612383Y632557D01*
G01X612382Y632543D02*
Y632552D01*
G01X612383Y627557D02*
Y627559D01*
G01X612382Y627552D02*
X612383Y627557D01*
G01X612382Y627543D02*
Y627552D01*
G01X612383Y622557D02*
Y622559D01*
G01X612382Y622552D02*
X612383Y622557D01*
G01X612382Y622543D02*
Y622552D01*
G01X612383Y617557D02*
Y617559D01*
G01X612382Y617552D02*
X612383Y617557D01*
G01X612382Y617543D02*
Y617552D01*
G01X613367Y618904D02*
X613366Y618911D01*
G01X613367Y618900D02*
Y618904D01*
G01X613369Y618898D02*
X613367Y618900D01*
G01Y623904D02*
X613366Y623911D01*
G01X613367Y623900D02*
Y623904D01*
G01X613369Y623898D02*
X613367Y623900D01*
G01Y628904D02*
X613366Y628911D01*
G01X613367Y628900D02*
Y628904D01*
G01X613369Y628898D02*
X613367Y628900D01*
G01Y633904D02*
X613366Y633911D01*
G01X613367Y633900D02*
Y633904D01*
G01X613369Y633898D02*
X613367Y633900D01*
G01Y638904D02*
X613366Y638911D01*
G01X613367Y638900D02*
Y638904D01*
G01X613369Y638898D02*
X613367Y638900D01*
G01Y643904D02*
X613366Y643911D01*
G01X613367Y643900D02*
Y643904D01*
G01X613369Y643898D02*
X613367Y643900D01*
G01X612382Y618944D02*
Y618954D01*
G01X612383Y618939D02*
X612382Y618944D01*
G01X612383Y618937D02*
Y618939D01*
G01X612382Y623944D02*
Y623954D01*
G01X612383Y623939D02*
X612382Y623944D01*
G01X612383Y623937D02*
Y623939D01*
G01X612382Y628944D02*
Y628954D01*
G01X612383Y628939D02*
X612382Y628944D01*
G01X612383Y628937D02*
Y628939D01*
G01X612382Y633944D02*
Y633954D01*
G01X612383Y633939D02*
X612382Y633944D01*
G01X612383Y633937D02*
Y633939D01*
G01X612382Y638944D02*
Y638954D01*
G01X612383Y638939D02*
X612382Y638944D01*
G01X612383Y638937D02*
Y638939D01*
G01X612382Y643944D02*
Y643954D01*
G01X612383Y643939D02*
X612382Y643944D01*
G01X612383Y643937D02*
Y643939D01*
G01X613358Y619081D02*
X613366Y619055D01*
G01X613348Y619107D02*
X613358Y619081D01*
G01X613337Y619134D02*
X613348Y619107D01*
G01X613358Y624081D02*
X613366Y624055D01*
G01X613348Y624107D02*
X613358Y624081D01*
G01X613337Y624134D02*
X613348Y624107D01*
G01X613358Y629081D02*
X613366Y629055D01*
G01X613348Y629107D02*
X613358Y629081D01*
G01X613337Y629134D02*
X613348Y629107D01*
G01X613358Y634081D02*
X613366Y634055D01*
G01X613348Y634107D02*
X613358Y634081D01*
G01X613337Y634134D02*
X613348Y634107D01*
G01X613358Y639081D02*
X613366Y639055D01*
G01X613348Y639107D02*
X613358Y639081D01*
G01X613337Y639134D02*
X613348Y639107D01*
G01X613358Y644081D02*
X613366Y644055D01*
G01X613348Y644107D02*
X613358Y644081D01*
G01X613337Y644134D02*
X613348Y644107D01*
G01X613349Y618932D02*
X613330Y618937D01*
G01X613363Y618918D02*
X613349Y618932D01*
G01X613369Y618898D02*
X613363Y618918D01*
G01X613349Y623932D02*
X613330Y623937D01*
G01X613363Y623918D02*
X613349Y623932D01*
G01X613369Y623898D02*
X613363Y623918D01*
G01X613349Y628932D02*
X613330Y628937D01*
G01X613363Y628918D02*
X613349Y628932D01*
G01X613369Y628898D02*
X613363Y628918D01*
G01X613349Y633932D02*
X613330Y633937D01*
G01X613363Y633918D02*
X613349Y633932D01*
G01X613369Y633898D02*
X613363Y633918D01*
G01X613349Y638932D02*
X613330Y638937D01*
G01X613363Y638918D02*
X613349Y638932D01*
G01X613369Y638898D02*
X613363Y638918D01*
G01X613349Y643932D02*
X613330Y643937D01*
G01X613363Y643918D02*
X613349Y643932D01*
G01X613369Y643898D02*
X613363Y643918D01*
G01X613354Y618929D02*
X613365Y618913D01*
G01X613329Y618937D02*
X613354Y618929D01*
G01Y623929D02*
X613365Y623913D01*
G01X613329Y623937D02*
X613354Y623929D01*
G01Y628929D02*
X613365Y628913D01*
G01X613329Y628937D02*
X613354Y628929D01*
G01Y633929D02*
X613365Y633913D01*
G01X613329Y633937D02*
X613354Y633929D01*
G01X613367Y647552D02*
X613366Y647543D01*
G01X613367Y647557D02*
Y647552D01*
G01X613369Y647559D02*
X613367Y647557D01*
G01Y642552D02*
X613366Y642543D01*
G01X613367Y642557D02*
Y642552D01*
G01X613369Y642559D02*
X613367Y642557D01*
G01Y637552D02*
X613366Y637543D01*
G01X613367Y637557D02*
Y637552D01*
G01X613369Y637559D02*
X613367Y637557D01*
G01Y632552D02*
X613366Y632543D01*
G01X613367Y632557D02*
Y632552D01*
G01X613369Y632559D02*
X613367Y632557D01*
G01Y627552D02*
X613366Y627543D01*
G01X613367Y627557D02*
Y627552D01*
G01X613369Y627559D02*
X613367Y627557D01*
G01Y622552D02*
X613366Y622543D01*
G01X613367Y622557D02*
Y622552D01*
G01X613369Y622559D02*
X613367Y622557D01*
G01Y617552D02*
X613366Y617543D01*
G01X613367Y617557D02*
Y617552D01*
G01X613369Y617559D02*
X613367Y617557D01*
G01X613354Y638929D02*
X613365Y638913D01*
G01X613329Y638937D02*
X613354Y638929D01*
G01Y643929D02*
X613365Y643913D01*
G01X613329Y643937D02*
X613354Y643929D01*
G01X668504Y646457D02*
G03X651969I-8268J0D01*
G01D02*
G03X668504I8268J0D01*
G01X608976Y606437D02*
G03I-1102J0D01*
G01X610433Y601161D02*
G03X611614Y602343I0J1181D01*
G01X609449Y606437D02*
G03I-1575J0D01*
G01X668504Y646457D02*
G03I-8268J0D01*
G01X617717Y647559D02*
X612383D01*
G01X612382Y647067D02*
X613366D01*
G01Y644429D02*
X612382D01*
G01X612383Y643937D02*
X617717D01*
G01Y643898D02*
X613369D01*
G01X617717Y642559D02*
X612383D01*
G01X612382Y642067D02*
X613366D01*
G01Y639429D02*
X612382D01*
G01X612383Y638937D02*
X617717D01*
G01Y638898D02*
X613369D01*
G01X617717Y637559D02*
X612383D01*
G01X612382Y637067D02*
X613366D01*
G01Y634429D02*
X612382D01*
G01X612383Y633937D02*
X617717D01*
G01Y633898D02*
X613369D01*
G01X617717Y632559D02*
X612383D01*
G01X612382Y632067D02*
X613366D01*
G01Y629429D02*
X612382D01*
G01X612383Y628937D02*
X617717D01*
G01Y628898D02*
X613369D01*
G01X617717Y627559D02*
X612383D01*
G01X612382Y627067D02*
X613366D01*
G01Y624429D02*
X612382D01*
G01X612383Y623937D02*
X617717D01*
G01Y623898D02*
X613369D01*
G01X617717Y622559D02*
X612383D01*
G01X612382Y622067D02*
X613366D01*
G01Y619429D02*
X612382D01*
G01X612383Y618937D02*
X617717D01*
G01Y618898D02*
X613369D01*
G01X617717Y617559D02*
X612383D01*
G01X612382Y617067D02*
X613366D01*
G01Y647363D02*
X612382Y647362D01*
G01Y644133D02*
X613337Y644134D01*
G01X613366Y642363D02*
X612382Y642362D01*
G01Y639133D02*
X613337Y639134D01*
G01X613366Y637363D02*
X612382Y637362D01*
G01Y634133D02*
X613337Y634134D01*
G01X613366Y632363D02*
X612382Y632362D01*
G01Y629133D02*
X613337Y629134D01*
G01X613366Y627363D02*
X612382Y627362D01*
G01Y624133D02*
X613337Y624134D01*
G01X613366Y622363D02*
X612382Y622362D01*
G01Y619133D02*
X613337Y619134D01*
G01X613366Y617363D02*
X612382Y617362D01*
G01X611614Y610886D02*
X614764D01*
G01X609055Y607539D02*
X606693D01*
G01X609055Y605846D02*
X606693D01*
G01X610433Y601161D02*
X605315D01*
G01X610359Y609508D02*
X609055Y607539D01*
G01Y605846D02*
X611365Y601617D01*
G01X606693Y607539D02*
X605389Y609508D01*
G01X615354Y611752D02*
X618701Y608406D01*
G01X608858Y614429D02*
X610039Y613248D01*
G01X613366Y618911D02*
X613367Y618920D01*
G01X613366Y623911D02*
X613367Y623920D01*
G01X613366Y628911D02*
X613367Y628920D01*
G01X613366Y633911D02*
X613367Y633920D01*
G01X613366Y638911D02*
X613367Y638920D01*
G01X613366Y643911D02*
X613367Y643920D01*
G01X617717Y647559D02*
Y648937D01*
G01Y642559D02*
Y643937D01*
G01Y637559D02*
Y638937D01*
G01Y632559D02*
Y633937D01*
G01Y627559D02*
Y628937D01*
G01Y622559D02*
Y623937D01*
G01Y617559D02*
Y618937D01*
G01X615354Y749744D02*
Y611752D01*
G01X614764Y751988D02*
Y609508D01*
G01X614547Y618937D02*
Y617559D01*
G01Y623937D02*
Y622559D01*
G01Y628937D02*
Y627559D01*
G01Y633937D02*
Y632559D01*
G01Y638937D02*
Y637559D01*
G01Y643937D02*
Y642559D01*
G01Y648937D02*
Y647559D01*
G01X613366Y647067D02*
Y649429D01*
G01Y642067D02*
Y644429D01*
G01Y637067D02*
Y639429D01*
G01Y632067D02*
Y634429D01*
G01Y627067D02*
Y629429D01*
G01Y622067D02*
Y624429D01*
G01Y617067D02*
Y619429D01*
G01X612382D02*
Y617067D01*
G01Y624429D02*
Y622067D01*
G01Y629429D02*
Y627067D01*
G01Y634429D02*
Y632067D01*
G01Y639429D02*
Y637067D01*
G01Y644429D02*
Y642067D01*
G01Y649429D02*
Y647067D01*
G01X611614Y610886D02*
Y602343D01*
G01X610039Y649705D02*
Y613248D01*
G01X609055Y607539D02*
Y605846D01*
G01X608858Y650886D02*
Y614429D01*
G01X606693Y605846D02*
Y607539D01*
G01X613333Y649035D02*
X613337Y649134D01*
G01X613328Y648963D02*
X613333Y649035D01*
G01X613330Y648937D02*
X613328Y648963D01*
G01X613333Y674035D02*
X613337Y674134D01*
G01X613328Y673963D02*
X613333Y674035D01*
G01X613330Y673937D02*
X613328Y673963D01*
G01X613333Y679035D02*
X613337Y679134D01*
G01X613328Y678963D02*
X613333Y679035D01*
G01X613330Y678937D02*
X613328Y678963D01*
G01X613333Y684035D02*
X613337Y684134D01*
G01X613328Y683963D02*
X613333Y684035D01*
G01X613330Y683937D02*
X613328Y683963D01*
G01X613333Y689035D02*
X613337Y689134D01*
G01X613328Y688963D02*
X613333Y689035D01*
G01X613330Y688937D02*
X613328Y688963D01*
G01X613333Y694035D02*
X613337Y694134D01*
G01X613328Y693963D02*
X613333Y694035D01*
G01X613330Y693937D02*
X613328Y693963D01*
G01X612383Y692557D02*
Y692559D01*
G01X612382Y692552D02*
X612383Y692557D01*
G01X612382Y692543D02*
Y692552D01*
G01X612383Y687557D02*
Y687559D01*
G01X612382Y687552D02*
X612383Y687557D01*
G01X612382Y687543D02*
Y687552D01*
G01X612383Y682557D02*
Y682559D01*
G01X612382Y682552D02*
X612383Y682557D01*
G01X612382Y682543D02*
Y682552D01*
G01X612383Y677557D02*
Y677559D01*
G01X612382Y677552D02*
X612383Y677557D01*
G01X612382Y677543D02*
Y677552D01*
G01X612383Y672557D02*
Y672559D01*
G01X612382Y672552D02*
X612383Y672557D01*
G01X612382Y672543D02*
Y672552D01*
G01X613367Y648904D02*
X613366Y648911D01*
G01X613367Y648900D02*
Y648904D01*
G01X613369Y648898D02*
X613367Y648900D01*
G01Y673904D02*
X613366Y673911D01*
G01X613367Y673900D02*
Y673904D01*
G01X613369Y673898D02*
X613367Y673900D01*
G01X612382Y648944D02*
Y648954D01*
G01X612383Y648939D02*
X612382Y648944D01*
G01X612383Y648937D02*
Y648939D01*
G01X612382Y673944D02*
Y673954D01*
G01X612383Y673939D02*
X612382Y673944D01*
G01X612383Y673937D02*
Y673939D01*
G01X612382Y678944D02*
Y678954D01*
G01X612383Y678939D02*
X612382Y678944D01*
G01X612383Y678937D02*
Y678939D01*
G01X612382Y683944D02*
Y683954D01*
G01X612383Y683939D02*
X612382Y683944D01*
G01X612383Y683937D02*
Y683939D01*
G01X612382Y688944D02*
Y688954D01*
G01X612383Y688939D02*
X612382Y688944D01*
G01X612383Y688937D02*
Y688939D01*
G01X612382Y693944D02*
Y693954D01*
G01X612383Y693939D02*
X612382Y693944D01*
G01X612383Y693937D02*
Y693939D01*
G01X613358Y649081D02*
X613366Y649055D01*
G01X613348Y649107D02*
X613358Y649081D01*
G01X613337Y649134D02*
X613348Y649107D01*
G01X613358Y674081D02*
X613366Y674055D01*
G01X613348Y674107D02*
X613358Y674081D01*
G01X613337Y674134D02*
X613348Y674107D01*
G01X613358Y679081D02*
X613366Y679055D01*
G01X613348Y679107D02*
X613358Y679081D01*
G01X613337Y679134D02*
X613348Y679107D01*
G01X613358Y684081D02*
X613366Y684055D01*
G01X613348Y684107D02*
X613358Y684081D01*
G01X613337Y684134D02*
X613348Y684107D01*
G01X613358Y689081D02*
X613366Y689055D01*
G01X613348Y689107D02*
X613358Y689081D01*
G01X613337Y689134D02*
X613348Y689107D01*
G01X613358Y694081D02*
X613366Y694055D01*
G01X613348Y694107D02*
X613358Y694081D01*
G01X613337Y694134D02*
X613348Y694107D01*
G01X613349Y648932D02*
X613330Y648937D01*
G01X613363Y648918D02*
X613349Y648932D01*
G01X613369Y648898D02*
X613363Y648918D01*
G01X613349Y673932D02*
X613330Y673937D01*
G01X613363Y673918D02*
X613349Y673932D01*
G01X613369Y673898D02*
X613363Y673918D01*
G01X613349Y678932D02*
X613330Y678937D01*
G01X613363Y678918D02*
X613349Y678932D01*
G01X613369Y678898D02*
X613363Y678918D01*
G01X613349Y683932D02*
X613330Y683937D01*
G01X613363Y683918D02*
X613349Y683932D01*
G01X613369Y683898D02*
X613363Y683918D01*
G01X613349Y688932D02*
X613330Y688937D01*
G01X613363Y688918D02*
X613349Y688932D01*
G01X613369Y688898D02*
X613363Y688918D01*
G01X613349Y693932D02*
X613330Y693937D01*
G01X613363Y693918D02*
X613349Y693932D01*
G01X613369Y693898D02*
X613363Y693918D01*
G01X613367Y678904D02*
X613366Y678911D01*
G01X613367Y678900D02*
Y678904D01*
G01X613369Y678898D02*
X613367Y678900D01*
G01Y683904D02*
X613366Y683911D01*
G01X613367Y683900D02*
Y683904D01*
G01X613369Y683898D02*
X613367Y683900D01*
G01Y688904D02*
X613366Y688911D01*
G01X613367Y688900D02*
Y688904D01*
G01X613369Y688898D02*
X613367Y688900D01*
G01Y693904D02*
X613366Y693911D01*
G01X613367Y693900D02*
Y693904D01*
G01X613369Y693898D02*
X613367Y693900D01*
G01Y692552D02*
X613366Y692543D01*
G01X613367Y692557D02*
Y692552D01*
G01X613369Y692559D02*
X613367Y692557D01*
G01Y687552D02*
X613366Y687543D01*
G01X613367Y687557D02*
Y687552D01*
G01X613369Y687559D02*
X613367Y687557D01*
G01Y682552D02*
X613366Y682543D01*
G01X613367Y682557D02*
Y682552D01*
G01X613369Y682559D02*
X613367Y682557D01*
G01Y677552D02*
X613366Y677543D01*
G01X613367Y677557D02*
Y677552D01*
G01X613369Y677559D02*
X613367Y677557D01*
G01Y672552D02*
X613366Y672543D01*
G01X613367Y672557D02*
Y672552D01*
G01X613369Y672559D02*
X613367Y672557D01*
G01X613354Y648929D02*
X613365Y648913D01*
G01X613329Y648937D02*
X613354Y648929D01*
G01Y673929D02*
X613365Y673913D01*
G01X613329Y673937D02*
X613354Y673929D01*
G01Y678929D02*
X613365Y678913D01*
G01X613329Y678937D02*
X613354Y678929D01*
G01Y683929D02*
X613365Y683913D01*
G01X613329Y683937D02*
X613354Y683929D01*
G01Y688929D02*
X613365Y688913D01*
G01X613329Y688937D02*
X613354Y688929D01*
G01Y693929D02*
X613365Y693913D01*
G01X613329Y693937D02*
X613354Y693929D01*
G01X613366Y694429D02*
X612382D01*
G01X612383Y693937D02*
X617717D01*
G01Y693898D02*
X613369D01*
G01X617717Y692559D02*
X612383D01*
G01X612382Y692067D02*
X613366D01*
G01Y689429D02*
X612382D01*
G01X612383Y688937D02*
X617717D01*
G01Y688898D02*
X613369D01*
G01X617717Y687559D02*
X612383D01*
G01X612382Y687067D02*
X613366D01*
G01Y684429D02*
X612382D01*
G01X612383Y683937D02*
X617717D01*
G01Y683898D02*
X613369D01*
G01X617717Y682559D02*
X612383D01*
G01X612382Y682067D02*
X613366D01*
G01Y679429D02*
X612382D01*
G01X612383Y678937D02*
X617717D01*
G01Y678898D02*
X613369D01*
G01X617717Y677559D02*
X612383D01*
G01X612382Y677067D02*
X613366D01*
G01Y674429D02*
X612382D01*
G01X612383Y673937D02*
X617717D01*
G01Y673898D02*
X613369D01*
G01X617717Y672559D02*
X612383D01*
G01X612382Y672067D02*
X613366D01*
G01X610039Y671791D02*
X613976D01*
G01X608858Y670610D02*
X612795D01*
G01Y650886D02*
X608858D01*
G01X613976Y649705D02*
X610039D01*
G01X613366Y649429D02*
X612382D01*
G01X612383Y648937D02*
X617717D01*
G01Y648898D02*
X613369D01*
G01X612382Y694133D02*
X613337Y694134D01*
G01X613366Y692363D02*
X612382Y692362D01*
G01Y689133D02*
X613337Y689134D01*
G01X613366Y687363D02*
X612382Y687362D01*
G01Y684133D02*
X613337Y684134D01*
G01X613366Y682363D02*
X612382Y682362D01*
G01Y679133D02*
X613337Y679134D01*
G01X613366Y677363D02*
X612382Y677362D01*
G01Y674133D02*
X613337Y674134D01*
G01X613366Y672363D02*
X612382Y672362D01*
G01Y649133D02*
X613337Y649134D01*
G01X612795Y670610D02*
X613976Y671791D01*
G01X608858Y670610D02*
X610039Y671791D01*
G01X612795Y650886D02*
X613976Y649705D01*
G01X608858Y650886D02*
X610039Y649705D01*
G01X613366Y648911D02*
X613367Y648920D01*
G01X613366Y673911D02*
X613367Y673920D01*
G01X613366Y678911D02*
X613367Y678920D01*
G01X613366Y683911D02*
X613367Y683920D01*
G01X613366Y688911D02*
X613367Y688920D01*
G01X613366Y693911D02*
X613367Y693920D01*
G01X617717Y692559D02*
Y693937D01*
G01Y687559D02*
Y688937D01*
G01Y682559D02*
Y683937D01*
G01Y677559D02*
Y678937D01*
G01Y672559D02*
Y673937D01*
G01X614547D02*
Y672559D01*
G01Y678937D02*
Y677559D01*
G01Y683937D02*
Y682559D01*
G01Y688937D02*
Y687559D01*
G01Y693937D02*
Y692559D01*
G01X613976Y671791D02*
Y649705D01*
G01X613366Y692067D02*
Y694429D01*
G01Y687067D02*
Y689429D01*
G01Y682067D02*
Y684429D01*
G01Y677067D02*
Y679429D01*
G01Y672067D02*
Y674429D01*
G01X612795Y670610D02*
Y650886D01*
G01X612382Y674429D02*
Y672067D01*
G01Y679429D02*
Y677067D01*
G01Y684429D02*
Y682067D01*
G01Y689429D02*
Y687067D01*
G01Y694429D02*
Y692067D01*
G01X610039Y748248D02*
Y671791D01*
G01X608858Y747067D02*
Y670610D01*
G01X613333Y699035D02*
X613337Y699134D01*
G01X613328Y698963D02*
X613333Y699035D01*
G01X613330Y698937D02*
X613328Y698963D01*
G01X613333Y704035D02*
X613337Y704134D01*
G01X613328Y703963D02*
X613333Y704035D01*
G01X613330Y703937D02*
X613328Y703963D01*
G01X613333Y709035D02*
X613337Y709134D01*
G01X613328Y708963D02*
X613333Y709035D01*
G01X613330Y708937D02*
X613328Y708963D01*
G01X613333Y714035D02*
X613337Y714134D01*
G01X613328Y713963D02*
X613333Y714035D01*
G01X613330Y713937D02*
X613328Y713963D01*
G01X613333Y719035D02*
X613337Y719134D01*
G01X613328Y718963D02*
X613333Y719035D01*
G01X613330Y718937D02*
X613328Y718963D01*
G01X613333Y724035D02*
X613337Y724134D01*
G01X613328Y723963D02*
X613333Y724035D01*
G01X613330Y723937D02*
X613328Y723963D01*
G01X613333Y729035D02*
X613337Y729134D01*
G01X613328Y728963D02*
X613333Y729035D01*
G01X613330Y728937D02*
X613328Y728963D01*
G01X613333Y734035D02*
X613337Y734134D01*
G01X613328Y733963D02*
X613333Y734035D01*
G01X613330Y733937D02*
X613328Y733963D01*
G01X613333Y739035D02*
X613337Y739134D01*
G01X613328Y738963D02*
X613333Y739035D01*
G01X613330Y738937D02*
X613328Y738963D01*
G01X613333Y744035D02*
X613337Y744134D01*
G01X613328Y743963D02*
X613333Y744035D01*
G01X613330Y743937D02*
X613328Y743963D01*
G01X612383Y742557D02*
Y742559D01*
G01X612382Y742552D02*
X612383Y742557D01*
G01X612382Y742543D02*
Y742552D01*
G01X612383Y737557D02*
Y737559D01*
G01X612382Y737552D02*
X612383Y737557D01*
G01X612382Y737543D02*
Y737552D01*
G01X612383Y732557D02*
Y732559D01*
G01X612382Y732552D02*
X612383Y732557D01*
G01X612382Y732543D02*
Y732552D01*
G01X612383Y727557D02*
Y727559D01*
G01X612382Y727552D02*
X612383Y727557D01*
G01X612382Y727543D02*
Y727552D01*
G01X612383Y722557D02*
Y722559D01*
G01X612382Y722552D02*
X612383Y722557D01*
G01X612382Y722543D02*
Y722552D01*
G01X612383Y717557D02*
Y717559D01*
G01X612382Y717552D02*
X612383Y717557D01*
G01X612382Y717543D02*
Y717552D01*
G01X612383Y712557D02*
Y712559D01*
G01X612382Y712552D02*
X612383Y712557D01*
G01X612382Y712543D02*
Y712552D01*
G01X612383Y707557D02*
Y707559D01*
G01X612382Y707552D02*
X612383Y707557D01*
G01X612382Y707543D02*
Y707552D01*
G01X612383Y702557D02*
Y702559D01*
G01X612382Y702552D02*
X612383Y702557D01*
G01X612382Y702543D02*
Y702552D01*
G01X612383Y697557D02*
Y697559D01*
G01X612382Y697552D02*
X612383Y697557D01*
G01X612382Y697543D02*
Y697552D01*
G01Y698944D02*
Y698954D01*
G01X612383Y698939D02*
X612382Y698944D01*
G01X612383Y698937D02*
Y698939D01*
G01X612382Y703944D02*
Y703954D01*
G01X612383Y703939D02*
X612382Y703944D01*
G01X612383Y703937D02*
Y703939D01*
G01X612382Y708944D02*
Y708954D01*
G01X612383Y708939D02*
X612382Y708944D01*
G01X612383Y708937D02*
Y708939D01*
G01X612382Y713944D02*
Y713954D01*
G01X612383Y713939D02*
X612382Y713944D01*
G01X612383Y713937D02*
Y713939D01*
G01X612382Y718944D02*
Y718954D01*
G01X612383Y718939D02*
X612382Y718944D01*
G01X612383Y718937D02*
Y718939D01*
G01X612382Y723944D02*
Y723954D01*
G01X612383Y723939D02*
X612382Y723944D01*
G01X612383Y723937D02*
Y723939D01*
G01X613358Y699081D02*
X613366Y699055D01*
G01X613348Y699107D02*
X613358Y699081D01*
G01X613337Y699134D02*
X613348Y699107D01*
G01X613358Y704081D02*
X613366Y704055D01*
G01X613348Y704107D02*
X613358Y704081D01*
G01X613337Y704134D02*
X613348Y704107D01*
G01X613358Y709081D02*
X613366Y709055D01*
G01X613348Y709107D02*
X613358Y709081D01*
G01X613337Y709134D02*
X613348Y709107D01*
G01X613358Y714081D02*
X613366Y714055D01*
G01X613348Y714107D02*
X613358Y714081D01*
G01X613337Y714134D02*
X613348Y714107D01*
G01X613358Y719081D02*
X613366Y719055D01*
G01X613348Y719107D02*
X613358Y719081D01*
G01X613337Y719134D02*
X613348Y719107D01*
G01X613358Y724081D02*
X613366Y724055D01*
G01X613348Y724107D02*
X613358Y724081D01*
G01X613337Y724134D02*
X613348Y724107D01*
G01X613349Y698932D02*
X613330Y698937D01*
G01X613363Y698918D02*
X613349Y698932D01*
G01X613369Y698898D02*
X613363Y698918D01*
G01X613349Y703932D02*
X613330Y703937D01*
G01X613363Y703918D02*
X613349Y703932D01*
G01X613369Y703898D02*
X613363Y703918D01*
G01X613349Y708932D02*
X613330Y708937D01*
G01X613363Y708918D02*
X613349Y708932D01*
G01X613369Y708898D02*
X613363Y708918D01*
G01X613349Y713932D02*
X613330Y713937D01*
G01X613363Y713918D02*
X613349Y713932D01*
G01X613369Y713898D02*
X613363Y713918D01*
G01X613349Y718932D02*
X613330Y718937D01*
G01X613363Y718918D02*
X613349Y718932D01*
G01X613369Y718898D02*
X613363Y718918D01*
G01X613349Y723932D02*
X613330Y723937D01*
G01X613363Y723918D02*
X613349Y723932D01*
G01X613369Y723898D02*
X613363Y723918D01*
G01X613349Y728932D02*
X613330Y728937D01*
G01X613363Y728918D02*
X613349Y728932D01*
G01X613369Y728898D02*
X613363Y728918D01*
G01X613349Y733932D02*
X613330Y733937D01*
G01X613363Y733918D02*
X613349Y733932D01*
G01X613369Y733898D02*
X613363Y733918D01*
G01X613349Y738932D02*
X613330Y738937D01*
G01X613363Y738918D02*
X613349Y738932D01*
G01X613369Y738898D02*
X613363Y738918D01*
G01X613349Y743932D02*
X613330Y743937D01*
G01X613363Y743918D02*
X613349Y743932D01*
G01X613369Y743898D02*
X613363Y743918D01*
G01X613367Y698904D02*
X613366Y698911D01*
G01X613367Y698900D02*
Y698904D01*
G01X613369Y698898D02*
X613367Y698900D01*
G01Y703904D02*
X613366Y703911D01*
G01X613367Y703900D02*
Y703904D01*
G01X613369Y703898D02*
X613367Y703900D01*
G01Y708904D02*
X613366Y708911D01*
G01X613367Y708900D02*
Y708904D01*
G01X613369Y708898D02*
X613367Y708900D01*
G01Y713904D02*
X613366Y713911D01*
G01X613367Y713900D02*
Y713904D01*
G01X613369Y713898D02*
X613367Y713900D01*
G01Y718904D02*
X613366Y718911D01*
G01X613367Y718900D02*
Y718904D01*
G01X613369Y718898D02*
X613367Y718900D01*
G01Y723904D02*
X613366Y723911D01*
G01X613367Y723900D02*
Y723904D01*
G01X613369Y723898D02*
X613367Y723900D01*
G01Y728904D02*
X613366Y728911D01*
G01X613367Y728900D02*
Y728904D01*
G01X613369Y728898D02*
X613367Y728900D01*
G01Y733904D02*
X613366Y733911D01*
G01X613367Y733900D02*
Y733904D01*
G01X613369Y733898D02*
X613367Y733900D01*
G01Y738904D02*
X613366Y738911D01*
G01X613367Y738900D02*
Y738904D01*
G01X613369Y738898D02*
X613367Y738900D01*
G01Y743904D02*
X613366Y743911D01*
G01X613367Y743900D02*
Y743904D01*
G01X613369Y743898D02*
X613367Y743900D01*
G01X612382Y728944D02*
Y728954D01*
G01X612383Y728939D02*
X612382Y728944D01*
G01X612383Y728937D02*
Y728939D01*
G01X612382Y733944D02*
Y733954D01*
G01X612383Y733939D02*
X612382Y733944D01*
G01X612383Y733937D02*
Y733939D01*
G01X612382Y738944D02*
Y738954D01*
G01X612383Y738939D02*
X612382Y738944D01*
G01X612383Y738937D02*
Y738939D01*
G01X612382Y743944D02*
Y743954D01*
G01X612383Y743939D02*
X612382Y743944D01*
G01X612383Y743937D02*
Y743939D01*
G01X613358Y729081D02*
X613366Y729055D01*
G01X613348Y729107D02*
X613358Y729081D01*
G01X613337Y729134D02*
X613348Y729107D01*
G01X613358Y734081D02*
X613366Y734055D01*
G01X613348Y734107D02*
X613358Y734081D01*
G01X613337Y734134D02*
X613348Y734107D01*
G01X613358Y739081D02*
X613366Y739055D01*
G01X613348Y739107D02*
X613358Y739081D01*
G01X613337Y739134D02*
X613348Y739107D01*
G01X613358Y744081D02*
X613366Y744055D01*
G01X613348Y744107D02*
X613358Y744081D01*
G01X613337Y744134D02*
X613348Y744107D01*
G01X613367Y742552D02*
X613366Y742543D01*
G01X613367Y742557D02*
Y742552D01*
G01X613369Y742559D02*
X613367Y742557D01*
G01Y737552D02*
X613366Y737543D01*
G01X613367Y737557D02*
Y737552D01*
G01X613369Y737559D02*
X613367Y737557D01*
G01Y732552D02*
X613366Y732543D01*
G01X613367Y732557D02*
Y732552D01*
G01X613369Y732559D02*
X613367Y732557D01*
G01Y727552D02*
X613366Y727543D01*
G01X613367Y727557D02*
Y727552D01*
G01X613369Y727559D02*
X613367Y727557D01*
G01Y722552D02*
X613366Y722543D01*
G01X613367Y722557D02*
Y722552D01*
G01X613369Y722559D02*
X613367Y722557D01*
G01Y717552D02*
X613366Y717543D01*
G01X613367Y717557D02*
Y717552D01*
G01X613369Y717559D02*
X613367Y717557D01*
G01Y712552D02*
X613366Y712543D01*
G01X613367Y712557D02*
Y712552D01*
G01X613369Y712559D02*
X613367Y712557D01*
G01Y707552D02*
X613366Y707543D01*
G01X613367Y707557D02*
Y707552D01*
G01X613369Y707559D02*
X613367Y707557D01*
G01Y702552D02*
X613366Y702543D01*
G01X613367Y702557D02*
Y702552D01*
G01X613369Y702559D02*
X613367Y702557D01*
G01Y697552D02*
X613366Y697543D01*
G01X613367Y697557D02*
Y697552D01*
G01X613369Y697559D02*
X613367Y697557D01*
G01X613354Y698929D02*
X613365Y698913D01*
G01X613329Y698937D02*
X613354Y698929D01*
G01Y703929D02*
X613365Y703913D01*
G01X613329Y703937D02*
X613354Y703929D01*
G01Y708929D02*
X613365Y708913D01*
G01X613329Y708937D02*
X613354Y708929D01*
G01Y713929D02*
X613365Y713913D01*
G01X613329Y713937D02*
X613354Y713929D01*
G01Y718929D02*
X613365Y718913D01*
G01X613329Y718937D02*
X613354Y718929D01*
G01Y723929D02*
X613365Y723913D01*
G01X613329Y723937D02*
X613354Y723929D01*
G01Y728929D02*
X613365Y728913D01*
G01X613329Y728937D02*
X613354Y728929D01*
G01Y733929D02*
X613365Y733913D01*
G01X613329Y733937D02*
X613354Y733929D01*
G01Y738929D02*
X613365Y738913D01*
G01X613329Y738937D02*
X613354Y738929D01*
G01Y743929D02*
X613365Y743913D01*
G01X613329Y743937D02*
X613354Y743929D01*
G01X613366Y744429D02*
X612382D01*
G01X612383Y743937D02*
X617717D01*
G01Y743898D02*
X613369D01*
G01X617717Y742559D02*
X612383D01*
G01X612382Y742067D02*
X613366D01*
G01Y739429D02*
X612382D01*
G01X612383Y738937D02*
X617717D01*
G01Y738898D02*
X613369D01*
G01X617717Y737559D02*
X612383D01*
G01X612382Y737067D02*
X613366D01*
G01Y734429D02*
X612382D01*
G01X612383Y733937D02*
X617717D01*
G01Y733898D02*
X613369D01*
G01X617717Y732559D02*
X612383D01*
G01X612382Y732067D02*
X613366D01*
G01Y729429D02*
X612382D01*
G01X612383Y728937D02*
X617717D01*
G01Y728898D02*
X613369D01*
G01X617717Y727559D02*
X612383D01*
G01X612382Y727067D02*
X613366D01*
G01Y724429D02*
X612382D01*
G01X612383Y723937D02*
X617717D01*
G01Y723898D02*
X613369D01*
G01X617717Y722559D02*
X612383D01*
G01X612382Y722067D02*
X613366D01*
G01Y719429D02*
X612382D01*
G01X612383Y718937D02*
X617717D01*
G01Y718898D02*
X613369D01*
G01X617717Y717559D02*
X612383D01*
G01X612382Y717067D02*
X613366D01*
G01Y714429D02*
X612382D01*
G01X612383Y713937D02*
X617717D01*
G01Y713898D02*
X613369D01*
G01X617717Y712559D02*
X612383D01*
G01X612382Y712067D02*
X613366D01*
G01Y709429D02*
X612382D01*
G01X612383Y708937D02*
X617717D01*
G01Y708898D02*
X613369D01*
G01X617717Y707559D02*
X612383D01*
G01X612382Y707067D02*
X613366D01*
G01X612382Y744133D02*
X613337Y744134D01*
G01X613366Y742363D02*
X612382Y742362D01*
G01Y739133D02*
X613337Y739134D01*
G01X613366Y737363D02*
X612382Y737362D01*
G01Y734133D02*
X613337Y734134D01*
G01X613366Y732363D02*
X612382Y732362D01*
G01Y729133D02*
X613337Y729134D01*
G01X613366Y727363D02*
X612382Y727362D01*
G01Y724133D02*
X613337Y724134D01*
G01X613366Y722363D02*
X612382Y722362D01*
G01Y719133D02*
X613337Y719134D01*
G01X613366Y717363D02*
X612382Y717362D01*
G01Y714133D02*
X613337Y714134D01*
G01X613366Y712363D02*
X612382Y712362D01*
G01Y709133D02*
X613337Y709134D01*
G01X613366Y707363D02*
X612382Y707362D01*
G01X613366Y704429D02*
X612382D01*
G01X612383Y703937D02*
X617717D01*
G01Y703898D02*
X613369D01*
G01X617717Y702559D02*
X612383D01*
G01X612382Y702067D02*
X613366D01*
G01Y699429D02*
X612382D01*
G01X612383Y698937D02*
X617717D01*
G01Y698898D02*
X613369D01*
G01X617717Y697559D02*
X612383D01*
G01X612382Y697067D02*
X613366D01*
G01X612382Y704133D02*
X613337Y704134D01*
G01X613366Y702363D02*
X612382Y702362D01*
G01Y699133D02*
X613337Y699134D01*
G01X613366Y697363D02*
X612382Y697362D01*
G01X613366Y698911D02*
X613367Y698920D01*
G01X613366Y703911D02*
X613367Y703920D01*
G01X613366Y708911D02*
X613367Y708920D01*
G01X613366Y713911D02*
X613367Y713920D01*
G01X613366Y718911D02*
X613367Y718920D01*
G01X613366Y723911D02*
X613367Y723920D01*
G01X613366Y728911D02*
X613367Y728920D01*
G01X613366Y733911D02*
X613367Y733920D01*
G01X613366Y738911D02*
X613367Y738920D01*
G01X613366Y743911D02*
X613367Y743920D01*
G01X617717Y742559D02*
Y743937D01*
G01Y737559D02*
Y738937D01*
G01Y732559D02*
Y733937D01*
G01Y727559D02*
Y728937D01*
G01Y722559D02*
Y723937D01*
G01Y717559D02*
Y718937D01*
G01Y712559D02*
Y713937D01*
G01Y707559D02*
Y708937D01*
G01Y702559D02*
Y703937D01*
G01Y697559D02*
Y698937D01*
G01X614547D02*
Y697559D01*
G01Y703937D02*
Y702559D01*
G01Y708937D02*
Y707559D01*
G01Y713937D02*
Y712559D01*
G01Y718937D02*
Y717559D01*
G01Y723937D02*
Y722559D01*
G01Y728937D02*
Y727559D01*
G01Y733937D02*
Y732559D01*
G01Y738937D02*
Y737559D01*
G01Y743937D02*
Y742559D01*
G01X613366Y742067D02*
Y744429D01*
G01Y737067D02*
Y739429D01*
G01Y732067D02*
Y734429D01*
G01Y727067D02*
Y729429D01*
G01Y722067D02*
Y724429D01*
G01Y717067D02*
Y719429D01*
G01Y712067D02*
Y714429D01*
G01Y707067D02*
Y709429D01*
G01Y702067D02*
Y704429D01*
G01Y697067D02*
Y699429D01*
G01X612382D02*
Y697067D01*
G01Y704429D02*
Y702067D01*
G01Y709429D02*
Y707067D01*
G01Y714429D02*
Y712067D01*
G01Y719429D02*
Y717067D01*
G01Y724429D02*
Y722067D01*
G01Y729429D02*
Y727067D01*
G01Y734429D02*
Y732067D01*
G01Y739429D02*
Y737067D01*
G01Y744429D02*
Y742067D01*
G01X611811Y769429D02*
G03X611220Y770020I-591J0D01*
G01X606693Y768248D02*
G03Y766280I0J-984D01*
G01X609055D02*
G03Y768248I0J984D01*
G01X618701Y768839D02*
G03X616732Y770807I-1968J0D01*
G01X611614Y759154D02*
G03X610433Y760335I-1181J0D01*
G01X609764Y755059D02*
G03I-1890J0D01*
G01X610236D02*
G03I-2362J0D01*
G01X611220Y770020D02*
X604528D01*
G01X609055Y768248D02*
X606693D01*
G01Y766280D02*
X609055D01*
G01X605315Y760335D02*
X610433D01*
G01X606693Y755650D02*
X609055D01*
G01X606693Y753957D02*
X609055D01*
G01X614764Y750610D02*
X611614D01*
G01X618701Y753091D02*
X615354Y749744D01*
G01X608858Y747067D02*
X610039Y748248D01*
G01X609055Y753957D02*
X610359Y751988D01*
G01X605389D02*
X606693Y753957D01*
G01X611365Y759879D02*
X609055Y755650D01*
G01X618701Y753091D02*
Y768839D01*
G01X611811Y763327D02*
Y769429D01*
G01X611614Y759154D02*
Y750610D01*
G01X609055Y755650D02*
Y753957D01*
G01X606693D02*
Y755650D01*
G01X610358Y831641D02*
G03X644169I16906J-13531D01*
G01X637244Y844772D02*
G03X644169Y831641I37662J11471D01*
G01X610358D02*
G03X617283Y844772I-30737J24602D01*
G01X610358Y831641D02*
G03X644169I16906J-13531D01*
G01X637244Y844772D02*
G03X644169Y831641I37662J11471D01*
G01X610358D02*
G03X617283Y844772I-30737J24601D01*
G01X637244D02*
G03X617283I-9980J-3039D01*
G01X637244D02*
G03X617283I-9980J-3040D01*
G01X613367Y1080308D02*
X613366Y1080299D01*
G01X613367Y1080313D02*
Y1080308D01*
G01X613369Y1080315D02*
X613367Y1080313D01*
G01Y1075308D02*
X613366Y1075299D01*
G01X613367Y1075313D02*
Y1075308D01*
G01X613369Y1075315D02*
X613367Y1075313D01*
G01Y1070308D02*
X613366Y1070299D01*
G01X613367Y1070313D02*
Y1070308D01*
G01X613369Y1070315D02*
X613367Y1070313D01*
G01X612383Y1080313D02*
Y1080315D01*
G01X612382Y1080308D02*
X612383Y1080313D01*
G01X612382Y1080299D02*
Y1080308D01*
G01X612383Y1075313D02*
Y1075315D01*
G01X612382Y1075308D02*
X612383Y1075313D01*
G01X612382Y1075299D02*
Y1075308D01*
G01X612383Y1070313D02*
Y1070315D01*
G01X612382Y1070308D02*
X612383Y1070313D01*
G01X612382Y1070299D02*
Y1070308D01*
G01X613333Y1071791D02*
X613337Y1071890D01*
G01X613328Y1071719D02*
X613333Y1071791D01*
G01X613330Y1071693D02*
X613328Y1071719D01*
G01X613333Y1076791D02*
X613337Y1076890D01*
G01X613328Y1076719D02*
X613333Y1076791D01*
G01X613330Y1076693D02*
X613328Y1076719D01*
G01X613333Y1081791D02*
X613337Y1081890D01*
G01X613328Y1081719D02*
X613333Y1081791D01*
G01X613330Y1081693D02*
X613328Y1081719D01*
G01X613349Y1071688D02*
X613330Y1071693D01*
G01X613363Y1071674D02*
X613349Y1071688D01*
G01X613369Y1071654D02*
X613363Y1071674D01*
G01X613349Y1076688D02*
X613330Y1076693D01*
G01X613363Y1076674D02*
X613349Y1076688D01*
G01X613369Y1076654D02*
X613363Y1076674D01*
G01X613349Y1081688D02*
X613330Y1081693D01*
G01X613363Y1081674D02*
X613349Y1081688D01*
G01X613369Y1081654D02*
X613363Y1081674D01*
G01X612382Y1071700D02*
Y1071709D01*
G01X612383Y1071695D02*
X612382Y1071700D01*
G01X612383Y1071693D02*
Y1071695D01*
G01X612382Y1076700D02*
Y1076709D01*
G01X612383Y1076695D02*
X612382Y1076700D01*
G01X612383Y1076693D02*
Y1076695D01*
G01X612382Y1081700D02*
Y1081709D01*
G01X612383Y1081695D02*
X612382Y1081700D01*
G01X612383Y1081693D02*
Y1081695D01*
G01X613358Y1071837D02*
X613366Y1071811D01*
G01X613348Y1071863D02*
X613358Y1071837D01*
G01X613337Y1071890D02*
X613348Y1071863D01*
G01X613358Y1076837D02*
X613366Y1076811D01*
G01X613348Y1076863D02*
X613358Y1076837D01*
G01X613337Y1076890D02*
X613348Y1076863D01*
G01X613358Y1081837D02*
X613366Y1081811D01*
G01X613348Y1081863D02*
X613358Y1081837D01*
G01X613337Y1081890D02*
X613348Y1081863D01*
G01X613367Y1071660D02*
X613366Y1071667D01*
G01X613367Y1071656D02*
Y1071660D01*
G01X613369Y1071654D02*
X613367Y1071656D01*
G01Y1076660D02*
X613366Y1076667D01*
G01X613367Y1076656D02*
Y1076660D01*
G01X613369Y1076654D02*
X613367Y1076656D01*
G01Y1081660D02*
X613366Y1081667D01*
G01X613367Y1081656D02*
Y1081660D01*
G01X613369Y1081654D02*
X613367Y1081656D01*
G01X613354Y1071685D02*
X613365Y1071669D01*
G01X613329Y1071693D02*
X613354Y1071685D01*
G01Y1076685D02*
X613365Y1076669D01*
G01X613329Y1076693D02*
X613354Y1076685D01*
G01Y1081685D02*
X613365Y1081669D01*
G01X613329Y1081693D02*
X613354Y1081685D01*
G01X611220Y1044232D02*
G03X611811Y1044823I0J591D01*
G01X609055Y1046004D02*
G03Y1047972I0J984D01*
G01X606693D02*
G03Y1046004I0J-984D01*
G01X608976Y1059193D02*
G03I-1102J0D01*
G01X610433Y1053917D02*
G03X611614Y1055098I0J1181D01*
G01X609449Y1059193D02*
G03I-1575J0D01*
G01X616732Y1043445D02*
G03X618701Y1045413I0J1969D01*
G01X613366Y1082185D02*
X612382D01*
G01X612383Y1081693D02*
X617717D01*
G01Y1081654D02*
X613369D01*
G01X617717Y1080315D02*
X612383D01*
G01X612382Y1079823D02*
X613366D01*
G01Y1077185D02*
X612382D01*
G01X612383Y1076693D02*
X617717D01*
G01Y1076654D02*
X613369D01*
G01X617717Y1075315D02*
X612383D01*
G01X612382Y1074823D02*
X613366D01*
G01Y1072185D02*
X612382D01*
G01X612383Y1071693D02*
X617717D01*
G01Y1071654D02*
X613369D01*
G01X617717Y1070315D02*
X612383D01*
G01X612382Y1069823D02*
X613366D01*
G01X612382Y1081889D02*
X613337Y1081890D01*
G01X613366Y1080119D02*
X612382Y1080118D01*
G01Y1076889D02*
X613337Y1076890D01*
G01X613366Y1075119D02*
X612382Y1075118D01*
G01Y1071889D02*
X613337Y1071890D01*
G01X613366Y1070119D02*
X612382Y1070118D01*
G01X611614Y1063642D02*
X614764D01*
G01X609055Y1060295D02*
X606693D01*
G01X609055Y1058602D02*
X606693D01*
G01X610433Y1053917D02*
X605315D01*
G01X609055Y1047972D02*
X606693D01*
G01Y1046004D02*
X609055D01*
G01X611220Y1044232D02*
X604528D01*
G01X615354Y1064508D02*
X618701Y1061161D01*
G01X608858Y1067185D02*
X610039Y1066004D01*
G01X606693Y1060295D02*
X605389Y1062264D01*
G01X609055Y1058602D02*
X611365Y1054373D01*
G01X613366Y1071667D02*
X613367Y1071676D01*
G01X613366Y1076667D02*
X613367Y1076676D01*
G01X613366Y1081667D02*
X613367Y1081676D01*
G01X618701Y1045413D02*
Y1061161D01*
G01X617717Y1080315D02*
Y1081693D01*
G01Y1075315D02*
Y1076693D01*
G01Y1070315D02*
Y1071693D01*
G01X615354Y1202500D02*
Y1064508D01*
G01X614764Y1204744D02*
Y1062264D01*
G01X614547Y1071693D02*
Y1070315D01*
G01Y1076693D02*
Y1075315D01*
G01Y1081693D02*
Y1080315D01*
G01X613366Y1079823D02*
Y1082185D01*
G01Y1074823D02*
Y1077185D01*
G01Y1069823D02*
Y1072185D01*
G01Y1071667D02*
Y1071811D01*
G01Y1076667D02*
Y1076811D01*
G01Y1081667D02*
Y1081811D01*
G01X612382Y1072185D02*
Y1069823D01*
G01Y1077185D02*
Y1074823D01*
G01Y1082185D02*
Y1079823D01*
G01X611811Y1050925D02*
Y1044823D01*
G01X611614Y1063642D02*
Y1055098D01*
G01X610039Y1102461D02*
Y1066004D01*
G01X609055Y1060295D02*
Y1058602D01*
G01X608858Y1103642D02*
Y1067185D01*
G01X606693Y1058602D02*
Y1060295D01*
G01X610359Y1062264D02*
X609055Y1060295D01*
G01X613367Y1130308D02*
X613366Y1130299D01*
G01X613367Y1130313D02*
Y1130308D01*
G01X613369Y1130315D02*
X613367Y1130313D01*
G01Y1125308D02*
X613366Y1125299D01*
G01X613367Y1125313D02*
Y1125308D01*
G01X613369Y1125315D02*
X613367Y1125313D01*
G01Y1100308D02*
X613366Y1100299D01*
G01X613367Y1100313D02*
Y1100308D01*
G01X613369Y1100315D02*
X613367Y1100313D01*
G01Y1095308D02*
X613366Y1095299D01*
G01X613367Y1095313D02*
Y1095308D01*
G01X613369Y1095315D02*
X613367Y1095313D01*
G01Y1090308D02*
X613366Y1090299D01*
G01X613367Y1090313D02*
Y1090308D01*
G01X613369Y1090315D02*
X613367Y1090313D01*
G01Y1085308D02*
X613366Y1085299D01*
G01X613367Y1085313D02*
Y1085308D01*
G01X613369Y1085315D02*
X613367Y1085313D01*
G01X612383Y1130313D02*
Y1130315D01*
G01X612382Y1130308D02*
X612383Y1130313D01*
G01X612382Y1130299D02*
Y1130308D01*
G01X612383Y1125313D02*
Y1125315D01*
G01X612382Y1125308D02*
X612383Y1125313D01*
G01X612382Y1125299D02*
Y1125308D01*
G01X612383Y1100313D02*
Y1100315D01*
G01X612382Y1100308D02*
X612383Y1100313D01*
G01X612382Y1100299D02*
Y1100308D01*
G01X612383Y1095313D02*
Y1095315D01*
G01X612382Y1095308D02*
X612383Y1095313D01*
G01X612382Y1095299D02*
Y1095308D01*
G01X612383Y1090313D02*
Y1090315D01*
G01X612382Y1090308D02*
X612383Y1090313D01*
G01X612382Y1090299D02*
Y1090308D01*
G01X612383Y1085313D02*
Y1085315D01*
G01X612382Y1085308D02*
X612383Y1085313D01*
G01X612382Y1085299D02*
Y1085308D01*
G01X613333Y1086791D02*
X613337Y1086890D01*
G01X613328Y1086719D02*
X613333Y1086791D01*
G01X613330Y1086693D02*
X613328Y1086719D01*
G01X613333Y1091791D02*
X613337Y1091890D01*
G01X613328Y1091719D02*
X613333Y1091791D01*
G01X613330Y1091693D02*
X613328Y1091719D01*
G01X613333Y1096791D02*
X613337Y1096890D01*
G01X613328Y1096719D02*
X613333Y1096791D01*
G01X613330Y1096693D02*
X613328Y1096719D01*
G01X613333Y1101791D02*
X613337Y1101890D01*
G01X613328Y1101719D02*
X613333Y1101791D01*
G01X613330Y1101693D02*
X613328Y1101719D01*
G01X613333Y1126791D02*
X613337Y1126890D01*
G01X613328Y1126719D02*
X613333Y1126791D01*
G01X613330Y1126693D02*
X613328Y1126719D01*
G01X613349Y1086688D02*
X613330Y1086693D01*
G01X613363Y1086674D02*
X613349Y1086688D01*
G01X613369Y1086654D02*
X613363Y1086674D01*
G01X613349Y1091688D02*
X613330Y1091693D01*
G01X613363Y1091674D02*
X613349Y1091688D01*
G01X613369Y1091654D02*
X613363Y1091674D01*
G01X613349Y1096688D02*
X613330Y1096693D01*
G01X613363Y1096674D02*
X613349Y1096688D01*
G01X613369Y1096654D02*
X613363Y1096674D01*
G01X613349Y1101688D02*
X613330Y1101693D01*
G01X613363Y1101674D02*
X613349Y1101688D01*
G01X613369Y1101654D02*
X613363Y1101674D01*
G01X612382Y1086700D02*
Y1086709D01*
G01X612383Y1086695D02*
X612382Y1086700D01*
G01X612383Y1086693D02*
Y1086695D01*
G01X612382Y1091700D02*
Y1091709D01*
G01X612383Y1091695D02*
X612382Y1091700D01*
G01X612383Y1091693D02*
Y1091695D01*
G01X612382Y1096700D02*
Y1096709D01*
G01X612383Y1096695D02*
X612382Y1096700D01*
G01X612383Y1096693D02*
Y1096695D01*
G01X612382Y1101700D02*
Y1101709D01*
G01X612383Y1101695D02*
X612382Y1101700D01*
G01X612383Y1101693D02*
Y1101695D01*
G01X612382Y1126700D02*
Y1126709D01*
G01X612383Y1126695D02*
X612382Y1126700D01*
G01X612383Y1126693D02*
Y1126695D01*
G01X613358Y1086837D02*
X613366Y1086811D01*
G01X613348Y1086863D02*
X613358Y1086837D01*
G01X613337Y1086890D02*
X613348Y1086863D01*
G01X613358Y1091837D02*
X613366Y1091811D01*
G01X613348Y1091863D02*
X613358Y1091837D01*
G01X613337Y1091890D02*
X613348Y1091863D01*
G01X613358Y1096837D02*
X613366Y1096811D01*
G01X613348Y1096863D02*
X613358Y1096837D01*
G01X613337Y1096890D02*
X613348Y1096863D01*
G01X613358Y1101837D02*
X613366Y1101811D01*
G01X613348Y1101863D02*
X613358Y1101837D01*
G01X613337Y1101890D02*
X613348Y1101863D01*
G01X613358Y1126837D02*
X613366Y1126811D01*
G01X613348Y1126863D02*
X613358Y1126837D01*
G01X613337Y1126890D02*
X613348Y1126863D01*
G01X613349Y1126688D02*
X613330Y1126693D01*
G01X613363Y1126674D02*
X613349Y1126688D01*
G01X613369Y1126654D02*
X613363Y1126674D01*
G01X613367Y1086660D02*
X613366Y1086667D01*
G01X613367Y1086656D02*
Y1086660D01*
G01X613369Y1086654D02*
X613367Y1086656D01*
G01Y1091660D02*
X613366Y1091667D01*
G01X613367Y1091656D02*
Y1091660D01*
G01X613369Y1091654D02*
X613367Y1091656D01*
G01Y1096660D02*
X613366Y1096667D01*
G01X613367Y1096656D02*
Y1096660D01*
G01X613369Y1096654D02*
X613367Y1096656D01*
G01Y1101660D02*
X613366Y1101667D01*
G01X613367Y1101656D02*
Y1101660D01*
G01X613369Y1101654D02*
X613367Y1101656D01*
G01Y1126660D02*
X613366Y1126667D01*
G01X613367Y1126656D02*
Y1126660D01*
G01X613369Y1126654D02*
X613367Y1126656D01*
G01X613354Y1086685D02*
X613365Y1086669D01*
G01X613329Y1086693D02*
X613354Y1086685D01*
G01Y1091685D02*
X613365Y1091669D01*
G01X613329Y1091693D02*
X613354Y1091685D01*
G01Y1096685D02*
X613365Y1096669D01*
G01X613329Y1096693D02*
X613354Y1096685D01*
G01Y1101685D02*
X613365Y1101669D01*
G01X613329Y1101693D02*
X613354Y1101685D01*
G01Y1126685D02*
X613365Y1126669D01*
G01X613329Y1126693D02*
X613354Y1126685D01*
G01X617717Y1130315D02*
X612383D01*
G01X612382Y1129823D02*
X613366D01*
G01Y1127185D02*
X612382D01*
G01X612383Y1126693D02*
X617717D01*
G01Y1126654D02*
X613369D01*
G01X617717Y1125315D02*
X612383D01*
G01X612382Y1124823D02*
X613366D01*
G01X610039Y1124547D02*
X613976D01*
G01X608858Y1123366D02*
X612795D01*
G01Y1103642D02*
X608858D01*
G01X613976Y1102461D02*
X610039D01*
G01X613366Y1102185D02*
X612382D01*
G01X612383Y1101693D02*
X617717D01*
G01Y1101654D02*
X613369D01*
G01X617717Y1100315D02*
X612383D01*
G01X612382Y1099823D02*
X613366D01*
G01Y1097185D02*
X612382D01*
G01X612383Y1096693D02*
X617717D01*
G01Y1096654D02*
X613369D01*
G01X617717Y1095315D02*
X612383D01*
G01X612382Y1094823D02*
X613366D01*
G01Y1092185D02*
X612382D01*
G01X612383Y1091693D02*
X617717D01*
G01Y1091654D02*
X613369D01*
G01X617717Y1090315D02*
X612383D01*
G01X612382Y1089823D02*
X613366D01*
G01Y1087185D02*
X612382D01*
G01X612383Y1086693D02*
X617717D01*
G01Y1086654D02*
X613369D01*
G01X617717Y1085315D02*
X612383D01*
G01X612382Y1084823D02*
X613366D01*
G01Y1130119D02*
X612382Y1130118D01*
G01Y1126889D02*
X613337Y1126890D01*
G01X613366Y1125119D02*
X612382Y1125118D01*
G01Y1101889D02*
X613337Y1101890D01*
G01X613366Y1100119D02*
X612382Y1100118D01*
G01Y1096889D02*
X613337Y1096890D01*
G01X613366Y1095119D02*
X612382Y1095118D01*
G01Y1091889D02*
X613337Y1091890D01*
G01X613366Y1090119D02*
X612382Y1090118D01*
G01Y1086889D02*
X613337Y1086890D01*
G01X613366Y1085119D02*
X612382Y1085118D01*
G01X612795Y1103642D02*
X613976Y1102461D01*
G01X608858Y1103642D02*
X610039Y1102461D01*
G01X613366Y1086667D02*
X613367Y1086676D01*
G01X613366Y1091667D02*
X613367Y1091676D01*
G01X613366Y1096667D02*
X613367Y1096676D01*
G01X613366Y1101667D02*
X613367Y1101676D01*
G01X613366Y1126667D02*
X613367Y1126676D01*
G01X617717Y1130315D02*
Y1131693D01*
G01Y1125315D02*
Y1126693D01*
G01Y1100315D02*
Y1101693D01*
G01Y1095315D02*
Y1096693D01*
G01Y1090315D02*
Y1091693D01*
G01Y1085315D02*
Y1086693D01*
G01X614547D02*
Y1085315D01*
G01Y1091693D02*
Y1090315D01*
G01Y1096693D02*
Y1095315D01*
G01Y1101693D02*
Y1100315D01*
G01Y1126693D02*
Y1125315D01*
G01Y1131693D02*
Y1130315D01*
G01X613976Y1124547D02*
Y1102461D01*
G01X613366Y1129823D02*
Y1132185D01*
G01Y1124823D02*
Y1127185D01*
G01Y1099823D02*
Y1102185D01*
G01Y1094823D02*
Y1097185D01*
G01Y1089823D02*
Y1092185D01*
G01Y1084823D02*
Y1087185D01*
G01Y1086667D02*
Y1086811D01*
G01Y1091667D02*
Y1091811D01*
G01Y1096667D02*
Y1096811D01*
G01Y1101667D02*
Y1101811D01*
G01Y1126667D02*
Y1126811D01*
G01X612795Y1123366D02*
Y1103642D01*
G01X612382Y1087185D02*
Y1084823D01*
G01Y1092185D02*
Y1089823D01*
G01Y1097185D02*
Y1094823D01*
G01Y1102185D02*
Y1099823D01*
G01Y1127185D02*
Y1124823D01*
G01Y1132185D02*
Y1129823D01*
G01X610039Y1201004D02*
Y1124547D01*
G01X608858Y1199823D02*
Y1123366D01*
G01X612795D02*
X613976Y1124547D01*
G01X608858Y1123366D02*
X610039Y1124547D01*
G01X613367Y1175308D02*
X613366Y1175299D01*
G01X613367Y1175313D02*
Y1175308D01*
G01X613369Y1175315D02*
X613367Y1175313D01*
G01Y1170308D02*
X613366Y1170299D01*
G01X613367Y1170313D02*
Y1170308D01*
G01X613369Y1170315D02*
X613367Y1170313D01*
G01Y1165308D02*
X613366Y1165299D01*
G01X613367Y1165313D02*
Y1165308D01*
G01X613369Y1165315D02*
X613367Y1165313D01*
G01Y1160308D02*
X613366Y1160299D01*
G01X613367Y1160313D02*
Y1160308D01*
G01X613369Y1160315D02*
X613367Y1160313D01*
G01Y1155308D02*
X613366Y1155299D01*
G01X613367Y1155313D02*
Y1155308D01*
G01X613369Y1155315D02*
X613367Y1155313D01*
G01Y1150308D02*
X613366Y1150299D01*
G01X613367Y1150313D02*
Y1150308D01*
G01X613369Y1150315D02*
X613367Y1150313D01*
G01Y1145308D02*
X613366Y1145299D01*
G01X613367Y1145313D02*
Y1145308D01*
G01X613369Y1145315D02*
X613367Y1145313D01*
G01Y1140308D02*
X613366Y1140299D01*
G01X613367Y1140313D02*
Y1140308D01*
G01X613369Y1140315D02*
X613367Y1140313D01*
G01Y1135308D02*
X613366Y1135299D01*
G01X613367Y1135313D02*
Y1135308D01*
G01X613369Y1135315D02*
X613367Y1135313D01*
G01X612383Y1175313D02*
Y1175315D01*
G01X612382Y1175308D02*
X612383Y1175313D01*
G01X612382Y1175299D02*
Y1175308D01*
G01X612383Y1170313D02*
Y1170315D01*
G01X612382Y1170308D02*
X612383Y1170313D01*
G01X612382Y1170299D02*
Y1170308D01*
G01X612383Y1165313D02*
Y1165315D01*
G01X612382Y1165308D02*
X612383Y1165313D01*
G01X612382Y1165299D02*
Y1165308D01*
G01X612383Y1160313D02*
Y1160315D01*
G01X612382Y1160308D02*
X612383Y1160313D01*
G01X612382Y1160299D02*
Y1160308D01*
G01X612383Y1155313D02*
Y1155315D01*
G01X612382Y1155308D02*
X612383Y1155313D01*
G01X612382Y1155299D02*
Y1155308D01*
G01X612383Y1150313D02*
Y1150315D01*
G01X612382Y1150308D02*
X612383Y1150313D01*
G01X612382Y1150299D02*
Y1150308D01*
G01X612383Y1145313D02*
Y1145315D01*
G01X612382Y1145308D02*
X612383Y1145313D01*
G01X612382Y1145299D02*
Y1145308D01*
G01X612383Y1140313D02*
Y1140315D01*
G01X612382Y1140308D02*
X612383Y1140313D01*
G01X612382Y1140299D02*
Y1140308D01*
G01X612383Y1135313D02*
Y1135315D01*
G01X612382Y1135308D02*
X612383Y1135313D01*
G01X612382Y1135299D02*
Y1135308D01*
G01X613333Y1131791D02*
X613337Y1131890D01*
G01X613328Y1131719D02*
X613333Y1131791D01*
G01X613330Y1131693D02*
X613328Y1131719D01*
G01X613333Y1136791D02*
X613337Y1136890D01*
G01X613328Y1136719D02*
X613333Y1136791D01*
G01X613330Y1136693D02*
X613328Y1136719D01*
G01X613333Y1141791D02*
X613337Y1141890D01*
G01X613328Y1141719D02*
X613333Y1141791D01*
G01X613330Y1141693D02*
X613328Y1141719D01*
G01X613333Y1146791D02*
X613337Y1146890D01*
G01X613328Y1146719D02*
X613333Y1146791D01*
G01X613330Y1146693D02*
X613328Y1146719D01*
G01X613333Y1151791D02*
X613337Y1151890D01*
G01X613328Y1151719D02*
X613333Y1151791D01*
G01X613330Y1151693D02*
X613328Y1151719D01*
G01X613333Y1156791D02*
X613337Y1156890D01*
G01X613328Y1156719D02*
X613333Y1156791D01*
G01X613330Y1156693D02*
X613328Y1156719D01*
G01X613333Y1161791D02*
X613337Y1161890D01*
G01X613328Y1161719D02*
X613333Y1161791D01*
G01X613330Y1161693D02*
X613328Y1161719D01*
G01X613333Y1166791D02*
X613337Y1166890D01*
G01X613328Y1166719D02*
X613333Y1166791D01*
G01X613330Y1166693D02*
X613328Y1166719D01*
G01X613333Y1171791D02*
X613337Y1171890D01*
G01X613328Y1171719D02*
X613333Y1171791D01*
G01X613330Y1171693D02*
X613328Y1171719D01*
G01X613333Y1176791D02*
X613337Y1176890D01*
G01X613328Y1176719D02*
X613333Y1176791D01*
G01X613330Y1176693D02*
X613328Y1176719D01*
G01X612382Y1131700D02*
Y1131709D01*
G01X612383Y1131695D02*
X612382Y1131700D01*
G01X612383Y1131693D02*
Y1131695D01*
G01X612382Y1136700D02*
Y1136709D01*
G01X612383Y1136695D02*
X612382Y1136700D01*
G01X612383Y1136693D02*
Y1136695D01*
G01X612382Y1141700D02*
Y1141709D01*
G01X612383Y1141695D02*
X612382Y1141700D01*
G01X612383Y1141693D02*
Y1141695D01*
G01X612382Y1146700D02*
Y1146709D01*
G01X612383Y1146695D02*
X612382Y1146700D01*
G01X612383Y1146693D02*
Y1146695D01*
G01X612382Y1151700D02*
Y1151709D01*
G01X612383Y1151695D02*
X612382Y1151700D01*
G01X612383Y1151693D02*
Y1151695D01*
G01X612382Y1156700D02*
Y1156709D01*
G01X612383Y1156695D02*
X612382Y1156700D01*
G01X612383Y1156693D02*
Y1156695D01*
G01X612382Y1161700D02*
Y1161709D01*
G01X612383Y1161695D02*
X612382Y1161700D01*
G01X612383Y1161693D02*
Y1161695D01*
G01X612382Y1166700D02*
Y1166709D01*
G01X612383Y1166695D02*
X612382Y1166700D01*
G01X612383Y1166693D02*
Y1166695D01*
G01X612382Y1171700D02*
Y1171709D01*
G01X612383Y1171695D02*
X612382Y1171700D01*
G01X612383Y1171693D02*
Y1171695D01*
G01X613358Y1131837D02*
X613366Y1131811D01*
G01X613348Y1131863D02*
X613358Y1131837D01*
G01X613337Y1131890D02*
X613348Y1131863D01*
G01X613358Y1136837D02*
X613366Y1136811D01*
G01X613348Y1136863D02*
X613358Y1136837D01*
G01X613337Y1136890D02*
X613348Y1136863D01*
G01X613358Y1141837D02*
X613366Y1141811D01*
G01X613348Y1141863D02*
X613358Y1141837D01*
G01X613337Y1141890D02*
X613348Y1141863D01*
G01X613358Y1146837D02*
X613366Y1146811D01*
G01X613348Y1146863D02*
X613358Y1146837D01*
G01X613337Y1146890D02*
X613348Y1146863D01*
G01X613358Y1151837D02*
X613366Y1151811D01*
G01X613348Y1151863D02*
X613358Y1151837D01*
G01X613337Y1151890D02*
X613348Y1151863D01*
G01X613358Y1156837D02*
X613366Y1156811D01*
G01X613348Y1156863D02*
X613358Y1156837D01*
G01X613337Y1156890D02*
X613348Y1156863D01*
G01X613358Y1161837D02*
X613366Y1161811D01*
G01X613348Y1161863D02*
X613358Y1161837D01*
G01X613337Y1161890D02*
X613348Y1161863D01*
G01X613358Y1166837D02*
X613366Y1166811D01*
G01X613348Y1166863D02*
X613358Y1166837D01*
G01X613337Y1166890D02*
X613348Y1166863D01*
G01X613358Y1171837D02*
X613366Y1171811D01*
G01X613348Y1171863D02*
X613358Y1171837D01*
G01X613337Y1171890D02*
X613348Y1171863D01*
G01X613358Y1176837D02*
X613366Y1176811D01*
G01X613348Y1176863D02*
X613358Y1176837D01*
G01X613337Y1176890D02*
X613348Y1176863D01*
G01X613349Y1131688D02*
X613330Y1131693D01*
G01X613363Y1131674D02*
X613349Y1131688D01*
G01X613369Y1131654D02*
X613363Y1131674D01*
G01X613349Y1136688D02*
X613330Y1136693D01*
G01X613363Y1136674D02*
X613349Y1136688D01*
G01X613369Y1136654D02*
X613363Y1136674D01*
G01X613349Y1141688D02*
X613330Y1141693D01*
G01X613363Y1141674D02*
X613349Y1141688D01*
G01X613369Y1141654D02*
X613363Y1141674D01*
G01X613349Y1146688D02*
X613330Y1146693D01*
G01X613363Y1146674D02*
X613349Y1146688D01*
G01X613369Y1146654D02*
X613363Y1146674D01*
G01X613349Y1151688D02*
X613330Y1151693D01*
G01X613363Y1151674D02*
X613349Y1151688D01*
G01X613369Y1151654D02*
X613363Y1151674D01*
G01X613349Y1156688D02*
X613330Y1156693D01*
G01X613363Y1156674D02*
X613349Y1156688D01*
G01X613369Y1156654D02*
X613363Y1156674D01*
G01X613349Y1161688D02*
X613330Y1161693D01*
G01X613363Y1161674D02*
X613349Y1161688D01*
G01X613369Y1161654D02*
X613363Y1161674D01*
G01X613349Y1166688D02*
X613330Y1166693D01*
G01X613363Y1166674D02*
X613349Y1166688D01*
G01X613369Y1166654D02*
X613363Y1166674D01*
G01X613349Y1171688D02*
X613330Y1171693D01*
G01X613363Y1171674D02*
X613349Y1171688D01*
G01X613369Y1171654D02*
X613363Y1171674D01*
G01X613349Y1176688D02*
X613330Y1176693D01*
G01X613363Y1176674D02*
X613349Y1176688D01*
G01X613369Y1176654D02*
X613363Y1176674D01*
G01X612382Y1176700D02*
Y1176709D01*
G01X612383Y1176695D02*
X612382Y1176700D01*
G01X612383Y1176693D02*
Y1176695D01*
G01X613367Y1131660D02*
X613366Y1131667D01*
G01X613367Y1131656D02*
Y1131660D01*
G01X613369Y1131654D02*
X613367Y1131656D01*
G01Y1136660D02*
X613366Y1136667D01*
G01X613367Y1136656D02*
Y1136660D01*
G01X613369Y1136654D02*
X613367Y1136656D01*
G01Y1141660D02*
X613366Y1141667D01*
G01X613367Y1141656D02*
Y1141660D01*
G01X613369Y1141654D02*
X613367Y1141656D01*
G01Y1146660D02*
X613366Y1146667D01*
G01X613367Y1146656D02*
Y1146660D01*
G01X613369Y1146654D02*
X613367Y1146656D01*
G01Y1151660D02*
X613366Y1151667D01*
G01X613367Y1151656D02*
Y1151660D01*
G01X613369Y1151654D02*
X613367Y1151656D01*
G01Y1156660D02*
X613366Y1156667D01*
G01X613367Y1156656D02*
Y1156660D01*
G01X613369Y1156654D02*
X613367Y1156656D01*
G01Y1161660D02*
X613366Y1161667D01*
G01X613367Y1161656D02*
Y1161660D01*
G01X613369Y1161654D02*
X613367Y1161656D01*
G01Y1166660D02*
X613366Y1166667D01*
G01X613367Y1166656D02*
Y1166660D01*
G01X613369Y1166654D02*
X613367Y1166656D01*
G01Y1171660D02*
X613366Y1171667D01*
G01X613367Y1171656D02*
Y1171660D01*
G01X613369Y1171654D02*
X613367Y1171656D01*
G01Y1176660D02*
X613366Y1176667D01*
G01X613367Y1176656D02*
Y1176660D01*
G01X613369Y1176654D02*
X613367Y1176656D01*
G01X613354Y1131685D02*
X613365Y1131669D01*
G01X613329Y1131693D02*
X613354Y1131685D01*
G01Y1136685D02*
X613365Y1136669D01*
G01X613329Y1136693D02*
X613354Y1136685D01*
G01Y1141685D02*
X613365Y1141669D01*
G01X613329Y1141693D02*
X613354Y1141685D01*
G01Y1146685D02*
X613365Y1146669D01*
G01X613329Y1146693D02*
X613354Y1146685D01*
G01Y1151685D02*
X613365Y1151669D01*
G01X613329Y1151693D02*
X613354Y1151685D01*
G01Y1156685D02*
X613365Y1156669D01*
G01X613329Y1156693D02*
X613354Y1156685D01*
G01Y1161685D02*
X613365Y1161669D01*
G01X613329Y1161693D02*
X613354Y1161685D01*
G01Y1166685D02*
X613365Y1166669D01*
G01X613329Y1166693D02*
X613354Y1166685D01*
G01Y1171685D02*
X613365Y1171669D01*
G01X613329Y1171693D02*
X613354Y1171685D01*
G01Y1176685D02*
X613365Y1176669D01*
G01X613329Y1176693D02*
X613354Y1176685D01*
G01X613366Y1177185D02*
X612382D01*
G01X612383Y1176693D02*
X617717D01*
G01Y1176654D02*
X613369D01*
G01X617717Y1175315D02*
X612383D01*
G01X612382Y1174823D02*
X613366D01*
G01Y1172185D02*
X612382D01*
G01X612383Y1171693D02*
X617717D01*
G01Y1171654D02*
X613369D01*
G01X617717Y1170315D02*
X612383D01*
G01X612382Y1169823D02*
X613366D01*
G01Y1167185D02*
X612382D01*
G01X612383Y1166693D02*
X617717D01*
G01Y1166654D02*
X613369D01*
G01X617717Y1165315D02*
X612383D01*
G01X612382Y1164823D02*
X613366D01*
G01Y1162185D02*
X612382D01*
G01X612383Y1161693D02*
X617717D01*
G01Y1161654D02*
X613369D01*
G01X617717Y1160315D02*
X612383D01*
G01X612382Y1159823D02*
X613366D01*
G01Y1157185D02*
X612382D01*
G01X612383Y1156693D02*
X617717D01*
G01Y1156654D02*
X613369D01*
G01X617717Y1155315D02*
X612383D01*
G01X612382Y1154823D02*
X613366D01*
G01X612382Y1176889D02*
X613337Y1176890D01*
G01X613366Y1175119D02*
X612382Y1175118D01*
G01Y1171889D02*
X613337Y1171890D01*
G01X613366Y1170119D02*
X612382Y1170118D01*
G01Y1166889D02*
X613337Y1166890D01*
G01X613366Y1165119D02*
X612382Y1165118D01*
G01Y1161889D02*
X613337Y1161890D01*
G01X613366Y1160119D02*
X612382Y1160118D01*
G01Y1156889D02*
X613337Y1156890D01*
G01X613366Y1155119D02*
X612382Y1155118D01*
G01X613366Y1152185D02*
X612382D01*
G01X612383Y1151693D02*
X617717D01*
G01Y1151654D02*
X613369D01*
G01X617717Y1150315D02*
X612383D01*
G01X612382Y1149823D02*
X613366D01*
G01Y1147185D02*
X612382D01*
G01X612383Y1146693D02*
X617717D01*
G01Y1146654D02*
X613369D01*
G01X617717Y1145315D02*
X612383D01*
G01X612382Y1144823D02*
X613366D01*
G01Y1142185D02*
X612382D01*
G01X612383Y1141693D02*
X617717D01*
G01Y1141654D02*
X613369D01*
G01X617717Y1140315D02*
X612383D01*
G01X612382Y1139823D02*
X613366D01*
G01Y1137185D02*
X612382D01*
G01X612383Y1136693D02*
X617717D01*
G01Y1136654D02*
X613369D01*
G01X617717Y1135315D02*
X612383D01*
G01X612382Y1134823D02*
X613366D01*
G01Y1132185D02*
X612382D01*
G01X612383Y1131693D02*
X617717D01*
G01Y1131654D02*
X613369D01*
G01X612382Y1151889D02*
X613337Y1151890D01*
G01X613366Y1150119D02*
X612382Y1150118D01*
G01Y1146889D02*
X613337Y1146890D01*
G01X613366Y1145119D02*
X612382Y1145118D01*
G01Y1141889D02*
X613337Y1141890D01*
G01X613366Y1140119D02*
X612382Y1140118D01*
G01Y1136889D02*
X613337Y1136890D01*
G01X613366Y1135119D02*
X612382Y1135118D01*
G01Y1131889D02*
X613337Y1131890D01*
G01X613366Y1131667D02*
X613367Y1131676D01*
G01X613366Y1136667D02*
X613367Y1136676D01*
G01X613366Y1141667D02*
X613367Y1141676D01*
G01X613366Y1146667D02*
X613367Y1146676D01*
G01X613366Y1151667D02*
X613367Y1151676D01*
G01X613366Y1156667D02*
X613367Y1156676D01*
G01X613366Y1161667D02*
X613367Y1161676D01*
G01X613366Y1166667D02*
X613367Y1166676D01*
G01X613366Y1171667D02*
X613367Y1171676D01*
G01X613366Y1176667D02*
X613367Y1176676D01*
G01X617717Y1175315D02*
Y1176693D01*
G01Y1170315D02*
Y1171693D01*
G01Y1165315D02*
Y1166693D01*
G01Y1160315D02*
Y1161693D01*
G01Y1155315D02*
Y1156693D01*
G01Y1150315D02*
Y1151693D01*
G01Y1145315D02*
Y1146693D01*
G01Y1140315D02*
Y1141693D01*
G01Y1135315D02*
Y1136693D01*
G01X614547D02*
Y1135315D01*
G01Y1141693D02*
Y1140315D01*
G01Y1146693D02*
Y1145315D01*
G01Y1151693D02*
Y1150315D01*
G01Y1156693D02*
Y1155315D01*
G01Y1161693D02*
Y1160315D01*
G01Y1166693D02*
Y1165315D01*
G01Y1171693D02*
Y1170315D01*
G01Y1176693D02*
Y1175315D01*
G01X613366Y1174823D02*
Y1177185D01*
G01Y1169823D02*
Y1172185D01*
G01Y1164823D02*
Y1167185D01*
G01Y1159823D02*
Y1162185D01*
G01Y1154823D02*
Y1157185D01*
G01Y1149823D02*
Y1152185D01*
G01Y1144823D02*
Y1147185D01*
G01Y1139823D02*
Y1142185D01*
G01Y1134823D02*
Y1137185D01*
G01Y1131667D02*
Y1131811D01*
G01Y1136667D02*
Y1136811D01*
G01Y1141667D02*
Y1141811D01*
G01Y1146667D02*
Y1146811D01*
G01Y1151667D02*
Y1151811D01*
G01Y1156667D02*
Y1156811D01*
G01Y1161667D02*
Y1161811D01*
G01Y1166667D02*
Y1166811D01*
G01Y1171667D02*
Y1171811D01*
G01Y1176667D02*
Y1176811D01*
G01X612382Y1137185D02*
Y1134823D01*
G01Y1142185D02*
Y1139823D01*
G01Y1147185D02*
Y1144823D01*
G01Y1152185D02*
Y1149823D01*
G01Y1157185D02*
Y1154823D01*
G01Y1162185D02*
Y1159823D01*
G01Y1167185D02*
Y1164823D01*
G01Y1172185D02*
Y1169823D01*
G01Y1177185D02*
Y1174823D01*
G01X613367Y1195308D02*
X613366Y1195299D01*
G01X613367Y1195313D02*
Y1195308D01*
G01X613369Y1195315D02*
X613367Y1195313D01*
G01Y1190308D02*
X613366Y1190299D01*
G01X613367Y1190313D02*
Y1190308D01*
G01X613369Y1190315D02*
X613367Y1190313D01*
G01Y1185308D02*
X613366Y1185299D01*
G01X613367Y1185313D02*
Y1185308D01*
G01X613369Y1185315D02*
X613367Y1185313D01*
G01Y1180308D02*
X613366Y1180299D01*
G01X613367Y1180313D02*
Y1180308D01*
G01X613369Y1180315D02*
X613367Y1180313D01*
G01X612383Y1195313D02*
Y1195315D01*
G01X612382Y1195308D02*
X612383Y1195313D01*
G01X612382Y1195299D02*
Y1195308D01*
G01X612383Y1190313D02*
Y1190315D01*
G01X612382Y1190308D02*
X612383Y1190313D01*
G01X612382Y1190299D02*
Y1190308D01*
G01X612383Y1185313D02*
Y1185315D01*
G01X612382Y1185308D02*
X612383Y1185313D01*
G01X612382Y1185299D02*
Y1185308D01*
G01X612383Y1180313D02*
Y1180315D01*
G01X612382Y1180308D02*
X612383Y1180313D01*
G01X612382Y1180299D02*
Y1180308D01*
G01X613333Y1181791D02*
X613337Y1181890D01*
G01X613328Y1181719D02*
X613333Y1181791D01*
G01X613330Y1181693D02*
X613328Y1181719D01*
G01X613333Y1186791D02*
X613337Y1186890D01*
G01X613328Y1186719D02*
X613333Y1186791D01*
G01X613330Y1186693D02*
X613328Y1186719D01*
G01X613333Y1191791D02*
X613337Y1191890D01*
G01X613328Y1191719D02*
X613333Y1191791D01*
G01X613330Y1191693D02*
X613328Y1191719D01*
G01X613333Y1196791D02*
X613337Y1196890D01*
G01X613328Y1196719D02*
X613333Y1196791D01*
G01X613330Y1196693D02*
X613328Y1196719D01*
G01X613349Y1181688D02*
X613330Y1181693D01*
G01X613363Y1181674D02*
X613349Y1181688D01*
G01X613369Y1181654D02*
X613363Y1181674D01*
G01X613349Y1186688D02*
X613330Y1186693D01*
G01X613363Y1186674D02*
X613349Y1186688D01*
G01X613369Y1186654D02*
X613363Y1186674D01*
G01X613349Y1191688D02*
X613330Y1191693D01*
G01X613363Y1191674D02*
X613349Y1191688D01*
G01X613369Y1191654D02*
X613363Y1191674D01*
G01X613349Y1196688D02*
X613330Y1196693D01*
G01X613363Y1196674D02*
X613349Y1196688D01*
G01X613369Y1196654D02*
X613363Y1196674D01*
G01X612382Y1181700D02*
Y1181709D01*
G01X612383Y1181695D02*
X612382Y1181700D01*
G01X612383Y1181693D02*
Y1181695D01*
G01X612382Y1186700D02*
Y1186709D01*
G01X612383Y1186695D02*
X612382Y1186700D01*
G01X612383Y1186693D02*
Y1186695D01*
G01X612382Y1191700D02*
Y1191709D01*
G01X612383Y1191695D02*
X612382Y1191700D01*
G01X612383Y1191693D02*
Y1191695D01*
G01X612382Y1196700D02*
Y1196709D01*
G01X612383Y1196695D02*
X612382Y1196700D01*
G01X612383Y1196693D02*
Y1196695D01*
G01X613358Y1181837D02*
X613366Y1181811D01*
G01X613348Y1181863D02*
X613358Y1181837D01*
G01X613337Y1181890D02*
X613348Y1181863D01*
G01X613358Y1186837D02*
X613366Y1186811D01*
G01X613348Y1186863D02*
X613358Y1186837D01*
G01X613337Y1186890D02*
X613348Y1186863D01*
G01X613358Y1191837D02*
X613366Y1191811D01*
G01X613348Y1191863D02*
X613358Y1191837D01*
G01X613337Y1191890D02*
X613348Y1191863D01*
G01X613358Y1196837D02*
X613366Y1196811D01*
G01X613348Y1196863D02*
X613358Y1196837D01*
G01X613337Y1196890D02*
X613348Y1196863D01*
G01X613367Y1181660D02*
X613366Y1181667D01*
G01X613367Y1181656D02*
Y1181660D01*
G01X613369Y1181654D02*
X613367Y1181656D01*
G01Y1186660D02*
X613366Y1186667D01*
G01X613367Y1186656D02*
Y1186660D01*
G01X613369Y1186654D02*
X613367Y1186656D01*
G01Y1191660D02*
X613366Y1191667D01*
G01X613367Y1191656D02*
Y1191660D01*
G01X613369Y1191654D02*
X613367Y1191656D01*
G01Y1196660D02*
X613366Y1196667D01*
G01X613367Y1196656D02*
Y1196660D01*
G01X613369Y1196654D02*
X613367Y1196656D01*
G01X613354Y1181685D02*
X613365Y1181669D01*
G01X613329Y1181693D02*
X613354Y1181685D01*
G01Y1186685D02*
X613365Y1186669D01*
G01X613329Y1186693D02*
X613354Y1186685D01*
G01Y1191685D02*
X613365Y1191669D01*
G01X613329Y1191693D02*
X613354Y1191685D01*
G01Y1196685D02*
X613365Y1196669D01*
G01X613329Y1196693D02*
X613354Y1196685D01*
G01X611811Y1222185D02*
G03X611220Y1222776I-591J0D01*
G01X606693Y1221004D02*
G03Y1219035I0J-985D01*
G01X609055D02*
G03Y1221004I0J985D01*
G01X618701Y1221594D02*
G03X616732Y1223563I-1969J0D01*
G01X611614Y1211909D02*
G03X610433Y1213091I-1181J1D01*
G01X609764Y1207815D02*
G03I-1890J0D01*
G01X610236D02*
G03I-2362J0D01*
G01X611220Y1222776D02*
X604528D01*
G01X609055Y1221004D02*
X606693D01*
G01Y1219035D02*
X609055D01*
G01X605315Y1213091D02*
X610433D01*
G01X606693Y1208406D02*
X609055D01*
G01X606693Y1206713D02*
X609055D01*
G01X614764Y1203366D02*
X611614D01*
G01X613366Y1197185D02*
X612382D01*
G01X612383Y1196693D02*
X617717D01*
G01Y1196654D02*
X613369D01*
G01X617717Y1195315D02*
X612383D01*
G01X612382Y1194823D02*
X613366D01*
G01Y1192185D02*
X612382D01*
G01X612383Y1191693D02*
X617717D01*
G01Y1191654D02*
X613369D01*
G01X617717Y1190315D02*
X612383D01*
G01X612382Y1189823D02*
X613366D01*
G01Y1187185D02*
X612382D01*
G01X612383Y1186693D02*
X617717D01*
G01Y1186654D02*
X613369D01*
G01X617717Y1185315D02*
X612383D01*
G01X612382Y1184823D02*
X613366D01*
G01Y1182185D02*
X612382D01*
G01X612383Y1181693D02*
X617717D01*
G01Y1181654D02*
X613369D01*
G01X617717Y1180315D02*
X612383D01*
G01X612382Y1179823D02*
X613366D01*
G01X612382Y1196889D02*
X613337Y1196890D01*
G01X613366Y1195119D02*
X612382Y1195118D01*
G01Y1191889D02*
X613337Y1191890D01*
G01X613366Y1190119D02*
X612382Y1190118D01*
G01Y1186889D02*
X613337Y1186890D01*
G01X613366Y1185119D02*
X612382Y1185118D01*
G01Y1181889D02*
X613337Y1181890D01*
G01X613366Y1180119D02*
X612382Y1180118D01*
G01X609055Y1206713D02*
X610359Y1204744D01*
G01X613366Y1181667D02*
X613367Y1181676D01*
G01X613366Y1186667D02*
X613367Y1186676D01*
G01X613366Y1191667D02*
X613367Y1191676D01*
G01X613366Y1196667D02*
X613367Y1196676D01*
G01X618701Y1205846D02*
Y1221594D01*
G01X617717Y1195315D02*
Y1196693D01*
G01Y1190315D02*
Y1191693D01*
G01Y1185315D02*
Y1186693D01*
G01Y1180315D02*
Y1181693D01*
G01X614547D02*
Y1180315D01*
G01Y1186693D02*
Y1185315D01*
G01Y1191693D02*
Y1190315D01*
G01Y1196693D02*
Y1195315D01*
G01X613366Y1194823D02*
Y1197185D01*
G01Y1189823D02*
Y1192185D01*
G01Y1184823D02*
Y1187185D01*
G01Y1179823D02*
Y1182185D01*
G01Y1181667D02*
Y1181811D01*
G01Y1186667D02*
Y1186811D01*
G01Y1191667D02*
Y1191811D01*
G01Y1196667D02*
Y1196811D01*
G01X612382Y1182185D02*
Y1179823D01*
G01Y1187185D02*
Y1184823D01*
G01Y1192185D02*
Y1189823D01*
G01Y1197185D02*
Y1194823D01*
G01X611811Y1216083D02*
Y1222185D01*
G01X611614Y1211909D02*
Y1203366D01*
G01X609055Y1208406D02*
Y1206713D01*
G01X606693D02*
Y1208406D01*
G01X611365Y1212635D02*
X609055Y1208406D01*
G01X618701Y1205846D02*
X615354Y1202500D01*
G01X608858Y1199823D02*
X610039Y1201004D01*
G01X605389Y1204744D02*
X606693Y1206713D01*
G01X610358Y1284397D02*
G03X644169I16906J-13531D01*
G01X610358D02*
G03X644169I16906J-13531D01*
G01X637244Y1297528D02*
G03X644169Y1284397I37662J11471D01*
G01X637244Y1297528D02*
G03X617283I-9980J-3040D01*
G01X610358Y1284397D02*
G03X617283Y1297528I-30737J24602D01*
G01X637244D02*
G03X617283I-9980J-3040D01*
G01X637244D02*
G03X644169Y1284397I37662J11471D01*
G01X610358D02*
G03X617283Y1297528I-30737J24601D01*
G01X659474Y0D02*
G03Y-7874I0J-3937D01*
G01D02*
X780203D01*
G01X674114Y20472D02*
G03X682776I4331J0D01*
G01X659474Y-7874D02*
X780203D01*
G01X659474Y0D02*
G03Y-7874I0J-3937D01*
G01X682776Y20473D02*
G03I-4331J0D01*
G01Y20472D02*
G03X674114I-4331J0D01*
G01X692126Y374803D02*
G03X693307I591J0D01*
G01Y368504D02*
G03X692126I-590J0D01*
G01X690157D02*
G03X688976I-590J0D01*
G01Y374803D02*
G03X690157I590J0D01*
G01X692126D02*
G03X693307I591J0D01*
G01Y368504D02*
G03X692126I-590J0D01*
G01X690157D02*
G03X688976I-590J0D01*
G01Y374803D02*
G03X690157I590J0D01*
G01X694094Y368504D02*
Y374803D01*
G01Y368504D02*
Y374803D01*
G01X688189Y368504D02*
Y374803D01*
G01D02*
Y368504D01*
G01X692126Y374803D02*
X690157D01*
G01X688976D02*
X688189D01*
G01X692126D02*
X690157D01*
G01X688976D02*
X688189D01*
G01X694094D02*
X693307D01*
G01X694094D02*
X693307D01*
G01X694094Y373819D02*
X688189D01*
G01Y373622D02*
X694094D01*
G01X688189Y369685D02*
X694094D01*
G01Y369488D02*
X688189D01*
G01X693307Y368504D02*
X694094D01*
G01X693307D02*
X694094D01*
G01X690157D02*
X692126D01*
G01X688189D02*
X688976D01*
G01X690157D02*
X692126D01*
G01X688189D02*
X688976D01*
G01X692126Y827559D02*
G03X693307I591J0D01*
G01Y821260D02*
G03X692126I-590J0D01*
G01X690157D02*
G03X688976I-590J0D01*
G01Y827559D02*
G03X690157I590J0D01*
G01X692126D02*
G03X693307I591J0D01*
G01Y821260D02*
G03X692126I-590J0D01*
G01X690157D02*
G03X688976I-590J0D01*
G01Y827559D02*
G03X690157I590J0D01*
G01X692126D02*
X690157D01*
G01X688976D02*
X688189D01*
G01X692126D02*
X690157D01*
G01X688976D02*
X688189D01*
G01X694094D02*
X693307D01*
G01X694094D02*
X693307D01*
G01X694094Y826575D02*
X688189D01*
G01Y826378D02*
X694094D01*
G01X688189Y822441D02*
X694094D01*
G01Y822244D02*
X688189D01*
G01X693307Y821260D02*
X694094D01*
G01X693307D02*
X694094D01*
G01X690157D02*
X692126D01*
G01X688189D02*
X688976D01*
G01X690157D02*
X692126D01*
G01X688189D02*
X688976D01*
G01X694094D02*
Y827559D01*
G01Y821260D02*
Y827559D01*
G01X688189Y821260D02*
Y827559D01*
G01D02*
Y821260D01*
G01X663091Y1062992D02*
G03X677067I6988J0D01*
G01D02*
G03X663091I-6988J0D01*
G01X677067D02*
G03I-6988J0D01*
G01X664567Y1114173D02*
G03X675591I5512J0D01*
G01D02*
G03X664567I-5512J0D01*
G01X675591D02*
G03I-5512J0D01*
G01X693307Y1274016D02*
G03X692126I-590J0D01*
G01X690157D02*
G03X688976I-590J0D01*
G01X693307D02*
G03X692126I-590J0D01*
G01X690157D02*
G03X688976I-590J0D01*
G01X688189Y1275197D02*
X694094D01*
G01Y1275000D02*
X688189D01*
G01X693307Y1274016D02*
X694094D01*
G01X693307D02*
X694094D01*
G01X690157D02*
X692126D01*
G01X688189D02*
X688976D01*
G01X690157D02*
X692126D01*
G01X688189D02*
X688976D01*
G01X694094D02*
Y1280315D01*
G01Y1274016D02*
Y1280315D01*
G01X688189Y1274016D02*
Y1280315D01*
G01D02*
Y1274016D01*
G01X692126Y1280315D02*
G03X693307I591J0D01*
G01X688976D02*
G03X690157I590J0D01*
G01X692126D02*
G03X693307I591J0D01*
G01X688976D02*
G03X690157I590J0D01*
G01X692126D02*
X690157D01*
G01X688976D02*
X688189D01*
G01X692126D02*
X690157D01*
G01X688976D02*
X688189D01*
G01X694094D02*
X693307D01*
G01X694094D02*
X693307D01*
G01X694094Y1279331D02*
X688189D01*
G01Y1279134D02*
X694094D01*
G01X692520Y1374803D02*
G03Y1382677I0J3937D01*
G01Y1374803D02*
G03Y1382677I0J3937D01*
G01X740488Y-335933D02*
X1922083D01*
G01X728150Y139311D02*
G03X728740Y138720I591J0D01*
G01X735433D02*
G03X736024Y139311I0J591D01*
G01X733268Y140492D02*
G03Y142461I0J984D01*
G01X730906D02*
G03Y140492I0J-984D01*
G01X733189Y153681D02*
G03I-1102J0D01*
G01X734646Y148406D02*
G03X735827Y149587I0J1181D01*
G01X728346D02*
G03X729528Y148406I1181J0D01*
G01X733661Y153681D02*
G03I-1574J0D01*
G01X721260Y139902D02*
G03X723228Y137933I1969J0D01*
G01X740945D02*
G03X742913Y139902I0J1968D01*
G01X727559Y161673D02*
X726378Y160492D01*
G01X724606Y158996D02*
X721260Y155650D01*
G01X734571Y156752D02*
X733268Y154783D01*
G01X728595Y148861D02*
X730906Y153091D01*
G01X742913Y139902D02*
Y155650D01*
G01X739567Y296988D02*
Y158996D01*
G01X738976Y299232D02*
Y156752D01*
G01X736024Y145413D02*
Y139311D01*
G01X735827Y158130D02*
Y149587D01*
G01X734252Y196949D02*
Y160492D01*
G01X733268Y154783D02*
Y153091D01*
G01X733071Y198130D02*
Y161673D01*
G01X730906Y153091D02*
Y154783D01*
G01X728346Y149587D02*
Y158130D01*
G01X728150Y145413D02*
Y139311D01*
G01X727559Y161673D02*
Y294311D01*
G01X726378Y160492D02*
Y295492D01*
G01X724606Y195787D02*
Y156752D01*
G01X721260Y155650D02*
Y139902D01*
G01X733268Y153091D02*
X735578Y148861D01*
G01X730906Y154783D02*
X729602Y156752D01*
G01X739567Y158996D02*
X742913Y155650D01*
G01X733071Y161673D02*
X734252Y160492D01*
G01X733071Y161673D02*
X727559D01*
G01X734252Y160492D02*
X726378D01*
G01X739567Y158996D02*
X724606D01*
G01X735827Y158130D02*
X738976D01*
G01X728346D02*
X724606D01*
G01Y156752D02*
X738976D01*
G01X733268Y154783D02*
X730906D01*
G01X733268Y153091D02*
X730906D01*
G01X734646Y148406D02*
X729528D01*
G01X742913Y148366D02*
X721260D01*
G01X736024Y145413D02*
X728150D01*
G01Y143839D02*
X736024D01*
G01X733268Y142461D02*
X730906D01*
G01Y140492D02*
X733268D01*
G01X735433Y138720D02*
X728740D01*
G01X740945Y137933D02*
X723228D01*
G01X723169Y201132D02*
Y201128D01*
G01X723171Y201126D02*
X723169Y201132D01*
G01X723183Y201111D02*
X723171Y201126D01*
G01X723207Y201102D02*
X723183Y201111D01*
G01X723169Y204282D02*
Y204278D01*
G01X723171Y204276D02*
X723169Y204282D01*
G01X723182Y204260D02*
X723171Y204276D01*
G01X723207Y204252D02*
X723182Y204260D01*
G01X723169Y210581D02*
Y210577D01*
G01X723171Y210575D02*
X723169Y210581D01*
G01X723182Y210559D02*
X723171Y210575D01*
G01X723207Y210551D02*
X723182Y210559D01*
G01X723169Y197983D02*
Y197979D01*
G01X723171Y197976D02*
X723169Y197983D01*
G01X723182Y197961D02*
X723171Y197976D01*
G01X723207Y197953D02*
X723182Y197961D01*
G01X737566Y166173D02*
X737577Y166157D01*
G01X737542Y166181D02*
X737566Y166173D01*
G01Y171173D02*
X737577Y171157D01*
G01X737542Y171181D02*
X737566Y171173D01*
G01Y176173D02*
X737577Y176157D01*
G01X737542Y176181D02*
X737566Y176173D01*
G01Y181173D02*
X737577Y181157D01*
G01X737542Y181181D02*
X737566Y181173D01*
G01Y186173D02*
X737577Y186157D01*
G01X737542Y186181D02*
X737566Y186173D01*
G01Y191173D02*
X737577Y191157D01*
G01X737542Y191181D02*
X737566Y191173D01*
G01Y196173D02*
X737577Y196157D01*
G01X737542Y196181D02*
X737566Y196173D01*
G01X723169Y207431D02*
Y207428D01*
G01X723170Y207426D02*
X723169Y207431D01*
G01X723181Y207411D02*
X723170Y207426D01*
G01X723204Y207402D02*
X723181Y207411D01*
G01X724122Y199133D02*
X724113Y199134D01*
G01X724131Y199130D02*
X724122Y199133D01*
G01X724139Y199124D02*
X724131Y199130D01*
G01X724122Y202282D02*
X724113Y202283D01*
G01X724131Y202279D02*
X724122Y202282D01*
G01X724139Y202274D02*
X724131Y202279D01*
G01Y197945D02*
X724134Y197947D01*
G01X724128Y197944D02*
X724131Y197945D01*
G01X724125Y197943D02*
X724128Y197944D01*
G01X724121Y197942D02*
X724125Y197943D01*
G01X724118Y197942D02*
X724121D01*
G01X724114D02*
X724118D01*
G01X723192Y199142D02*
X723189Y199140D01*
G01X723195Y199143D02*
X723192Y199142D01*
G01X723198Y199144D02*
X723195Y199143D01*
G01X723202Y199144D02*
X723198D01*
G01X723205Y199145D02*
X723202Y199144D01*
G01X723209Y199145D02*
X723205D01*
G01X724131Y201095D02*
X724134Y201096D01*
G01X724128Y201094D02*
X724131Y201095D01*
G01X724125Y201093D02*
X724128Y201094D01*
G01X724121Y201092D02*
X724125Y201093D01*
G01X724118Y201091D02*
X724121Y201092D01*
G01X724114Y201091D02*
X724118D01*
G01X723192Y202291D02*
X723189Y202290D01*
G01X723195Y202293D02*
X723192Y202291D01*
G01X723198Y202294D02*
X723195Y202293D01*
G01X723202Y202294D02*
X723198D01*
G01X723205Y202295D02*
X723202Y202294D01*
G01X723209Y202295D02*
X723205D01*
G01X724131Y204244D02*
X724134Y204246D01*
G01X724128Y204243D02*
X724131Y204244D01*
G01X724125Y204242D02*
X724128Y204243D01*
G01X724121Y204241D02*
X724125Y204242D01*
G01X724118Y204241D02*
X724121D01*
G01X724114D02*
X724118D01*
G01X723192Y205441D02*
X723189Y205439D01*
G01X723195Y205442D02*
X723192Y205441D01*
G01X723198Y205443D02*
X723195Y205442D01*
G01X723202Y205444D02*
X723198Y205443D01*
G01X723205Y205444D02*
X723202D01*
G01X723209D02*
X723205D01*
G01X724131Y207394D02*
X724134Y207396D01*
G01X724128Y207393D02*
X724131Y207394D01*
G01X724125Y207392D02*
X724128Y207393D01*
G01X724121Y207391D02*
X724125Y207392D01*
G01X724118Y207391D02*
X724121D01*
G01X724114D02*
X724118D01*
G01X723192Y208591D02*
X723189Y208589D01*
G01X723195Y208592D02*
X723192Y208591D01*
G01X723198Y208593D02*
X723195Y208592D01*
G01X723202Y208593D02*
X723198D01*
G01X723205Y208594D02*
X723202Y208593D01*
G01X723209Y208594D02*
X723205D01*
G01X724131Y210544D02*
X724134Y210545D01*
G01X724128Y210543D02*
X724131Y210544D01*
G01X724125Y210541D02*
X724128Y210543D01*
G01X724121Y210541D02*
X724125D01*
G01X724118Y210540D02*
X724121Y210541D01*
G01X724114Y210540D02*
X724118D01*
G01X723192Y211740D02*
X723189Y211739D01*
G01X723195Y211741D02*
X723192Y211740D01*
G01X723198Y211743D02*
X723195Y211741D01*
G01X723202Y211743D02*
X723198D01*
G01X723205Y211744D02*
X723202Y211743D01*
G01X723209Y211744D02*
X723205D01*
G01X722422Y201142D02*
X721988D01*
G01X722796D02*
X722422D01*
G01Y207441D02*
X721988D01*
G01X722796D02*
X722422D01*
G01Y210591D02*
X721988D01*
G01X722795D02*
X722422D01*
G01X724144Y199132D02*
X724148Y199127D01*
G01X724139Y199137D02*
X724144Y199132D01*
G01X724133Y199141D02*
X724139Y199137D01*
G01X724128Y199143D02*
X724133Y199141D01*
G01X724121Y199145D02*
X724128Y199143D01*
G01X724114Y199145D02*
X724121D01*
G01X724144Y202282D02*
X724148Y202277D01*
G01X724139Y202286D02*
X724144Y202282D01*
G01X724133Y202290D02*
X724139Y202286D01*
G01X724128Y202293D02*
X724133Y202290D01*
G01X724121Y202294D02*
X724128Y202293D01*
G01X724114Y202295D02*
X724121Y202294D01*
G01X724144Y205431D02*
X724148Y205426D01*
G01X724139Y205436D02*
X724144Y205431D01*
G01X724133Y205440D02*
X724139Y205436D01*
G01X724128Y205442D02*
X724133Y205440D01*
G01X724121Y205444D02*
X724128Y205442D01*
G01X724114Y205444D02*
X724121D01*
G01X724144Y208581D02*
X724148Y208576D01*
G01X724139Y208585D02*
X724144Y208581D01*
G01X724133Y208589D02*
X724139Y208585D01*
G01X724128Y208592D02*
X724133Y208589D01*
G01X724121Y208594D02*
X724128Y208592D01*
G01X724114Y208594D02*
X724121D01*
G01X724144Y211731D02*
X724148Y211726D01*
G01X724139Y211735D02*
X724144Y211731D01*
G01X724133Y211739D02*
X724139Y211735D01*
G01X724128Y211741D02*
X724133Y211739D01*
G01X724121Y211743D02*
X724128Y211741D01*
G01X724114Y211744D02*
X724121Y211743D01*
G01X723170Y197971D02*
X723169Y197979D01*
G01X723172Y197965D02*
X723170Y197971D01*
G01X723176Y197958D02*
X723172Y197965D01*
G01X723181Y197952D02*
X723176Y197958D01*
G01X723187Y197948D02*
X723181Y197952D01*
G01X723194Y197944D02*
X723187Y197948D01*
G01X723201Y197943D02*
X723194Y197944D01*
G01X723209Y197942D02*
X723201Y197943D01*
G01X723170Y201121D02*
X723169Y201128D01*
G01X723172Y201114D02*
X723170Y201121D01*
G01X723176Y201108D02*
X723172Y201114D01*
G01X723181Y201102D02*
X723176Y201108D01*
G01X723187Y201097D02*
X723181Y201102D01*
G01X723194Y201094D02*
X723187Y201097D01*
G01X723201Y201092D02*
X723194Y201094D01*
G01X723209Y201091D02*
X723201Y201092D01*
G01X723170Y204270D02*
X723169Y204278D01*
G01X723172Y204264D02*
X723170Y204270D01*
G01X723176Y204257D02*
X723172Y204264D01*
G01X723181Y204252D02*
X723176Y204257D01*
G01X723187Y204247D02*
X723181Y204252D01*
G01X723194Y204244D02*
X723187Y204247D01*
G01X723201Y204242D02*
X723194Y204244D01*
G01X723209Y204241D02*
X723201Y204242D01*
G01X723170Y207420D02*
X723169Y207428D01*
G01X723172Y207413D02*
X723170Y207420D01*
G01X723176Y207407D02*
X723172Y207413D01*
G01X723181Y207401D02*
X723176Y207407D01*
G01X723187Y207396D02*
X723181Y207401D01*
G01X723194Y207393D02*
X723187Y207396D01*
G01X723201Y207391D02*
X723194Y207393D01*
G01X723209Y207391D02*
X723201D01*
G01X723170Y210570D02*
X723169Y210577D01*
G01X723172Y210563D02*
X723170Y210570D01*
G01X723176Y210557D02*
X723172Y210563D01*
G01X723181Y210551D02*
X723176Y210557D01*
G01X723187Y210546D02*
X723181Y210551D01*
G01X723194Y210543D02*
X723187Y210546D01*
G01X723201Y210541D02*
X723194Y210543D01*
G01X723209Y210540D02*
X723201Y210541D01*
G01X724123Y199133D02*
X724133Y199128D01*
G01X724113Y199134D02*
X724123Y199133D01*
G01Y202282D02*
X724133Y202278D01*
G01X724113Y202283D02*
X724123Y202282D01*
G01Y205432D02*
X724133Y205428D01*
G01X724113Y205433D02*
X724123Y205432D01*
G01Y208581D02*
X724133Y208577D01*
G01X724113Y208583D02*
X724123Y208581D01*
G01Y211731D02*
X724133Y211727D01*
G01X724113Y211732D02*
X724123Y211731D01*
G01X724122Y205432D02*
X724113Y205433D01*
G01X724131Y205429D02*
X724122Y205432D01*
G01X724139Y205424D02*
X724131Y205429D01*
G01X724122Y208581D02*
X724113Y208583D01*
G01X724131Y208578D02*
X724122Y208581D01*
G01X724139Y208573D02*
X724131Y208578D01*
G01X724122Y211731D02*
X724113Y211732D01*
G01X724131Y211728D02*
X724122Y211731D01*
G01X724139Y211723D02*
X724131Y211728D01*
G01X723208Y197948D02*
X723209Y197942D01*
G01X723207Y197952D02*
X723208Y197948D01*
G01X723206Y197953D02*
X723207Y197952D01*
G01X723208Y201098D02*
X723209Y201091D01*
G01X723207Y201101D02*
X723208Y201098D01*
G01X723206Y201102D02*
X723207Y201101D01*
G01X723208Y204247D02*
X723209Y204241D01*
G01X723207Y204251D02*
X723208Y204247D01*
G01X723206Y204252D02*
X723207Y204251D01*
G01X723208Y207397D02*
X723209Y207391D01*
G01X723207Y207400D02*
X723208Y207397D01*
G01X723206Y207402D02*
X723207Y207400D01*
G01X723208Y210546D02*
X723209Y210540D01*
G01X723207Y210550D02*
X723208Y210546D01*
G01X723206Y210551D02*
X723207Y210550D01*
G01X737579Y166148D02*
Y166156D01*
G01X737580Y166144D02*
X737579Y166148D01*
G01X737581Y166142D02*
X737580Y166144D01*
G01X737579Y171148D02*
Y171156D01*
G01X737580Y171144D02*
X737579Y171148D01*
G01X737581Y171142D02*
X737580Y171144D01*
G01X737579Y176148D02*
Y176156D01*
G01X737580Y176144D02*
X737579Y176148D01*
G01X737581Y176142D02*
X737580Y176144D01*
G01X737579Y181148D02*
Y181156D01*
G01X737580Y181144D02*
X737579Y181148D01*
G01X737581Y181142D02*
X737580Y181144D01*
G01X737579Y186148D02*
Y186156D01*
G01X737580Y186144D02*
X737579Y186148D01*
G01X737581Y186142D02*
X737580Y186144D01*
G01X737579Y191148D02*
Y191156D01*
G01X737580Y191144D02*
X737579Y191148D01*
G01X737581Y191142D02*
X737580Y191144D01*
G01X737579Y196148D02*
Y196156D01*
G01X737580Y196144D02*
X737579Y196148D01*
G01X737581Y196142D02*
X737580Y196144D01*
G01X723172Y199114D02*
X723167Y199094D01*
G01X723187Y199129D02*
X723172Y199114D01*
G01X723206Y199134D02*
X723187Y199129D01*
G01X723172Y202264D02*
X723167Y202244D01*
G01X723187Y202278D02*
X723172Y202264D01*
G01X723206Y202283D02*
X723187Y202278D01*
G01X723172Y205413D02*
X723167Y205394D01*
G01X723187Y205428D02*
X723172Y205413D01*
G01X723206Y205433D02*
X723187Y205428D01*
G01X723172Y208563D02*
X723167Y208543D01*
G01X723187Y208578D02*
X723172Y208563D01*
G01X723206Y208583D02*
X723187Y208578D01*
G01X723172Y211713D02*
X723167Y211693D01*
G01X723187Y211727D02*
X723172Y211713D01*
G01X723206Y211732D02*
X723187Y211727D01*
G01X724147Y197972D02*
X724152Y197992D01*
G01X724132Y197958D02*
X724147Y197972D01*
G01X724113Y197953D02*
X724132Y197958D01*
G01X724147Y201122D02*
X724152Y201142D01*
G01X724132Y201108D02*
X724147Y201122D01*
G01X724113Y201102D02*
X724132Y201108D01*
G01X724147Y204272D02*
X724152Y204291D01*
G01X724132Y204257D02*
X724147Y204272D01*
G01X724113Y204252D02*
X724132Y204257D01*
G01X724147Y207421D02*
X724152Y207441D01*
G01X724132Y207407D02*
X724147Y207421D01*
G01X724113Y207402D02*
X724132Y207407D01*
G01X724147Y210571D02*
X724152Y210591D01*
G01X724132Y210557D02*
X724147Y210571D01*
G01X724113Y210551D02*
X724132Y210557D01*
G01X723192Y201105D02*
X723206Y201102D01*
G01X723181Y201112D02*
X723192Y201105D01*
G01X723169Y201131D02*
X723181Y201112D01*
G01X723192Y210554D02*
X723206Y210551D01*
G01X723180Y210561D02*
X723192Y210554D01*
G01X723169Y210580D02*
X723180Y210561D01*
G01X723192Y204255D02*
X723206Y204252D01*
G01X723180Y204263D02*
X723192Y204255D01*
G01X723168Y204283D02*
X723180Y204263D01*
G01X724154Y197986D02*
Y197979D01*
G01X724153Y197991D02*
X724154Y197986D01*
G01X724152Y197992D02*
X724153Y197991D01*
G01X724154Y201136D02*
Y201128D01*
G01X724153Y201141D02*
X724154Y201136D01*
G01X724152Y201142D02*
X724153Y201141D01*
G01X724154Y204285D02*
Y204278D01*
G01X724153Y204290D02*
X724154Y204285D01*
G01X724152Y204291D02*
X724153Y204290D01*
G01X724154Y207435D02*
Y207428D01*
G01X724153Y207440D02*
X724154Y207435D01*
G01X724152Y207441D02*
X724153Y207440D01*
G01X724154Y210585D02*
Y210577D01*
G01X724153Y210589D02*
X724154Y210585D01*
G01X724152Y210591D02*
X724153Y210589D01*
G01X723191Y197956D02*
X723206Y197953D01*
G01X723178Y197964D02*
X723191Y197956D01*
G01X723168Y197985D02*
X723178Y197964D01*
G01X724153Y199115D02*
X724154Y199108D01*
G01X724151Y199121D02*
X724153Y199115D01*
G01X724148Y199127D02*
X724151Y199121D01*
G01X724153Y202265D02*
X724154Y202258D01*
G01X724151Y202271D02*
X724153Y202265D01*
G01X724148Y202277D02*
X724151Y202271D01*
G01X724153Y205414D02*
X724154Y205407D01*
G01X724151Y205420D02*
X724153Y205414D01*
G01X724148Y205426D02*
X724151Y205420D01*
G01X724153Y208564D02*
X724154Y208557D01*
G01X724151Y208570D02*
X724153Y208564D01*
G01X724148Y208576D02*
X724151Y208570D01*
G01X724153Y211713D02*
X724154Y211707D01*
G01X724151Y211720D02*
X724153Y211713D01*
G01X724148Y211726D02*
X724151Y211720D01*
G01X724115Y197948D02*
Y197942D01*
G01X724113Y197952D02*
X724115Y197948D01*
G01X724113Y197953D02*
Y197952D01*
G01X724115Y201097D02*
Y201091D01*
G01X724113Y201101D02*
X724115Y201097D01*
G01X724113Y201102D02*
Y201101D01*
G01X724115Y204247D02*
Y204241D01*
G01X724113Y204251D02*
X724115Y204247D01*
G01X724113Y204252D02*
Y204251D01*
G01X724115Y207396D02*
Y207391D01*
G01X724113Y207400D02*
X724115Y207396D01*
G01X724113Y207402D02*
Y207400D01*
G01X724115Y210546D02*
Y210540D01*
G01X724113Y210550D02*
X724115Y210546D01*
G01X724113Y210551D02*
Y210550D01*
G01X736594Y166189D02*
Y166198D01*
G01X736595Y166183D02*
X736594Y166189D01*
G01X736596Y166181D02*
X736595Y166183D01*
G01X736594Y171189D02*
Y171198D01*
G01X736595Y171183D02*
X736594Y171189D01*
G01X736596Y171181D02*
X736595Y171183D01*
G01X736594Y176189D02*
Y176198D01*
G01X736595Y176183D02*
X736594Y176189D01*
G01X736596Y176181D02*
X736595Y176183D01*
G01X736594Y181189D02*
Y181198D01*
G01X736595Y181183D02*
X736594Y181189D01*
G01X736596Y181181D02*
X736595Y181183D01*
G01X736594Y186189D02*
Y186198D01*
G01X736595Y186183D02*
X736594Y186189D01*
G01X736596Y186181D02*
X736595Y186183D01*
G01X736594Y191189D02*
Y191198D01*
G01X736595Y191183D02*
X736594Y191189D01*
G01X736596Y191181D02*
X736595Y191183D01*
G01X736594Y196189D02*
Y196198D01*
G01X736595Y196183D02*
X736594Y196189D01*
G01X736596Y196181D02*
X736595Y196183D01*
G01X737571Y166325D02*
X737579Y166299D01*
G01X737561Y166352D02*
X737571Y166325D01*
G01X737550Y166378D02*
X737561Y166352D01*
G01X737571Y171325D02*
X737579Y171299D01*
G01X737561Y171352D02*
X737571Y171325D01*
G01X737550Y171378D02*
X737561Y171352D01*
G01X737571Y176325D02*
X737579Y176299D01*
G01X737561Y176352D02*
X737571Y176325D01*
G01X737550Y176378D02*
X737561Y176352D01*
G01X737571Y181325D02*
X737579Y181299D01*
G01X737561Y181352D02*
X737571Y181325D01*
G01X737550Y181378D02*
X737561Y181352D01*
G01X737571Y186325D02*
X737579Y186299D01*
G01X737561Y186352D02*
X737571Y186325D01*
G01X737550Y186378D02*
X737561Y186352D01*
G01X737571Y191325D02*
X737579Y191299D01*
G01X737561Y191352D02*
X737571Y191325D01*
G01X737550Y191378D02*
X737561Y191352D01*
G01X737571Y196325D02*
X737579Y196299D01*
G01X737561Y196352D02*
X737571Y196325D01*
G01X737550Y196378D02*
X737561Y196352D01*
G01X723187Y207407D02*
X723206Y207402D01*
G01X723174Y207419D02*
X723187Y207407D01*
G01X723167Y207437D02*
X723174Y207419D01*
G01X737561Y166176D02*
X737542Y166181D01*
G01X737576Y166162D02*
X737561Y166176D01*
G01X737581Y166142D02*
X737576Y166162D01*
G01X737561Y171176D02*
X737542Y171181D01*
G01X737576Y171162D02*
X737561Y171176D01*
G01X737581Y171142D02*
X737576Y171162D01*
G01X737561Y176176D02*
X737542Y176181D01*
G01X737576Y176162D02*
X737561Y176176D01*
G01X737581Y176142D02*
X737576Y176162D01*
G01X737561Y181176D02*
X737542Y181181D01*
G01X737576Y181162D02*
X737561Y181176D01*
G01X737581Y181142D02*
X737576Y181162D01*
G01X737561Y186176D02*
X737542Y186181D01*
G01X737576Y186162D02*
X737561Y186176D01*
G01X737581Y186142D02*
X737576Y186162D01*
G01X737561Y191176D02*
X737542Y191181D01*
G01X737576Y191162D02*
X737561Y191176D01*
G01X737581Y191142D02*
X737576Y191162D01*
G01X737561Y196176D02*
X737542Y196181D01*
G01X737576Y196162D02*
X737561Y196176D01*
G01X737581Y196142D02*
X737576Y196162D01*
G01X737546Y166279D02*
X737550Y166378D01*
G01X737540Y166207D02*
X737546Y166279D01*
G01X737542Y166181D02*
X737540Y166207D01*
G01X737546Y171279D02*
X737550Y171378D01*
G01X737540Y171207D02*
X737546Y171279D01*
G01X737542Y171181D02*
X737540Y171207D01*
G01X737546Y176279D02*
X737550Y176378D01*
G01X737540Y176207D02*
X737546Y176279D01*
G01X737542Y176181D02*
X737540Y176207D01*
G01X737546Y181279D02*
X737550Y181378D01*
G01X737540Y181207D02*
X737546Y181279D01*
G01X737542Y181181D02*
X737540Y181207D01*
G01X737546Y186279D02*
X737550Y186378D01*
G01X737540Y186207D02*
X737546Y186279D01*
G01X737542Y186181D02*
X737540Y186207D01*
G01X737546Y191279D02*
X737550Y191378D01*
G01X737540Y191207D02*
X737546Y191279D01*
G01X737542Y191181D02*
X737540Y191207D01*
G01X737546Y196279D02*
X737550Y196378D01*
G01X737540Y196207D02*
X737546Y196279D01*
G01X737542Y196181D02*
X737540Y196207D01*
G01X724146Y205415D02*
X724139Y205424D01*
G01X724150Y205405D02*
X724146Y205415D01*
G01X724152Y205394D02*
X724150Y205405D01*
G01X724146Y199116D02*
X724139Y199124D01*
G01X724151Y199106D02*
X724146Y199116D01*
G01X724152Y199094D02*
X724151Y199106D01*
G01X724146Y202265D02*
X724139Y202274D01*
G01X724151Y202255D02*
X724146Y202265D01*
G01X724152Y202244D02*
X724151Y202255D01*
G01X724146Y208565D02*
X724139Y208573D01*
G01X724151Y208554D02*
X724146Y208565D01*
G01X724152Y208543D02*
X724151Y208554D01*
G01X724146Y211714D02*
X724139Y211723D01*
G01X724151Y211704D02*
X724146Y211714D01*
G01X724152Y211693D02*
X724151Y211704D01*
G01X723169Y210585D02*
Y210577D01*
G01X723168Y210589D02*
X723169Y210585D01*
G01Y210580D02*
X723168Y210589D01*
G01X723209Y211917D02*
Y211929D01*
G01X723206Y211904D02*
X723209Y211917D01*
G01X723206Y211890D02*
Y211904D01*
G01X723209Y208767D02*
Y208780D01*
G01X723206Y208754D02*
X723209Y208767D01*
G01X723206Y208741D02*
Y208754D01*
G01X723209Y205618D02*
Y205630D01*
G01X723206Y205605D02*
X723209Y205618D01*
G01X723206Y205591D02*
Y205605D01*
G01X723209Y202468D02*
Y202480D01*
G01X723206Y202455D02*
X723209Y202468D01*
G01X723206Y202441D02*
Y202455D01*
G01X723209Y199319D02*
Y199331D01*
G01X723206Y199306D02*
X723209Y199319D01*
G01X723206Y199292D02*
Y199306D01*
G01X736595Y194802D02*
X736596Y194803D01*
G01X736594Y194796D02*
X736595Y194802D01*
G01X736594Y194787D02*
Y194796D01*
G01X736595Y189802D02*
X736596Y189803D01*
G01X736594Y189796D02*
X736595Y189802D01*
G01X736594Y189787D02*
Y189796D01*
G01X736595Y184802D02*
X736596Y184803D01*
G01X736594Y184796D02*
X736595Y184802D01*
G01X736594Y184787D02*
Y184796D01*
G01X736595Y179802D02*
X736596Y179803D01*
G01X736594Y179796D02*
X736595Y179802D01*
G01X736594Y179787D02*
Y179796D01*
G01X736595Y174802D02*
X736596Y174803D01*
G01X736594Y174796D02*
X736595Y174802D01*
G01X736594Y174787D02*
Y174796D01*
G01X736595Y169802D02*
X736596Y169803D01*
G01X736594Y169796D02*
X736595Y169802D01*
G01X736594Y169787D02*
Y169796D01*
G01X736595Y164802D02*
X736596Y164803D01*
G01X736594Y164796D02*
X736595Y164802D01*
G01X736594Y164787D02*
Y164796D01*
G01X723206Y210380D02*
X723205Y210393D01*
G01X723209Y210367D02*
X723206Y210380D01*
G01X723209Y210354D02*
Y210367D01*
G01X723206Y207230D02*
X723205Y207244D01*
G01X723209Y207217D02*
X723206Y207230D01*
G01X723209Y207205D02*
Y207217D01*
G01X723206Y204081D02*
X723205Y204094D01*
G01X723209Y204068D02*
X723206Y204081D01*
G01X723209Y204055D02*
Y204068D01*
G01X723206Y200931D02*
X723205Y200944D01*
G01X723209Y200918D02*
X723206Y200931D01*
G01X723209Y200906D02*
Y200918D01*
G01X723206Y197781D02*
X723205Y197795D01*
G01X723209Y197769D02*
X723206Y197781D01*
G01X723209Y197756D02*
Y197769D01*
G01X724117Y211904D02*
X724118Y211890D01*
G01X724113Y211917D02*
X724117Y211904D01*
G01X724114Y211929D02*
X724113Y211917D01*
G01X724117Y208754D02*
X724118Y208741D01*
G01X724113Y208767D02*
X724117Y208754D01*
G01X724114Y208780D02*
X724113Y208767D01*
G01X724117Y205604D02*
X724118Y205591D01*
G01X724113Y205617D02*
X724117Y205604D01*
G01X724114Y205630D02*
X724113Y205617D01*
G01X724117Y202455D02*
X724118Y202441D01*
G01X724113Y202468D02*
X724117Y202455D01*
G01X724114Y202480D02*
X724113Y202468D01*
G01X724117Y199305D02*
X724118Y199292D01*
G01X724113Y199318D02*
X724117Y199305D01*
G01X724114Y199331D02*
X724113Y199318D01*
G01X723169Y204285D02*
Y204278D01*
G01X723168Y204290D02*
X723169Y204285D01*
G01X723168Y204283D02*
Y204290D01*
G01X724113Y210367D02*
X724114Y210354D01*
G01X724116Y210380D02*
X724113Y210367D01*
G01X724117Y210393D02*
X724116Y210380D01*
G01X724113Y207217D02*
X724114Y207205D01*
G01X724116Y207230D02*
X724113Y207217D01*
G01X724117Y207244D02*
X724116Y207230D01*
G01X724113Y204068D02*
X724114Y204055D01*
G01X724116Y204081D02*
X724113Y204068D01*
G01X724117Y204094D02*
X724116Y204081D01*
G01X724113Y200918D02*
X724114Y200906D01*
G01X724116Y200931D02*
X724113Y200918D01*
G01X724117Y200944D02*
X724116Y200931D01*
G01X724113Y197769D02*
X724114Y197756D01*
G01X724116Y197781D02*
X724113Y197769D01*
G01X724117Y197795D02*
X724116Y197781D01*
G01X723169Y197987D02*
Y197979D01*
G01X723168Y197991D02*
X723169Y197987D01*
G01X723168Y197985D02*
Y197991D01*
G01X723182Y211724D02*
X723206Y211732D01*
G01X723171Y211709D02*
X723182Y211724D01*
G01X723169Y211703D02*
X723171Y211709D01*
G01X723182Y208574D02*
X723206Y208583D01*
G01X723171Y208560D02*
X723182Y208574D01*
G01X723169Y208553D02*
X723171Y208560D01*
G01X723182Y205425D02*
X723206Y205433D01*
G01X723171Y205410D02*
X723182Y205425D01*
G01X723169Y205404D02*
X723171Y205410D01*
G01X723182Y202275D02*
X723206Y202283D01*
G01X723171Y202261D02*
X723182Y202275D01*
G01X723169Y202254D02*
X723171Y202261D01*
G01X723182Y199126D02*
X723206Y199134D01*
G01X723171Y199111D02*
X723182Y199126D01*
G01X723169Y199104D02*
X723171Y199111D01*
G01X724154Y211699D02*
Y211706D01*
G01X724153Y211695D02*
X724154Y211699D01*
G01X724152Y211693D02*
X724153Y211695D01*
G01X724154Y208550D02*
Y208557D01*
G01X724153Y208545D02*
X724154Y208550D01*
G01X724152Y208543D02*
X724153Y208545D01*
G01X724154Y205400D02*
Y205407D01*
G01X724153Y205396D02*
X724154Y205400D01*
G01X724152Y205394D02*
X724153Y205396D01*
G01X724154Y202250D02*
Y202257D01*
G01X724153Y202246D02*
X724154Y202250D01*
G01X724152Y202244D02*
X724153Y202246D01*
G01X723169Y207435D02*
Y207428D01*
G01X723168Y207440D02*
X723169Y207435D01*
G01X723167Y207437D02*
X723168Y207440D01*
G01X724154Y199101D02*
Y199108D01*
G01X724153Y199096D02*
X724154Y199101D01*
G01X724152Y199094D02*
X724153Y199096D01*
G01X723169Y201136D02*
Y201128D01*
G01X723168Y201141D02*
X723169Y201136D01*
G01X723167Y201138D02*
X723168Y201141D01*
G01X724114Y211737D02*
Y211744D01*
G01X724113Y211734D02*
X724114Y211737D01*
G01X724113Y211732D02*
Y211734D01*
G01X724114Y208588D02*
Y208594D01*
G01X724113Y208584D02*
X724114Y208588D01*
G01X724113Y208583D02*
Y208584D01*
G01X724114Y205438D02*
Y205444D01*
G01X724113Y205435D02*
X724114Y205438D01*
G01X724113Y205433D02*
Y205435D01*
G01X724114Y202289D02*
Y202295D01*
G01X724113Y202285D02*
X724114Y202289D01*
G01X724113Y202283D02*
Y202285D01*
G01X724114Y199139D02*
Y199145D01*
G01X724113Y199135D02*
X724114Y199139D01*
G01X724113Y199134D02*
Y199135D01*
G01X737579Y194796D02*
Y194787D01*
G01X737580Y194802D02*
X737579Y194796D01*
G01X737581Y194803D02*
X737580Y194802D01*
G01X737579Y189796D02*
Y189787D01*
G01X737580Y189802D02*
X737579Y189796D01*
G01X737581Y189803D02*
X737580Y189802D01*
G01X737579Y184796D02*
Y184787D01*
G01X737580Y184802D02*
X737579Y184796D01*
G01X737581Y184803D02*
X737580Y184802D01*
G01X737579Y179796D02*
Y179787D01*
G01X737580Y179802D02*
X737579Y179796D01*
G01X737581Y179803D02*
X737580Y179802D01*
G01X737579Y174796D02*
Y174787D01*
G01X737580Y174802D02*
X737579Y174796D01*
G01X737581Y174803D02*
X737580Y174802D01*
G01X737579Y169796D02*
Y169787D01*
G01X737580Y169802D02*
X737579Y169796D01*
G01X737581Y169803D02*
X737580Y169802D01*
G01X737579Y164796D02*
Y164787D01*
G01X737580Y164802D02*
X737579Y164796D01*
G01X737581Y164803D02*
X737580Y164802D01*
G01X723169Y211699D02*
Y211707D01*
G01X723168Y211694D02*
X723169Y211699D01*
G01X723167Y211693D02*
X723168Y211694D01*
G01X723169Y208550D02*
Y208557D01*
G01X723168Y208545D02*
X723169Y208550D01*
G01X723167Y208543D02*
X723168Y208545D01*
G01X723169Y205400D02*
Y205407D01*
G01X723168Y205395D02*
X723169Y205400D01*
G01X723167Y205394D02*
X723168Y205395D01*
G01X723169Y202250D02*
Y202258D01*
G01X723168Y202246D02*
X723169Y202250D01*
G01X723167Y202244D02*
X723168Y202246D01*
G01X723169Y199101D02*
Y199108D01*
G01X723168Y199096D02*
X723169Y199101D01*
G01X723167Y199094D02*
X723168Y199096D01*
G01X724151Y210565D02*
X724154Y210577D01*
G01X724144Y210554D02*
X724151Y210565D01*
G01X724134Y210545D02*
X724144Y210554D01*
G01X724151Y207415D02*
X724154Y207428D01*
G01X724144Y207404D02*
X724151Y207415D01*
G01X724134Y207396D02*
X724144Y207404D01*
G01X724151Y204265D02*
X724154Y204278D01*
G01X724144Y204254D02*
X724151Y204265D01*
G01X724134Y204246D02*
X724144Y204254D01*
G01X724151Y201116D02*
X724154Y201128D01*
G01X724144Y201105D02*
X724151Y201116D01*
G01X724134Y201096D02*
X724144Y201105D01*
G01X724151Y197966D02*
X724154Y197979D01*
G01X724144Y197955D02*
X724151Y197966D01*
G01X724134Y197947D02*
X724144Y197955D01*
G01X723208Y211737D02*
Y211744D01*
G01Y211733D02*
Y211737D01*
G01X723206Y211732D02*
X723208Y211733D01*
G01Y208588D02*
Y208594D01*
G01Y208584D02*
Y208588D01*
G01X723206Y208583D02*
X723208Y208584D01*
G01Y205438D02*
Y205444D01*
G01Y205434D02*
Y205438D01*
G01X723206Y205433D02*
X723208Y205434D01*
G01Y202289D02*
Y202295D01*
G01Y202285D02*
Y202289D01*
G01X723206Y202283D02*
X723208Y202285D01*
G01Y199139D02*
Y199145D01*
G01Y199135D02*
Y199139D01*
G01X723206Y199134D02*
X723208Y199135D01*
G01X723170Y211713D02*
X723169Y211707D01*
G01X723172Y211719D02*
X723170Y211713D01*
G01X723174Y211725D02*
X723172Y211719D01*
G01X723178Y211730D02*
X723174Y211725D01*
G01X723183Y211735D02*
X723178Y211730D01*
G01X723189Y211739D02*
X723183Y211735D01*
G01X723170Y208563D02*
X723169Y208557D01*
G01X723172Y208570D02*
X723170Y208563D01*
G01X723174Y208575D02*
X723172Y208570D01*
G01X723178Y208581D02*
X723174Y208575D01*
G01X723183Y208585D02*
X723178Y208581D01*
G01X723189Y208589D02*
X723183Y208585D01*
G01X723170Y205414D02*
X723169Y205407D01*
G01X723172Y205420D02*
X723170Y205414D01*
G01X723174Y205426D02*
X723172Y205420D01*
G01X723178Y205431D02*
X723174Y205426D01*
G01X723183Y205435D02*
X723178Y205431D01*
G01X723189Y205439D02*
X723183Y205435D01*
G01X723170Y202264D02*
X723169Y202258D01*
G01X723172Y202270D02*
X723170Y202264D01*
G01X723174Y202276D02*
X723172Y202270D01*
G01X723178Y202281D02*
X723174Y202276D01*
G01X723183Y202286D02*
X723178Y202281D01*
G01X723189Y202290D02*
X723183Y202286D01*
G01X723170Y199115D02*
X723169Y199108D01*
G01X723172Y199121D02*
X723170Y199115D01*
G01X723174Y199126D02*
X723172Y199121D01*
G01X723178Y199132D02*
X723174Y199126D01*
G01X723183Y199136D02*
X723178Y199132D01*
G01X723189Y199140D02*
X723183Y199136D01*
G01X724125Y210553D02*
X724113Y210551D01*
G01X724135Y210558D02*
X724125Y210553D01*
G01Y207404D02*
X724113Y207402D01*
G01X724135Y207409D02*
X724125Y207404D01*
G01Y204254D02*
X724113Y204252D01*
G01X724135Y204259D02*
X724125Y204254D01*
G01Y201104D02*
X724113Y201102D01*
G01X724135Y201109D02*
X724125Y201104D01*
G01Y197955D02*
X724113Y197953D01*
G01X724135Y197960D02*
X724125Y197955D01*
G01X724153Y199097D02*
X724154Y199108D01*
G01X724153Y202246D02*
X724154Y202257D01*
G01X724153Y205396D02*
X724154Y205407D01*
G01X724153Y208546D02*
X724154Y208557D01*
G01X724153Y211695D02*
X724154Y211706D01*
G01X737579Y166155D02*
Y166164D01*
G01Y171155D02*
Y171164D01*
G01Y176155D02*
Y176164D01*
G01Y181155D02*
Y181164D01*
G01Y186155D02*
Y186164D01*
G01Y191155D02*
Y191164D01*
G01Y196155D02*
Y196164D01*
G01X741929Y194803D02*
Y196181D01*
G01Y189803D02*
Y191181D01*
G01Y184803D02*
Y186181D01*
G01Y179803D02*
Y181181D01*
G01Y174803D02*
Y176181D01*
G01Y169803D02*
Y171181D01*
G01Y164803D02*
Y166181D01*
G01X738760D02*
Y164803D01*
G01Y171181D02*
Y169803D01*
G01Y176181D02*
Y174803D01*
G01Y181181D02*
Y179803D01*
G01Y186181D02*
Y184803D01*
G01Y191181D02*
Y189803D01*
G01Y196181D02*
Y194803D01*
G01X738189Y219035D02*
Y196949D01*
G01X737579Y166156D02*
Y166299D01*
G01Y171156D02*
Y171299D01*
G01Y176156D02*
Y176299D01*
G01Y181156D02*
Y181299D01*
G01Y186156D02*
Y186299D01*
G01Y191156D02*
Y191299D01*
G01Y196156D02*
Y196299D01*
G01Y194311D02*
Y196673D01*
G01Y189311D02*
Y191673D01*
G01Y184311D02*
Y186673D01*
G01Y179311D02*
Y181673D01*
G01Y174311D02*
Y176673D01*
G01Y169311D02*
Y171673D01*
G01Y164311D02*
Y166673D01*
G01X737008Y217854D02*
Y198130D01*
G01X736594Y166673D02*
Y164311D01*
G01Y171673D02*
Y169311D01*
G01Y176673D02*
Y174311D01*
G01Y181673D02*
Y179311D01*
G01Y186673D02*
Y184311D01*
G01Y191673D02*
Y189311D01*
G01Y196673D02*
Y194311D01*
G01X724154Y210394D02*
Y211890D01*
G01Y207244D02*
Y208740D01*
G01Y204094D02*
Y205591D01*
G01Y200945D02*
Y202441D01*
G01Y197795D02*
Y199291D01*
G01X724114Y197942D02*
Y197795D01*
G01Y201091D02*
Y200944D01*
G01Y202441D02*
Y202295D01*
G01Y199292D02*
Y199145D01*
G01Y207391D02*
Y207244D01*
G01Y204241D02*
Y204094D01*
G01Y205591D02*
Y205444D01*
G01Y210540D02*
Y210393D01*
G01Y211890D02*
Y211744D01*
G01Y208741D02*
Y208594D01*
G01X723209Y210393D02*
Y210540D01*
G01Y211744D02*
Y211891D01*
G01Y208594D02*
Y208741D01*
G01Y207243D02*
Y207391D01*
G01Y204094D02*
Y204241D01*
G01Y205444D02*
Y205591D01*
G01Y200944D02*
Y201091D01*
G01Y202295D02*
Y202442D01*
G01Y199145D02*
Y199292D01*
G01Y197794D02*
Y197942D01*
G01X723169Y202441D02*
Y200945D01*
G01Y199291D02*
Y197795D01*
G01Y205591D02*
Y204094D01*
G01Y211890D02*
Y210394D01*
G01Y208740D02*
Y207244D01*
G01X721988Y199134D02*
Y197953D01*
G01Y202283D02*
Y201102D01*
G01Y208583D02*
Y207402D01*
G01Y205433D02*
Y204252D01*
G01Y211732D02*
Y210551D01*
G01X721654Y220197D02*
Y195787D01*
G01X721260D02*
Y220197D01*
G01X718228Y210551D02*
Y211732D01*
G01Y207402D02*
Y208583D01*
G01Y204252D02*
Y205433D01*
G01Y201102D02*
Y202283D01*
G01Y197953D02*
Y199134D01*
G01X724154Y210577D02*
X724153Y210588D01*
G01X724154Y207428D02*
X724153Y207439D01*
G01X724154Y204278D02*
X724153Y204289D01*
G01X724154Y201128D02*
X724153Y201139D01*
G01X724154Y197979D02*
X724153Y197990D01*
G01X737008Y198130D02*
X738189Y196949D01*
G01X733071Y198130D02*
X734252Y196949D01*
G01X723167Y207437D02*
X723056Y207441D01*
G01X723167Y201138D02*
X723056Y201142D01*
G01X723167Y210587D02*
X723056Y210591D01*
G01X724114Y211929D02*
X723209D01*
G01X724154Y211890D02*
X723169D01*
G01X724113Y211732D02*
X718228D01*
G01Y211693D02*
X724152D01*
G01Y210591D02*
X718228D01*
G01X724113Y210551D02*
X718228D01*
G01X723169Y210394D02*
X724154D01*
G01X723209Y210354D02*
X724114D01*
G01Y208780D02*
X723209D01*
G01X724154Y208740D02*
X723169D01*
G01X724113Y208583D02*
X718228D01*
G01Y208543D02*
X724152D01*
G01Y207441D02*
X718228D01*
G01X724113Y207402D02*
X718228D01*
G01X723169Y207244D02*
X724154D01*
G01X723209Y207205D02*
X724114D01*
G01Y205630D02*
X723209D01*
G01X724154Y205591D02*
X723169D01*
G01X724113Y205433D02*
X718228D01*
G01Y205394D02*
X724152D01*
G01Y204291D02*
X718228D01*
G01X724113Y204252D02*
X718228D01*
G01X723169Y204094D02*
X724154D01*
G01X723209Y204055D02*
X724114D01*
G01Y202480D02*
X723209D01*
G01X724154Y202441D02*
X723169D01*
G01X724113Y202283D02*
X718228D01*
G01Y202244D02*
X724152D01*
G01Y201142D02*
X718228D01*
G01X724113Y201102D02*
X718228D01*
G01X723169Y200945D02*
X724154D01*
G01X723209Y200906D02*
X724114D01*
G01Y199331D02*
X723209D01*
G01X724154Y199291D02*
X723169D01*
G01X724113Y199134D02*
X718228D01*
G01Y199094D02*
X724152D01*
G01X737008Y198130D02*
X733071D01*
G01X724152Y197992D02*
X718228D01*
G01X724113Y197953D02*
X718228D01*
G01X723169Y197795D02*
X724154D01*
G01X723209Y197756D02*
X724114D01*
G01X738189Y196949D02*
X734252D01*
G01X737579Y196673D02*
X736594D01*
G01X736596Y196181D02*
X741929D01*
G01Y196142D02*
X737581D01*
G01X724606Y195787D02*
X721260D01*
G01X741929Y194803D02*
X736596D01*
G01X736594Y194311D02*
X737579D01*
G01Y191673D02*
X736594D01*
G01X736596Y191181D02*
X741929D01*
G01Y191142D02*
X737581D01*
G01X741929Y189803D02*
X736596D01*
G01X736594Y189311D02*
X737579D01*
G01Y186673D02*
X736594D01*
G01X736596Y186181D02*
X741929D01*
G01Y186142D02*
X737581D01*
G01X741929Y184803D02*
X736596D01*
G01X736594Y184311D02*
X737579D01*
G01Y181673D02*
X736594D01*
G01X736596Y181181D02*
X741929D01*
G01Y181142D02*
X737581D01*
G01X741929Y179803D02*
X736596D01*
G01X736594Y179311D02*
X737579D01*
G01Y176673D02*
X736594D01*
G01X736596Y176181D02*
X741929D01*
G01Y176142D02*
X737581D01*
G01X741929Y174803D02*
X736596D01*
G01X736594Y174311D02*
X737579D01*
G01Y171673D02*
X736594D01*
G01X736596Y171181D02*
X741929D01*
G01Y171142D02*
X737581D01*
G01X741929Y169803D02*
X736596D01*
G01X736594Y169311D02*
X737579D01*
G01X736594Y196377D02*
X737550Y196378D01*
G01X737579Y194607D02*
X736594Y194606D01*
G01Y191377D02*
X737550Y191378D01*
G01X737579Y189607D02*
X736594Y189606D01*
G01Y186377D02*
X737550Y186378D01*
G01X737579Y184607D02*
X736594Y184606D01*
G01Y181377D02*
X737550Y181378D01*
G01X737579Y179607D02*
X736594Y179606D01*
G01Y176377D02*
X737550Y176378D01*
G01X737579Y174607D02*
X736594Y174606D01*
G01Y171377D02*
X737550Y171378D01*
G01X737579Y169607D02*
X736594Y169606D01*
G01X737579Y166673D02*
X736594D01*
G01X736596Y166181D02*
X741929D01*
G01Y166142D02*
X737581D01*
G01X741929Y164803D02*
X736596D01*
G01X736594Y164311D02*
X737579D01*
G01X736594Y166377D02*
X737550Y166378D01*
G01X737579Y164607D02*
X736594Y164606D01*
G01X723169Y213731D02*
Y213727D01*
G01X723171Y213724D02*
X723169Y213731D01*
G01X723182Y213709D02*
X723171Y213724D01*
G01X723207Y213701D02*
X723182Y213709D01*
G01X724153Y213719D02*
X724154Y213727D01*
G01X724150Y213713D02*
X724153Y213719D01*
G01X724147Y213706D02*
X724150Y213713D01*
G01X724142Y213700D02*
X724147Y213706D01*
G01X724136Y213696D02*
X724142Y213700D01*
G01X724129Y213693D02*
X724136Y213696D01*
G01X724122Y213691D02*
X724129Y213693D01*
G01X724114Y213690D02*
X724122Y213691D01*
G01X723192Y214890D02*
X723189Y214888D01*
G01X723195Y214891D02*
X723192Y214890D01*
G01X723198Y214892D02*
X723195Y214891D01*
G01X723202Y214893D02*
X723198Y214892D01*
G01X723205Y214893D02*
X723202D01*
G01X723209D02*
X723205D01*
G01X724131Y216843D02*
X724134Y216844D01*
G01X724128Y216842D02*
X724131Y216843D01*
G01X724125Y216841D02*
X724128Y216842D01*
G01X724121Y216840D02*
X724125Y216841D01*
G01X724118Y216839D02*
X724121Y216840D01*
G01X724114Y216839D02*
X724118D01*
G01X723192Y218039D02*
X723189Y218038D01*
G01X723195Y218041D02*
X723192Y218039D01*
G01X723198Y218042D02*
X723195Y218041D01*
G01X723202Y218042D02*
X723198D01*
G01X723205Y218043D02*
X723202Y218042D01*
G01X723209Y218043D02*
X723205D01*
G01X724144Y214880D02*
X724148Y214875D01*
G01X724139Y214885D02*
X724144Y214880D01*
G01X724133Y214889D02*
X724139Y214885D01*
G01X724128Y214891D02*
X724133Y214889D01*
G01X724121Y214893D02*
X724128Y214891D01*
G01X724114Y214893D02*
X724121D01*
G01X724144Y218030D02*
X724148Y218025D01*
G01X724139Y218034D02*
X724144Y218030D01*
G01X724133Y218038D02*
X724139Y218034D01*
G01X724128Y218041D02*
X724133Y218038D01*
G01X724121Y218043D02*
X724128Y218041D01*
G01X724114Y218043D02*
X724121D01*
G01X723170Y213719D02*
X723169Y213727D01*
G01X723172Y213713D02*
X723170Y213719D01*
G01X723176Y213706D02*
X723172Y213713D01*
G01X723181Y213700D02*
X723176Y213706D01*
G01X723187Y213696D02*
X723181Y213700D01*
G01X723194Y213693D02*
X723187Y213696D01*
G01X723201Y213691D02*
X723194Y213693D01*
G01X723209Y213690D02*
X723201Y213691D01*
G01X723170Y216869D02*
X723169Y216876D01*
G01X723172Y216862D02*
X723170Y216869D01*
G01X723176Y216856D02*
X723172Y216862D01*
G01X723181Y216850D02*
X723176Y216856D01*
G01X723187Y216845D02*
X723181Y216850D01*
G01X723194Y216842D02*
X723187Y216845D01*
G01X723201Y216840D02*
X723194Y216842D01*
G01X723209Y216839D02*
X723201Y216840D01*
G01X724123Y214881D02*
X724133Y214876D01*
G01X724113Y214882D02*
X724123Y214881D01*
G01Y218030D02*
X724133Y218026D01*
G01X724113Y218031D02*
X724123Y218030D01*
G01X723169Y216880D02*
Y216876D01*
G01X723171Y216874D02*
X723169Y216880D01*
G01X723182Y216859D02*
X723171Y216874D01*
G01X723207Y216850D02*
X723182Y216859D01*
G01X737566Y221173D02*
X737577Y221157D01*
G01X737542Y221181D02*
X737566Y221173D01*
G01Y226173D02*
X737577Y226157D01*
G01X737542Y226181D02*
X737566Y226173D01*
G01Y231173D02*
X737577Y231157D01*
G01X737542Y231181D02*
X737566Y231173D01*
G01Y236173D02*
X737577Y236157D01*
G01X737542Y236181D02*
X737566Y236173D01*
G01Y241173D02*
X737577Y241157D01*
G01X737542Y241181D02*
X737566Y241173D01*
G01Y246173D02*
X737577Y246157D01*
G01X737542Y246181D02*
X737566Y246173D01*
G01Y251173D02*
X737577Y251157D01*
G01X737542Y251181D02*
X737566Y251173D01*
G01Y256173D02*
X737577Y256157D01*
G01X737542Y256181D02*
X737566Y256173D01*
G01X724122Y214881D02*
X724113Y214882D01*
G01X724131Y214878D02*
X724122Y214881D01*
G01X724139Y214872D02*
X724131Y214878D01*
G01X724122Y218030D02*
X724113Y218031D01*
G01X724131Y218027D02*
X724122Y218030D01*
G01X724139Y218022D02*
X724131Y218027D01*
G01X723208Y213696D02*
X723209Y213690D01*
G01X723207Y213700D02*
X723208Y213696D01*
G01X723206Y213701D02*
X723207Y213700D01*
G01X723208Y216846D02*
X723209Y216839D01*
G01X723207Y216849D02*
X723208Y216846D01*
G01X723206Y216850D02*
X723207Y216849D01*
G01X723172Y214862D02*
X723167Y214843D01*
G01X723187Y214877D02*
X723172Y214862D01*
G01X723206Y214882D02*
X723187Y214877D01*
G01X723172Y218012D02*
X723167Y217992D01*
G01X723187Y218026D02*
X723172Y218012D01*
G01X723206Y218031D02*
X723187Y218026D01*
G01X724147Y213720D02*
X724152Y213740D01*
G01X724132Y213706D02*
X724147Y213720D01*
G01X724113Y213701D02*
X724132Y213706D01*
G01X724147Y216870D02*
X724152Y216890D01*
G01X724132Y216856D02*
X724147Y216870D01*
G01X724113Y216850D02*
X724132Y216856D01*
G01X737579Y221148D02*
Y221156D01*
G01X737580Y221144D02*
X737579Y221148D01*
G01X737581Y221142D02*
X737580Y221144D01*
G01X737579Y226148D02*
Y226156D01*
G01X737580Y226144D02*
X737579Y226148D01*
G01X737581Y226142D02*
X737580Y226144D01*
G01X737579Y231148D02*
Y231156D01*
G01X737580Y231144D02*
X737579Y231148D01*
G01X737581Y231142D02*
X737580Y231144D01*
G01X737579Y236148D02*
Y236156D01*
G01X737580Y236144D02*
X737579Y236148D01*
G01X737581Y236142D02*
X737580Y236144D01*
G01X737579Y241148D02*
Y241156D01*
G01X737580Y241144D02*
X737579Y241148D01*
G01X737581Y241142D02*
X737580Y241144D01*
G01X737579Y246148D02*
Y246156D01*
G01X737580Y246144D02*
X737579Y246148D01*
G01X737581Y246142D02*
X737580Y246144D01*
G01X737579Y251148D02*
Y251156D01*
G01X737580Y251144D02*
X737579Y251148D01*
G01X737581Y251142D02*
X737580Y251144D01*
G01X737579Y256148D02*
Y256156D01*
G01X737580Y256144D02*
X737579Y256148D01*
G01X737581Y256142D02*
X737580Y256144D01*
G01X723192Y213704D02*
X723206Y213701D01*
G01X723180Y213711D02*
X723192Y213704D01*
G01X723168Y213731D02*
X723180Y213711D01*
G01X724154Y213734D02*
Y213727D01*
G01X724153Y213739D02*
X724154Y213734D01*
G01X724152Y213740D02*
X724153Y213739D01*
G01X724154Y216884D02*
Y216876D01*
G01X724153Y216889D02*
X724154Y216884D01*
G01X724152Y216890D02*
X724153Y216889D01*
G01X723192Y216853D02*
X723206Y216850D01*
G01X723179Y216861D02*
X723192Y216853D01*
G01X723168Y216881D02*
X723179Y216861D01*
G01X724153Y214863D02*
X724154Y214856D01*
G01X724151Y214869D02*
X724153Y214863D01*
G01X724148Y214875D02*
X724151Y214869D01*
G01X724153Y218013D02*
X724154Y218006D01*
G01X724151Y218019D02*
X724153Y218013D01*
G01X724148Y218025D02*
X724151Y218019D01*
G01X724115Y216845D02*
Y216839D01*
G01X724113Y216849D02*
X724115Y216845D01*
G01X724113Y216850D02*
Y216849D01*
G01X736594Y221189D02*
Y221198D01*
G01X736595Y221183D02*
X736594Y221189D01*
G01X736596Y221181D02*
X736595Y221183D01*
G01X736594Y226189D02*
Y226198D01*
G01X736595Y226183D02*
X736594Y226189D01*
G01X736596Y226181D02*
X736595Y226183D01*
G01X736594Y231189D02*
Y231198D01*
G01X736595Y231183D02*
X736594Y231189D01*
G01X736596Y231181D02*
X736595Y231183D01*
G01X736594Y236189D02*
Y236198D01*
G01X736595Y236183D02*
X736594Y236189D01*
G01X736596Y236181D02*
X736595Y236183D01*
G01X736594Y241189D02*
Y241198D01*
G01X736595Y241183D02*
X736594Y241189D01*
G01X736596Y241181D02*
X736595Y241183D01*
G01X736594Y246189D02*
Y246198D01*
G01X736595Y246183D02*
X736594Y246189D01*
G01X736596Y246181D02*
X736595Y246183D01*
G01X736594Y251189D02*
Y251198D01*
G01X736595Y251183D02*
X736594Y251189D01*
G01X736596Y251181D02*
X736595Y251183D01*
G01X736594Y256189D02*
Y256198D01*
G01X736595Y256183D02*
X736594Y256189D01*
G01X736596Y256181D02*
X736595Y256183D01*
G01X737571Y221325D02*
X737579Y221299D01*
G01X737561Y221352D02*
X737571Y221325D01*
G01X737550Y221378D02*
X737561Y221352D01*
G01X737571Y226325D02*
X737579Y226299D01*
G01X737561Y226352D02*
X737571Y226325D01*
G01X737550Y226378D02*
X737561Y226352D01*
G01X737571Y231325D02*
X737579Y231299D01*
G01X737561Y231352D02*
X737571Y231325D01*
G01X737550Y231378D02*
X737561Y231352D01*
G01X737571Y236325D02*
X737579Y236299D01*
G01X737561Y236352D02*
X737571Y236325D01*
G01X737550Y236378D02*
X737561Y236352D01*
G01X737571Y241325D02*
X737579Y241299D01*
G01X737561Y241352D02*
X737571Y241325D01*
G01X737550Y241378D02*
X737561Y241352D01*
G01X737571Y246325D02*
X737579Y246299D01*
G01X737561Y246352D02*
X737571Y246325D01*
G01X737550Y246378D02*
X737561Y246352D01*
G01X737571Y251325D02*
X737579Y251299D01*
G01X737561Y251352D02*
X737571Y251325D01*
G01X737550Y251378D02*
X737561Y251352D01*
G01X737571Y256325D02*
X737579Y256299D01*
G01X737561Y256352D02*
X737571Y256325D01*
G01X737550Y256378D02*
X737561Y256352D01*
G01Y221176D02*
X737542Y221181D01*
G01X737576Y221162D02*
X737561Y221176D01*
G01X737581Y221142D02*
X737576Y221162D01*
G01X737561Y226176D02*
X737542Y226181D01*
G01X737576Y226162D02*
X737561Y226176D01*
G01X737581Y226142D02*
X737576Y226162D01*
G01X737561Y231176D02*
X737542Y231181D01*
G01X737576Y231162D02*
X737561Y231176D01*
G01X737581Y231142D02*
X737576Y231162D01*
G01X737561Y236176D02*
X737542Y236181D01*
G01X737576Y236162D02*
X737561Y236176D01*
G01X737581Y236142D02*
X737576Y236162D01*
G01X737561Y241176D02*
X737542Y241181D01*
G01X737576Y241162D02*
X737561Y241176D01*
G01X737581Y241142D02*
X737576Y241162D01*
G01X737561Y246176D02*
X737542Y246181D01*
G01X737576Y246162D02*
X737561Y246176D01*
G01X737581Y246142D02*
X737576Y246162D01*
G01X737561Y251176D02*
X737542Y251181D01*
G01X737576Y251162D02*
X737561Y251176D01*
G01X737581Y251142D02*
X737576Y251162D01*
G01X737561Y256176D02*
X737542Y256181D01*
G01X737576Y256162D02*
X737561Y256176D01*
G01X737581Y256142D02*
X737576Y256162D01*
G01X737546Y221279D02*
X737550Y221378D01*
G01X737540Y221207D02*
X737546Y221279D01*
G01X737542Y221181D02*
X737540Y221207D01*
G01X737546Y226279D02*
X737550Y226378D01*
G01X737540Y226207D02*
X737546Y226279D01*
G01X737542Y226181D02*
X737540Y226207D01*
G01X737546Y231279D02*
X737550Y231378D01*
G01X737540Y231207D02*
X737546Y231279D01*
G01X737542Y231181D02*
X737540Y231207D01*
G01X737546Y236279D02*
X737550Y236378D01*
G01X737540Y236207D02*
X737546Y236279D01*
G01X737542Y236181D02*
X737540Y236207D01*
G01X737546Y241279D02*
X737550Y241378D01*
G01X737540Y241207D02*
X737546Y241279D01*
G01X737542Y241181D02*
X737540Y241207D01*
G01X737546Y246279D02*
X737550Y246378D01*
G01X737540Y246207D02*
X737546Y246279D01*
G01X737542Y246181D02*
X737540Y246207D01*
G01X737546Y251279D02*
X737550Y251378D01*
G01X737540Y251207D02*
X737546Y251279D01*
G01X737542Y251181D02*
X737540Y251207D01*
G01X737546Y256279D02*
X737550Y256378D01*
G01X737540Y256207D02*
X737546Y256279D01*
G01X737542Y256181D02*
X737540Y256207D01*
G01X724146Y214864D02*
X724139Y214872D01*
G01X724151Y214854D02*
X724146Y214864D01*
G01X724152Y214843D02*
X724151Y214854D01*
G01X724146Y218013D02*
X724139Y218022D01*
G01X724151Y218003D02*
X724146Y218013D01*
G01X724152Y217992D02*
X724151Y218003D01*
G01X723209Y218216D02*
Y218228D01*
G01X723206Y218203D02*
X723209Y218216D01*
G01X723206Y218189D02*
Y218203D01*
G01X723209Y215067D02*
Y215079D01*
G01X723206Y215054D02*
X723209Y215067D01*
G01X723206Y215040D02*
Y215054D01*
G01X736595Y259802D02*
X736596Y259803D01*
G01X736594Y259796D02*
X736595Y259802D01*
G01X736594Y259787D02*
Y259796D01*
G01X736595Y254802D02*
X736596Y254803D01*
G01X736594Y254796D02*
X736595Y254802D01*
G01X736594Y254787D02*
Y254796D01*
G01X736595Y249802D02*
X736596Y249803D01*
G01X736594Y249796D02*
X736595Y249802D01*
G01X736594Y249787D02*
Y249796D01*
G01X736595Y244802D02*
X736596Y244803D01*
G01X736594Y244796D02*
X736595Y244802D01*
G01X736594Y244787D02*
Y244796D01*
G01X736595Y239802D02*
X736596Y239803D01*
G01X736594Y239796D02*
X736595Y239802D01*
G01X736594Y239787D02*
Y239796D01*
G01X736595Y234802D02*
X736596Y234803D01*
G01X736594Y234796D02*
X736595Y234802D01*
G01X736594Y234787D02*
Y234796D01*
G01X736595Y229802D02*
X736596Y229803D01*
G01X736594Y229796D02*
X736595Y229802D01*
G01X736594Y229787D02*
Y229796D01*
G01X736595Y224802D02*
X736596Y224803D01*
G01X736594Y224796D02*
X736595Y224802D01*
G01X736594Y224787D02*
Y224796D01*
G01X736595Y219802D02*
X736596Y219803D01*
G01X736594Y219796D02*
X736595Y219802D01*
G01X736594Y219787D02*
Y219796D01*
G01X723169Y216884D02*
Y216876D01*
G01X723168Y216889D02*
X723169Y216884D01*
G01X723168Y216881D02*
Y216889D01*
G01X723206Y216679D02*
X723205Y216693D01*
G01X723209Y216666D02*
X723206Y216679D01*
G01X723209Y216654D02*
Y216666D01*
G01X723206Y213530D02*
X723205Y213543D01*
G01X723209Y213517D02*
X723206Y213530D01*
G01X723209Y213504D02*
Y213517D01*
G01X724117Y218203D02*
X724118Y218189D01*
G01X724113Y218216D02*
X724117Y218203D01*
G01X724114Y218228D02*
X724113Y218216D01*
G01X724117Y215053D02*
X724118Y215040D01*
G01X724113Y215066D02*
X724117Y215053D01*
G01X724114Y215079D02*
X724113Y215066D01*
G01X723169Y213734D02*
Y213727D01*
G01X723168Y213739D02*
X723169Y213734D01*
G01X723168Y213732D02*
Y213739D01*
G01X724113Y216666D02*
X724114Y216654D01*
G01X724116Y216679D02*
X724113Y216666D01*
G01X724117Y216693D02*
X724116Y216679D01*
G01X724113Y213517D02*
X724114Y213504D01*
G01X724116Y213530D02*
X724113Y213517D01*
G01X724117Y213543D02*
X724116Y213530D01*
G01X723182Y218023D02*
X723206Y218031D01*
G01X723171Y218009D02*
X723182Y218023D01*
G01X723169Y218002D02*
X723171Y218009D01*
G01X723182Y214874D02*
X723206Y214882D01*
G01X723171Y214859D02*
X723182Y214874D01*
G01X723169Y214852D02*
X723171Y214859D01*
G01X724154Y217998D02*
Y218006D01*
G01X724153Y217994D02*
X724154Y217998D01*
G01X724152Y217992D02*
X724153Y217994D01*
G01X724154Y214849D02*
Y214856D01*
G01X724153Y214844D02*
X724154Y214849D01*
G01X724152Y214843D02*
X724153Y214844D01*
G01X724114Y218037D02*
Y218043D01*
G01X724113Y218033D02*
X724114Y218037D01*
G01X724113Y218031D02*
Y218033D01*
G01X724114Y214887D02*
Y214893D01*
G01X724113Y214883D02*
X724114Y214887D01*
G01X724113Y214882D02*
Y214883D01*
G01X737579Y259796D02*
Y259787D01*
G01X737580Y259802D02*
X737579Y259796D01*
G01X737581Y259803D02*
X737580Y259802D01*
G01X737579Y254796D02*
Y254787D01*
G01X737580Y254802D02*
X737579Y254796D01*
G01X737581Y254803D02*
X737580Y254802D01*
G01X737579Y249796D02*
Y249787D01*
G01X737580Y249802D02*
X737579Y249796D01*
G01X737581Y249803D02*
X737580Y249802D01*
G01X737579Y244796D02*
Y244787D01*
G01X737580Y244802D02*
X737579Y244796D01*
G01X737581Y244803D02*
X737580Y244802D01*
G01X737579Y239796D02*
Y239787D01*
G01X737580Y239802D02*
X737579Y239796D01*
G01X737581Y239803D02*
X737580Y239802D01*
G01X737579Y234796D02*
Y234787D01*
G01X737580Y234802D02*
X737579Y234796D01*
G01X737581Y234803D02*
X737580Y234802D01*
G01X737579Y229796D02*
Y229787D01*
G01X737580Y229802D02*
X737579Y229796D01*
G01X737581Y229803D02*
X737580Y229802D01*
G01X737579Y224796D02*
Y224787D01*
G01X737580Y224802D02*
X737579Y224796D01*
G01X737581Y224803D02*
X737580Y224802D01*
G01X737579Y219796D02*
Y219787D01*
G01X737580Y219802D02*
X737579Y219796D01*
G01X737581Y219803D02*
X737580Y219802D01*
G01X723169Y217998D02*
Y218006D01*
G01X723168Y217994D02*
X723169Y217998D01*
G01X723167Y217992D02*
X723168Y217994D01*
G01X723169Y214849D02*
Y214856D01*
G01X723168Y214844D02*
X723169Y214849D01*
G01X723167Y214843D02*
X723168Y214844D01*
G01X724151Y216864D02*
X724154Y216876D01*
G01X724144Y216853D02*
X724151Y216864D01*
G01X724134Y216844D02*
X724144Y216853D01*
G01X723208Y218037D02*
Y218043D01*
G01Y218033D02*
Y218037D01*
G01X723206Y218031D02*
X723208Y218033D01*
G01Y214887D02*
Y214893D01*
G01Y214883D02*
Y214887D01*
G01X723206Y214882D02*
X723208Y214883D01*
G01X723170Y218012D02*
X723169Y218006D01*
G01X723172Y218019D02*
X723170Y218012D01*
G01X723174Y218024D02*
X723172Y218019D01*
G01X723178Y218030D02*
X723174Y218024D01*
G01X723183Y218034D02*
X723178Y218030D01*
G01X723189Y218038D02*
X723183Y218034D01*
G01X723170Y214863D02*
X723169Y214856D01*
G01X723172Y214869D02*
X723170Y214863D01*
G01X723174Y214874D02*
X723172Y214869D01*
G01X723178Y214880D02*
X723174Y214874D01*
G01X723183Y214884D02*
X723178Y214880D01*
G01X723189Y214888D02*
X723183Y214884D01*
G01X724125Y216852D02*
X724113Y216850D01*
G01X724135Y216857D02*
X724125Y216852D01*
G01Y213703D02*
X724113Y213701D01*
G01X724135Y213708D02*
X724125Y213703D01*
G01X737008Y217854D02*
X738189Y219035D01*
G01X733071Y217854D02*
X734252Y219035D01*
G01X724153Y214845D02*
X724154Y214856D01*
G01X724153Y217994D02*
X724154Y218006D01*
G01X737579Y221155D02*
Y221164D01*
G01Y226155D02*
Y226164D01*
G01Y231155D02*
Y231164D01*
G01Y236155D02*
Y236164D01*
G01Y241155D02*
Y241164D01*
G01Y246155D02*
Y246164D01*
G01Y251155D02*
Y251164D01*
G01Y256155D02*
Y256164D01*
G01X741929Y259803D02*
Y261181D01*
G01Y254803D02*
Y256181D01*
G01Y249803D02*
Y251181D01*
G01Y244803D02*
Y246181D01*
G01Y239803D02*
Y241181D01*
G01Y234803D02*
Y236181D01*
G01Y229803D02*
Y231181D01*
G01Y224803D02*
Y226181D01*
G01Y219803D02*
Y221181D01*
G01X738760D02*
Y219803D01*
G01Y226181D02*
Y224803D01*
G01Y231181D02*
Y229803D01*
G01Y236181D02*
Y234803D01*
G01Y241181D02*
Y239803D01*
G01Y246181D02*
Y244803D01*
G01Y251181D02*
Y249803D01*
G01Y256181D02*
Y254803D01*
G01Y261181D02*
Y259803D01*
G01X737579Y221156D02*
Y221299D01*
G01Y226156D02*
Y226299D01*
G01Y231156D02*
Y231299D01*
G01Y236156D02*
Y236299D01*
G01Y241156D02*
Y241299D01*
G01Y246156D02*
Y246299D01*
G01Y251156D02*
Y251299D01*
G01Y256156D02*
Y256299D01*
G01Y259311D02*
Y261673D01*
G01Y254311D02*
Y256673D01*
G01Y249311D02*
Y251673D01*
G01Y244311D02*
Y246673D01*
G01Y239311D02*
Y241673D01*
G01Y234311D02*
Y236673D01*
G01Y229311D02*
Y231673D01*
G01Y224311D02*
Y226673D01*
G01Y219311D02*
Y221673D01*
G01X736594D02*
Y219311D01*
G01Y226673D02*
Y224311D01*
G01Y231673D02*
Y229311D01*
G01Y236673D02*
Y234311D01*
G01Y241673D02*
Y239311D01*
G01Y246673D02*
Y244311D01*
G01Y251673D02*
Y249311D01*
G01Y256673D02*
Y254311D01*
G01Y261673D02*
Y259311D01*
G01X734252Y295492D02*
Y219035D01*
G01X733071Y294311D02*
Y217854D01*
G01X724606Y299232D02*
Y220197D01*
G01X724154Y216693D02*
Y218189D01*
G01Y213543D02*
Y215039D01*
G01X724114Y216839D02*
Y216693D01*
G01Y213690D02*
Y213543D01*
G01Y215040D02*
Y214893D01*
G01Y218189D02*
Y218043D01*
G01X723209D02*
Y218190D01*
G01Y216692D02*
Y216839D01*
G01Y213543D02*
Y213690D01*
G01Y214893D02*
Y215040D01*
G01X723169Y215039D02*
Y213543D01*
G01Y218189D02*
Y216693D01*
G01X721988Y218031D02*
Y216850D01*
G01Y214882D02*
Y213701D01*
G01X718228Y216850D02*
Y218031D01*
G01Y213701D02*
Y214882D01*
G01X724154Y216876D02*
X724153Y216887D01*
G01X724154Y213727D02*
X724153Y213738D01*
G01X724113Y213701D02*
X724116Y213690D01*
G01X741929Y259803D02*
X736596D01*
G01X736594Y259311D02*
X737579D01*
G01Y256673D02*
X736594D01*
G01X737579Y259607D02*
X736594Y259606D01*
G01Y256377D02*
X737550Y256378D01*
G01X723056Y216890D02*
X723168Y216881D01*
G01X736596Y256181D02*
X741929D01*
G01Y256142D02*
X737581D01*
G01X741929Y254803D02*
X736596D01*
G01X736594Y254311D02*
X737579D01*
G01Y251673D02*
X736594D01*
G01X736596Y251181D02*
X741929D01*
G01Y251142D02*
X737581D01*
G01X741929Y249803D02*
X736596D01*
G01X736594Y249311D02*
X737579D01*
G01Y246673D02*
X736594D01*
G01X736596Y246181D02*
X741929D01*
G01Y246142D02*
X737581D01*
G01X741929Y244803D02*
X736596D01*
G01X736594Y244311D02*
X737579D01*
G01Y241673D02*
X736594D01*
G01X736596Y241181D02*
X741929D01*
G01Y241142D02*
X737581D01*
G01X741929Y239803D02*
X736596D01*
G01X736594Y239311D02*
X737579D01*
G01Y236673D02*
X736594D01*
G01X736596Y236181D02*
X741929D01*
G01Y236142D02*
X737581D01*
G01X741929Y234803D02*
X736596D01*
G01X736594Y234311D02*
X737579D01*
G01Y231673D02*
X736594D01*
G01X736596Y231181D02*
X741929D01*
G01Y231142D02*
X737581D01*
G01X741929Y229803D02*
X736596D01*
G01X736594Y229311D02*
X737579D01*
G01Y226673D02*
X736594D01*
G01X736596Y226181D02*
X741929D01*
G01Y226142D02*
X737581D01*
G01X741929Y224803D02*
X736596D01*
G01X736594Y224311D02*
X737579D01*
G01Y221673D02*
X736594D01*
G01X736596Y221181D02*
X741929D01*
G01Y221142D02*
X737581D01*
G01X724606Y220197D02*
X721260D01*
G01X741929Y219803D02*
X736596D01*
G01X736594Y219311D02*
X737579D01*
G01X734252Y219035D02*
X738189D01*
G01X724114Y218228D02*
X723209D01*
G01X724154Y218189D02*
X723169D01*
G01X724113Y218031D02*
X718228D01*
G01Y217992D02*
X724152D01*
G01X733071Y217854D02*
X737008D01*
G01X724152Y216890D02*
X718228D01*
G01X724113Y216850D02*
X718228D01*
G01X723169Y216693D02*
X724154D01*
G01X723209Y216654D02*
X724114D01*
G01Y215079D02*
X723209D01*
G01X724154Y215039D02*
X723169D01*
G01X724113Y214882D02*
X718228D01*
G01Y214843D02*
X724152D01*
G01Y213740D02*
X718228D01*
G01X724113Y213701D02*
X718228D01*
G01X723169Y213543D02*
X724154D01*
G01X723209Y213504D02*
X724114D01*
G01X737579Y254607D02*
X736594Y254606D01*
G01Y251377D02*
X737550Y251378D01*
G01X737579Y249607D02*
X736594Y249606D01*
G01Y246377D02*
X737550Y246378D01*
G01X737579Y244607D02*
X736594Y244606D01*
G01Y241377D02*
X737550Y241378D01*
G01X737579Y239607D02*
X736594Y239606D01*
G01Y236377D02*
X737550Y236378D01*
G01X737579Y234607D02*
X736594Y234606D01*
G01Y231377D02*
X737550Y231378D01*
G01X737579Y229607D02*
X736594Y229606D01*
G01Y226377D02*
X737550Y226378D01*
G01X737579Y224607D02*
X736594Y224606D01*
G01Y221377D02*
X737550Y221378D01*
G01X737579Y219607D02*
X736594Y219606D01*
G01X737566Y261173D02*
X737577Y261157D01*
G01X737542Y261181D02*
X737566Y261173D01*
G01Y266173D02*
X737577Y266157D01*
G01X737542Y266181D02*
X737566Y266173D01*
G01Y271173D02*
X737577Y271157D01*
G01X737542Y271181D02*
X737566Y271173D01*
G01Y276173D02*
X737577Y276157D01*
G01X737542Y276181D02*
X737566Y276173D01*
G01Y281173D02*
X737577Y281157D01*
G01X737542Y281181D02*
X737566Y281173D01*
G01Y286173D02*
X737577Y286157D01*
G01X737542Y286181D02*
X737566Y286173D01*
G01Y291173D02*
X737577Y291157D01*
G01X737542Y291181D02*
X737566Y291173D01*
G01X737579Y261148D02*
Y261156D01*
G01X737580Y261144D02*
X737579Y261148D01*
G01X737581Y261142D02*
X737580Y261144D01*
G01X737579Y266148D02*
Y266156D01*
G01X737580Y266144D02*
X737579Y266148D01*
G01X737581Y266142D02*
X737580Y266144D01*
G01X737579Y271148D02*
Y271156D01*
G01X737580Y271144D02*
X737579Y271148D01*
G01X737581Y271142D02*
X737580Y271144D01*
G01X737579Y276148D02*
Y276156D01*
G01X737580Y276144D02*
X737579Y276148D01*
G01X737581Y276142D02*
X737580Y276144D01*
G01X737579Y281148D02*
Y281156D01*
G01X737580Y281144D02*
X737579Y281148D01*
G01X737581Y281142D02*
X737580Y281144D01*
G01X737579Y286148D02*
Y286156D01*
G01X737580Y286144D02*
X737579Y286148D01*
G01X737581Y286142D02*
X737580Y286144D01*
G01X737579Y291148D02*
Y291156D01*
G01X737580Y291144D02*
X737579Y291148D01*
G01X737581Y291142D02*
X737580Y291144D01*
G01X736594Y261189D02*
Y261198D01*
G01X736595Y261183D02*
X736594Y261189D01*
G01X736596Y261181D02*
X736595Y261183D01*
G01X736594Y266189D02*
Y266198D01*
G01X736595Y266183D02*
X736594Y266189D01*
G01X736596Y266181D02*
X736595Y266183D01*
G01X736594Y271189D02*
Y271198D01*
G01X736595Y271183D02*
X736594Y271189D01*
G01X736596Y271181D02*
X736595Y271183D01*
G01X736594Y276189D02*
Y276198D01*
G01X736595Y276183D02*
X736594Y276189D01*
G01X736596Y276181D02*
X736595Y276183D01*
G01X736594Y281189D02*
Y281198D01*
G01X736595Y281183D02*
X736594Y281189D01*
G01X736596Y281181D02*
X736595Y281183D01*
G01X736594Y286189D02*
Y286198D01*
G01X736595Y286183D02*
X736594Y286189D01*
G01X736596Y286181D02*
X736595Y286183D01*
G01X736594Y291189D02*
Y291198D01*
G01X736595Y291183D02*
X736594Y291189D01*
G01X736596Y291181D02*
X736595Y291183D01*
G01X737571Y261325D02*
X737579Y261299D01*
G01X737561Y261352D02*
X737571Y261325D01*
G01X737550Y261378D02*
X737561Y261352D01*
G01X737571Y266325D02*
X737579Y266299D01*
G01X737561Y266352D02*
X737571Y266325D01*
G01X737550Y266378D02*
X737561Y266352D01*
G01X737571Y271325D02*
X737579Y271299D01*
G01X737561Y271352D02*
X737571Y271325D01*
G01X737550Y271378D02*
X737561Y271352D01*
G01X737571Y276325D02*
X737579Y276299D01*
G01X737561Y276352D02*
X737571Y276325D01*
G01X737550Y276378D02*
X737561Y276352D01*
G01X737571Y281325D02*
X737579Y281299D01*
G01X737561Y281352D02*
X737571Y281325D01*
G01X737550Y281378D02*
X737561Y281352D01*
G01X737571Y286325D02*
X737579Y286299D01*
G01X737561Y286352D02*
X737571Y286325D01*
G01X737550Y286378D02*
X737561Y286352D01*
G01X737571Y291325D02*
X737579Y291299D01*
G01X737561Y291352D02*
X737571Y291325D01*
G01X737550Y291378D02*
X737561Y291352D01*
G01Y261176D02*
X737542Y261181D01*
G01X737576Y261162D02*
X737561Y261176D01*
G01X737581Y261142D02*
X737576Y261162D01*
G01X737561Y266176D02*
X737542Y266181D01*
G01X737576Y266162D02*
X737561Y266176D01*
G01X737581Y266142D02*
X737576Y266162D01*
G01X737561Y271176D02*
X737542Y271181D01*
G01X737576Y271162D02*
X737561Y271176D01*
G01X737581Y271142D02*
X737576Y271162D01*
G01X737561Y276176D02*
X737542Y276181D01*
G01X737576Y276162D02*
X737561Y276176D01*
G01X737581Y276142D02*
X737576Y276162D01*
G01X737561Y281176D02*
X737542Y281181D01*
G01X737576Y281162D02*
X737561Y281176D01*
G01X737581Y281142D02*
X737576Y281162D01*
G01X737561Y286176D02*
X737542Y286181D01*
G01X737576Y286162D02*
X737561Y286176D01*
G01X737581Y286142D02*
X737576Y286162D01*
G01X737561Y291176D02*
X737542Y291181D01*
G01X737576Y291162D02*
X737561Y291176D01*
G01X737581Y291142D02*
X737576Y291162D01*
G01X737546Y261279D02*
X737550Y261378D01*
G01X737540Y261207D02*
X737546Y261279D01*
G01X737542Y261181D02*
X737540Y261207D01*
G01X737546Y266279D02*
X737550Y266378D01*
G01X737540Y266207D02*
X737546Y266279D01*
G01X737542Y266181D02*
X737540Y266207D01*
G01X737546Y271279D02*
X737550Y271378D01*
G01X737540Y271207D02*
X737546Y271279D01*
G01X737542Y271181D02*
X737540Y271207D01*
G01X737546Y276279D02*
X737550Y276378D01*
G01X737540Y276207D02*
X737546Y276279D01*
G01X737542Y276181D02*
X737540Y276207D01*
G01X737546Y281279D02*
X737550Y281378D01*
G01X737540Y281207D02*
X737546Y281279D01*
G01X737542Y281181D02*
X737540Y281207D01*
G01X737546Y286279D02*
X737550Y286378D01*
G01X737540Y286207D02*
X737546Y286279D01*
G01X737542Y286181D02*
X737540Y286207D01*
G01X737546Y291279D02*
X737550Y291378D01*
G01X737540Y291207D02*
X737546Y291279D01*
G01X737542Y291181D02*
X737540Y291207D01*
G01X736595Y289802D02*
X736596Y289803D01*
G01X736594Y289796D02*
X736595Y289802D01*
G01X736594Y289787D02*
Y289796D01*
G01X736595Y284802D02*
X736596Y284803D01*
G01X736594Y284796D02*
X736595Y284802D01*
G01X736594Y284787D02*
Y284796D01*
G01X736595Y279802D02*
X736596Y279803D01*
G01X736594Y279796D02*
X736595Y279802D01*
G01X736594Y279787D02*
Y279796D01*
G01X736595Y274802D02*
X736596Y274803D01*
G01X736594Y274796D02*
X736595Y274802D01*
G01X736594Y274787D02*
Y274796D01*
G01X736595Y269802D02*
X736596Y269803D01*
G01X736594Y269796D02*
X736595Y269802D01*
G01X736594Y269787D02*
Y269796D01*
G01X736595Y264802D02*
X736596Y264803D01*
G01X736594Y264796D02*
X736595Y264802D01*
G01X736594Y264787D02*
Y264796D01*
G01X737579Y289796D02*
Y289787D01*
G01X737580Y289802D02*
X737579Y289796D01*
G01X737581Y289803D02*
X737580Y289802D01*
G01X737579Y284796D02*
Y284787D01*
G01X737580Y284802D02*
X737579Y284796D01*
G01X737581Y284803D02*
X737580Y284802D01*
G01X737579Y279796D02*
Y279787D01*
G01X737580Y279802D02*
X737579Y279796D01*
G01X737581Y279803D02*
X737580Y279802D01*
G01X737579Y274796D02*
Y274787D01*
G01X737580Y274802D02*
X737579Y274796D01*
G01X737581Y274803D02*
X737580Y274802D01*
G01X737579Y269796D02*
Y269787D01*
G01X737580Y269802D02*
X737579Y269796D01*
G01X737581Y269803D02*
X737580Y269802D01*
G01X737579Y264796D02*
Y264787D01*
G01X737580Y264802D02*
X737579Y264796D01*
G01X737581Y264803D02*
X737580Y264802D01*
G01X729528Y307579D02*
G03X728346Y306398I-1J-1181D01*
G01X735827D02*
G03X734646Y307579I-1181J0D01*
G01X733976Y302303D02*
G03I-1889J0D01*
G01X734449D02*
G03I-2362J0D01*
G01X742913Y300335D02*
X739567Y296988D01*
G01X733071Y294311D02*
X734252Y295492D01*
G01X729602Y299232D02*
X730906Y301201D01*
G01X735578Y307123D02*
X733268Y302894D01*
G01X737579Y261155D02*
Y261164D01*
G01Y266155D02*
Y266164D01*
G01Y271155D02*
Y271164D01*
G01Y276155D02*
Y276164D01*
G01Y281155D02*
Y281164D01*
G01Y286155D02*
Y286164D01*
G01Y291155D02*
Y291164D01*
G01X742913Y300335D02*
Y316083D01*
G01X741929Y289803D02*
Y291181D01*
G01Y284803D02*
Y286181D01*
G01Y279803D02*
Y281181D01*
G01Y274803D02*
Y276181D01*
G01Y269803D02*
Y271181D01*
G01Y264803D02*
Y266181D01*
G01X738760D02*
Y264803D01*
G01Y271181D02*
Y269803D01*
G01Y276181D02*
Y274803D01*
G01Y281181D02*
Y279803D01*
G01Y286181D02*
Y284803D01*
G01Y291181D02*
Y289803D01*
G01X737579Y261156D02*
Y261299D01*
G01Y266156D02*
Y266299D01*
G01Y271156D02*
Y271299D01*
G01Y276156D02*
Y276299D01*
G01Y281156D02*
Y281299D01*
G01Y286156D02*
Y286299D01*
G01Y291156D02*
Y291299D01*
G01Y289311D02*
Y291673D01*
G01Y284311D02*
Y286673D01*
G01Y279311D02*
Y281673D01*
G01Y274311D02*
Y276673D01*
G01Y269311D02*
Y271673D01*
G01Y264311D02*
Y266673D01*
G01X736594D02*
Y264311D01*
G01Y271673D02*
Y269311D01*
G01Y276673D02*
Y274311D01*
G01Y281673D02*
Y279311D01*
G01Y286673D02*
Y284311D01*
G01Y291673D02*
Y289311D01*
G01X735827Y306398D02*
Y297854D01*
G01X733268Y302894D02*
Y301201D01*
G01X730906D02*
Y302894D01*
G01X728346Y297854D02*
Y306398D01*
G01X721260Y316083D02*
Y300335D01*
G01X730906Y302894D02*
X728595Y307123D01*
G01X733268Y301201D02*
X734571Y299232D01*
G01X726378Y295492D02*
X727559Y294311D01*
G01X721260Y300335D02*
X724606Y296988D01*
G01X742913Y307618D02*
X721260D01*
G01X729528Y307579D02*
X734646D01*
G01X730906Y302894D02*
X733268D01*
G01X730906Y301201D02*
X733268D01*
G01X724606Y299232D02*
X738976D01*
G01X724606Y297854D02*
X728346D01*
G01X738976D02*
X735827D01*
G01X724606Y296988D02*
X739567D01*
G01X726378Y295492D02*
X734252D01*
G01X727559Y294311D02*
X733071D01*
G01X737579Y291673D02*
X736594D01*
G01X736596Y291181D02*
X741929D01*
G01Y291142D02*
X737581D01*
G01X741929Y289803D02*
X736596D01*
G01X736594Y289311D02*
X737579D01*
G01Y286673D02*
X736594D01*
G01X736596Y286181D02*
X741929D01*
G01Y286142D02*
X737581D01*
G01X741929Y284803D02*
X736596D01*
G01X736594Y284311D02*
X737579D01*
G01Y281673D02*
X736594D01*
G01X736596Y281181D02*
X741929D01*
G01Y281142D02*
X737581D01*
G01X741929Y279803D02*
X736596D01*
G01X736594Y279311D02*
X737579D01*
G01Y276673D02*
X736594D01*
G01X736596Y276181D02*
X741929D01*
G01Y276142D02*
X737581D01*
G01X741929Y274803D02*
X736596D01*
G01X736594Y274311D02*
X737579D01*
G01Y271673D02*
X736594D01*
G01X736596Y271181D02*
X741929D01*
G01Y271142D02*
X737581D01*
G01X741929Y269803D02*
X736596D01*
G01X736594Y269311D02*
X737579D01*
G01Y266673D02*
X736594D01*
G01X736596Y266181D02*
X741929D01*
G01Y266142D02*
X737581D01*
G01X741929Y264803D02*
X736596D01*
G01X736594Y264311D02*
X737579D01*
G01Y261673D02*
X736594D01*
G01X736596Y261181D02*
X741929D01*
G01Y261142D02*
X737581D01*
G01X736594Y291377D02*
X737550Y291378D01*
G01X737579Y289607D02*
X736594Y289606D01*
G01Y286377D02*
X737550Y286378D01*
G01X737579Y284607D02*
X736594Y284606D01*
G01Y281377D02*
X737550Y281378D01*
G01X737579Y279607D02*
X736594Y279606D01*
G01Y276377D02*
X737550Y276378D01*
G01X737579Y274607D02*
X736594Y274606D01*
G01Y271377D02*
X737550Y271378D01*
G01X737579Y269607D02*
X736594Y269606D01*
G01Y266377D02*
X737550Y266378D01*
G01X737579Y264607D02*
X736594Y264606D01*
G01Y261377D02*
X737550Y261378D01*
G01X736024Y316673D02*
G03X735433Y317264I-591J0D01*
G01X728740D02*
G03X728150Y316673I0J-590D01*
G01X730906Y315492D02*
G03Y313524I0J-984D01*
G01X733268D02*
G03Y315492I0J984D01*
G01X742913Y316083D02*
G03X740945Y318051I-1968J0D01*
G01X723228D02*
G03X721260Y316083I0J-1968D01*
G01X736024Y310571D02*
Y316673D01*
G01X728150Y310571D02*
Y316673D01*
G01X740945Y318051D02*
X723228D01*
G01X735433Y317264D02*
X728740D01*
G01X733268Y315492D02*
X730906D01*
G01Y313524D02*
X733268D01*
G01X736024Y312146D02*
X728150D01*
G01Y310571D02*
X736024D01*
G01X728150Y592067D02*
G03X728740Y591476I591J0D01*
G01X735433D02*
G03X736024Y592067I0J591D01*
G01X733268Y593248D02*
G03Y595217I0J985D01*
G01X730906D02*
G03Y593248I0J-985D01*
G01X721260Y592657D02*
G03X723228Y590689I1968J0D01*
G01X740945D02*
G03X742913Y592657I0J1968D01*
G01X736024Y598169D02*
X728150D01*
G01Y596594D02*
X736024D01*
G01X733268Y595217D02*
X730906D01*
G01Y593248D02*
X733268D01*
G01X735433Y591476D02*
X728740D01*
G01X740945Y590689D02*
X723228D01*
G01X742913Y592657D02*
Y608406D01*
G01X736024Y598169D02*
Y592067D01*
G01X728150Y598169D02*
Y592067D01*
G01X721260Y608406D02*
Y592657D01*
G01X737579Y618904D02*
Y618911D01*
G01X737580Y618900D02*
X737579Y618904D01*
G01X737581Y618898D02*
X737580Y618900D01*
G01X737579Y623904D02*
Y623911D01*
G01X737580Y623900D02*
X737579Y623904D01*
G01X737581Y623898D02*
X737580Y623900D01*
G01X737579Y628904D02*
Y628911D01*
G01X737580Y628900D02*
X737579Y628904D01*
G01X737581Y628898D02*
X737580Y628900D01*
G01X737579Y633904D02*
Y633911D01*
G01X737580Y633900D02*
X737579Y633904D01*
G01X737581Y633898D02*
X737580Y633900D01*
G01X737579Y638904D02*
Y638911D01*
G01X737580Y638900D02*
X737579Y638904D01*
G01X737581Y638898D02*
X737580Y638900D01*
G01X737579Y643904D02*
Y643911D01*
G01X737580Y643900D02*
X737579Y643904D01*
G01X737581Y643898D02*
X737580Y643900D01*
G01X736594Y618944D02*
Y618954D01*
G01X736595Y618939D02*
X736594Y618944D01*
G01X736596Y618937D02*
X736595Y618939D01*
G01X736594Y623944D02*
Y623954D01*
G01X736595Y623939D02*
X736594Y623944D01*
G01X736596Y623937D02*
X736595Y623939D01*
G01X736594Y628944D02*
Y628954D01*
G01X736595Y628939D02*
X736594Y628944D01*
G01X736596Y628937D02*
X736595Y628939D01*
G01X736594Y633944D02*
Y633954D01*
G01X736595Y633939D02*
X736594Y633944D01*
G01X736596Y633937D02*
X736595Y633939D01*
G01X736594Y638944D02*
Y638954D01*
G01X736595Y638939D02*
X736594Y638944D01*
G01X736596Y638937D02*
X736595Y638939D01*
G01X736594Y643944D02*
Y643954D01*
G01X736595Y643939D02*
X736594Y643944D01*
G01X736596Y643937D02*
X736595Y643939D01*
G01X737571Y619081D02*
X737579Y619055D01*
G01X737561Y619107D02*
X737571Y619081D01*
G01X737550Y619134D02*
X737561Y619107D01*
G01X737571Y624081D02*
X737579Y624055D01*
G01X737561Y624107D02*
X737571Y624081D01*
G01X737550Y624134D02*
X737561Y624107D01*
G01X737571Y629081D02*
X737579Y629055D01*
G01X737561Y629107D02*
X737571Y629081D01*
G01X737550Y629134D02*
X737561Y629107D01*
G01X737571Y634081D02*
X737579Y634055D01*
G01X737561Y634107D02*
X737571Y634081D01*
G01X737550Y634134D02*
X737561Y634107D01*
G01X737571Y639081D02*
X737579Y639055D01*
G01X737561Y639107D02*
X737571Y639081D01*
G01X737550Y639134D02*
X737561Y639107D01*
G01X737571Y644081D02*
X737579Y644055D01*
G01X737561Y644107D02*
X737571Y644081D01*
G01X737550Y644134D02*
X737561Y644107D01*
G01Y618932D02*
X737542Y618937D01*
G01X737576Y618918D02*
X737561Y618932D01*
G01X737581Y618898D02*
X737576Y618918D01*
G01X737561Y623932D02*
X737542Y623937D01*
G01X737576Y623918D02*
X737561Y623932D01*
G01X737581Y623898D02*
X737576Y623918D01*
G01X737561Y628932D02*
X737542Y628937D01*
G01X737576Y628918D02*
X737561Y628932D01*
G01X737581Y628898D02*
X737576Y628918D01*
G01X737561Y633932D02*
X737542Y633937D01*
G01X737576Y633918D02*
X737561Y633932D01*
G01X737581Y633898D02*
X737576Y633918D01*
G01X737561Y638932D02*
X737542Y638937D01*
G01X737576Y638918D02*
X737561Y638932D01*
G01X737581Y638898D02*
X737576Y638918D01*
G01X737561Y643932D02*
X737542Y643937D01*
G01X737576Y643918D02*
X737561Y643932D01*
G01X737581Y643898D02*
X737576Y643918D01*
G01X737546Y619035D02*
X737550Y619134D01*
G01X737540Y618963D02*
X737546Y619035D01*
G01X737542Y618937D02*
X737540Y618963D01*
G01X737546Y624035D02*
X737550Y624134D01*
G01X737540Y623963D02*
X737546Y624035D01*
G01X737542Y623937D02*
X737540Y623963D01*
G01X737546Y629035D02*
X737550Y629134D01*
G01X737540Y628963D02*
X737546Y629035D01*
G01X737542Y628937D02*
X737540Y628963D01*
G01X737546Y634035D02*
X737550Y634134D01*
G01X737540Y633963D02*
X737546Y634035D01*
G01X737542Y633937D02*
X737540Y633963D01*
G01X737546Y639035D02*
X737550Y639134D01*
G01X737540Y638963D02*
X737546Y639035D01*
G01X737542Y638937D02*
X737540Y638963D01*
G01X737546Y644035D02*
X737550Y644134D01*
G01X737540Y643963D02*
X737546Y644035D01*
G01X737542Y643937D02*
X737540Y643963D01*
G01X736595Y647557D02*
X736596Y647559D01*
G01X736594Y647552D02*
X736595Y647557D01*
G01X736594Y647543D02*
Y647552D01*
G01X736595Y642557D02*
X736596Y642559D01*
G01X736594Y642552D02*
X736595Y642557D01*
G01X736594Y642543D02*
Y642552D01*
G01X736595Y637557D02*
X736596Y637559D01*
G01X736594Y637552D02*
X736595Y637557D01*
G01X736594Y637543D02*
Y637552D01*
G01X736595Y632557D02*
X736596Y632559D01*
G01X736594Y632552D02*
X736595Y632557D01*
G01X736594Y632543D02*
Y632552D01*
G01X736595Y627557D02*
X736596Y627559D01*
G01X736594Y627552D02*
X736595Y627557D01*
G01X736594Y627543D02*
Y627552D01*
G01X736595Y622557D02*
X736596Y622559D01*
G01X736594Y622552D02*
X736595Y622557D01*
G01X736594Y622543D02*
Y622552D01*
G01X736595Y617557D02*
X736596Y617559D01*
G01X736594Y617552D02*
X736595Y617557D01*
G01X736594Y617543D02*
Y617552D01*
G01X737566Y618929D02*
X737577Y618913D01*
G01X737542Y618937D02*
X737566Y618929D01*
G01Y623929D02*
X737577Y623913D01*
G01X737542Y623937D02*
X737566Y623929D01*
G01Y628929D02*
X737577Y628913D01*
G01X737542Y628937D02*
X737566Y628929D01*
G01Y633929D02*
X737577Y633913D01*
G01X737542Y633937D02*
X737566Y633929D01*
G01Y638929D02*
X737577Y638913D01*
G01X737542Y638937D02*
X737566Y638929D01*
G01Y643929D02*
X737577Y643913D01*
G01X737542Y643937D02*
X737566Y643929D01*
G01X737579Y647552D02*
Y647543D01*
G01X737580Y647557D02*
X737579Y647552D01*
G01X737581Y647559D02*
X737580Y647557D01*
G01X737579Y642552D02*
Y642543D01*
G01X737580Y642557D02*
X737579Y642552D01*
G01X737581Y642559D02*
X737580Y642557D01*
G01X737579Y637552D02*
Y637543D01*
G01X737580Y637557D02*
X737579Y637552D01*
G01X737581Y637559D02*
X737580Y637557D01*
G01X737579Y632552D02*
Y632543D01*
G01X737580Y632557D02*
X737579Y632552D01*
G01X737581Y632559D02*
X737580Y632557D01*
G01X737579Y627552D02*
Y627543D01*
G01X737580Y627557D02*
X737579Y627552D01*
G01X737581Y627559D02*
X737580Y627557D01*
G01X737579Y622552D02*
Y622543D01*
G01X737580Y622557D02*
X737579Y622552D01*
G01X737581Y622559D02*
X737580Y622557D01*
G01X737579Y617552D02*
Y617543D01*
G01X737580Y617557D02*
X737579Y617552D01*
G01X737581Y617559D02*
X737580Y617557D01*
G01X733189Y606437D02*
G03I-1102J0D01*
G01X734646Y601161D02*
G03X735827Y602343I0J1181D01*
G01X728346D02*
G03X729528Y601161I1181J-1D01*
G01X733661Y606437D02*
G03I-1574J0D01*
G01X727559Y614429D02*
X726378Y613248D01*
G01X724606Y611752D02*
X721260Y608406D01*
G01X741929Y647559D02*
X736596D01*
G01X736594Y647067D02*
X737579D01*
G01Y644429D02*
X736594D01*
G01X736596Y643937D02*
X741929D01*
G01Y643898D02*
X737581D01*
G01X741929Y642559D02*
X736596D01*
G01X736594Y642067D02*
X737579D01*
G01Y639429D02*
X736594D01*
G01X736596Y638937D02*
X741929D01*
G01Y638898D02*
X737581D01*
G01X741929Y637559D02*
X736596D01*
G01X736594Y637067D02*
X737579D01*
G01Y634429D02*
X736594D01*
G01X736596Y633937D02*
X741929D01*
G01Y633898D02*
X737581D01*
G01X741929Y632559D02*
X736596D01*
G01X736594Y632067D02*
X737579D01*
G01Y629429D02*
X736594D01*
G01X736596Y628937D02*
X741929D01*
G01Y628898D02*
X737581D01*
G01X741929Y627559D02*
X736596D01*
G01X736594Y627067D02*
X737579D01*
G01Y624429D02*
X736594D01*
G01X736596Y623937D02*
X741929D01*
G01Y623898D02*
X737581D01*
G01X741929Y622559D02*
X736596D01*
G01X736594Y622067D02*
X737579D01*
G01Y619429D02*
X736594D01*
G01X736596Y618937D02*
X741929D01*
G01Y618898D02*
X737581D01*
G01X741929Y617559D02*
X736596D01*
G01X736594Y617067D02*
X737579D01*
G01Y647363D02*
X736594Y647362D01*
G01Y644133D02*
X737550Y644134D01*
G01X737579Y642363D02*
X736594Y642362D01*
G01Y639133D02*
X737550Y639134D01*
G01X737579Y637363D02*
X736594Y637362D01*
G01Y634133D02*
X737550Y634134D01*
G01X737579Y632363D02*
X736594Y632362D01*
G01Y629133D02*
X737550Y629134D01*
G01X737579Y627363D02*
X736594Y627362D01*
G01Y624133D02*
X737550Y624134D01*
G01X737579Y622363D02*
X736594Y622362D01*
G01Y619133D02*
X737550Y619134D01*
G01X737579Y617363D02*
X736594Y617362D01*
G01X734571Y609508D02*
X733268Y607539D01*
G01X728595Y601617D02*
X730906Y605846D01*
G01X733071Y614429D02*
X727559D01*
G01X734252Y613248D02*
X726378D01*
G01X739567Y611752D02*
X724606D01*
G01X735827Y610886D02*
X738976D01*
G01X728346D02*
X724606D01*
G01Y609508D02*
X738976D01*
G01X733268Y607539D02*
X730906D01*
G01X733268Y605846D02*
X730906D01*
G01X734646Y601161D02*
X729528D01*
G01X742913Y601122D02*
X721260D01*
G01X737579Y618911D02*
Y618920D01*
G01Y623911D02*
Y623920D01*
G01Y628911D02*
Y628920D01*
G01Y633911D02*
Y633920D01*
G01Y638911D02*
Y638920D01*
G01Y643911D02*
Y643920D01*
G01X741929Y647559D02*
Y648937D01*
G01Y642559D02*
Y643937D01*
G01Y637559D02*
Y638937D01*
G01Y632559D02*
Y633937D01*
G01Y627559D02*
Y628937D01*
G01Y622559D02*
Y623937D01*
G01Y617559D02*
Y618937D01*
G01X739567Y749744D02*
Y611752D01*
G01X738976Y751988D02*
Y609508D01*
G01X738760Y618937D02*
Y617559D01*
G01Y623937D02*
Y622559D01*
G01Y628937D02*
Y627559D01*
G01Y633937D02*
Y632559D01*
G01Y638937D02*
Y637559D01*
G01Y643937D02*
Y642559D01*
G01Y648937D02*
Y647559D01*
G01X737579Y647067D02*
Y649429D01*
G01Y642067D02*
Y644429D01*
G01Y637067D02*
Y639429D01*
G01Y632067D02*
Y634429D01*
G01Y627067D02*
Y629429D01*
G01Y622067D02*
Y624429D01*
G01Y617067D02*
Y619429D01*
G01X736594D02*
Y617067D01*
G01Y624429D02*
Y622067D01*
G01Y629429D02*
Y627067D01*
G01Y634429D02*
Y632067D01*
G01Y639429D02*
Y637067D01*
G01Y644429D02*
Y642067D01*
G01Y649429D02*
Y647067D01*
G01X735827Y610886D02*
Y602343D01*
G01X734252Y649705D02*
Y613248D01*
G01X733268Y607539D02*
Y605846D01*
G01X733071Y650886D02*
Y614429D01*
G01X730906Y605846D02*
Y607539D01*
G01X728346Y602343D02*
Y610886D01*
G01X727559Y614429D02*
Y747067D01*
G01X726378Y613248D02*
Y748248D01*
G01X724606Y648543D02*
Y609508D01*
G01X733268Y605846D02*
X735578Y601617D01*
G01X730906Y607539D02*
X729602Y609508D01*
G01X739567Y611752D02*
X742913Y608406D01*
G01X733071Y614429D02*
X734252Y613248D01*
G01X723208Y650704D02*
X723209Y650698D01*
G01X723207Y650707D02*
X723208Y650704D01*
G01X723206Y650709D02*
X723207Y650707D01*
G01X723208Y653854D02*
X723209Y653847D01*
G01X723207Y653857D02*
X723208Y653854D01*
G01X723206Y653858D02*
X723207Y653857D01*
G01X737579Y648904D02*
Y648911D01*
G01X737580Y648900D02*
X737579Y648904D01*
G01X737581Y648898D02*
X737580Y648900D01*
G01X723192Y653861D02*
X723206Y653858D01*
G01X723181Y653868D02*
X723192Y653861D01*
G01X723169Y653887D02*
X723181Y653868D01*
G01X723192Y663310D02*
X723206Y663307D01*
G01X723180Y663317D02*
X723192Y663310D01*
G01X723169Y663335D02*
X723180Y663317D01*
G01X723192Y657011D02*
X723206Y657008D01*
G01X723180Y657019D02*
X723192Y657011D01*
G01X723168Y657039D02*
X723180Y657019D01*
G01X723192Y666459D02*
X723206Y666457D01*
G01X723180Y666467D02*
X723192Y666459D01*
G01X723168Y666487D02*
X723180Y666467D01*
G01X724154Y650742D02*
Y650735D01*
G01X724153Y650747D02*
X724154Y650742D01*
G01X724152Y650748D02*
X724153Y650747D01*
G01X724154Y653892D02*
Y653884D01*
G01X724153Y653896D02*
X724154Y653892D01*
G01X724152Y653898D02*
X724153Y653896D01*
G01X724154Y657041D02*
Y657034D01*
G01X724153Y657046D02*
X724154Y657041D01*
G01X724152Y657047D02*
X724153Y657046D01*
G01X724154Y660191D02*
Y660183D01*
G01X724153Y660196D02*
X724154Y660191D01*
G01X724152Y660197D02*
X724153Y660196D01*
G01X724154Y663341D02*
Y663333D01*
G01X724153Y663345D02*
X724154Y663341D01*
G01X724152Y663346D02*
X724153Y663345D01*
G01X724154Y666490D02*
Y666483D01*
G01X724153Y666495D02*
X724154Y666490D01*
G01X724152Y666496D02*
X724153Y666495D01*
G01X724154Y669640D02*
Y669632D01*
G01X724153Y669644D02*
X724154Y669640D01*
G01X724152Y669646D02*
X724153Y669644D01*
G01X723192Y669609D02*
X723206Y669606D01*
G01X723179Y669617D02*
X723192Y669609D01*
G01X723168Y669637D02*
X723179Y669617D01*
G01X723191Y650712D02*
X723206Y650709D01*
G01X723178Y650720D02*
X723191Y650712D01*
G01X723168Y650741D02*
X723178Y650720D01*
G01X724153Y651871D02*
X724154Y651864D01*
G01X724151Y651877D02*
X724153Y651871D01*
G01X724148Y651883D02*
X724151Y651877D01*
G01X724153Y655020D02*
X724154Y655014D01*
G01X724151Y655027D02*
X724153Y655020D01*
G01X724148Y655033D02*
X724151Y655027D01*
G01X724153Y658170D02*
X724154Y658163D01*
G01X724151Y658176D02*
X724153Y658170D01*
G01X724148Y658182D02*
X724151Y658176D01*
G01X724153Y661320D02*
X724154Y661313D01*
G01X724151Y661326D02*
X724153Y661320D01*
G01X724148Y661332D02*
X724151Y661326D01*
G01X724153Y664469D02*
X724154Y664463D01*
G01X724151Y664476D02*
X724153Y664469D01*
G01X724148Y664481D02*
X724151Y664476D01*
G01X724153Y667619D02*
X724154Y667612D01*
G01X724151Y667625D02*
X724153Y667619D01*
G01X724148Y667631D02*
X724151Y667625D01*
G01X724153Y670769D02*
X724154Y670762D01*
G01X724151Y670775D02*
X724153Y670769D01*
G01X724148Y670781D02*
X724151Y670775D01*
G01X724115Y650704D02*
Y650698D01*
G01X724113Y650707D02*
X724115Y650704D01*
G01X724113Y650709D02*
Y650707D01*
G01X724115Y653853D02*
Y653847D01*
G01X724113Y653857D02*
X724115Y653853D01*
G01X724113Y653858D02*
Y653857D01*
G01X724115Y657003D02*
Y656997D01*
G01X724113Y657007D02*
X724115Y657003D01*
G01X724113Y657008D02*
Y657007D01*
G01X724115Y660152D02*
Y660146D01*
G01X724113Y660156D02*
X724115Y660152D01*
G01X724113Y660157D02*
Y660156D01*
G01X724115Y663302D02*
Y663296D01*
G01X724113Y663306D02*
X724115Y663302D01*
G01X724113Y663307D02*
Y663306D01*
G01X724115Y669601D02*
Y669595D01*
G01X724113Y669605D02*
X724115Y669601D01*
G01X724113Y669606D02*
Y669605D01*
G01X736594Y648944D02*
Y648954D01*
G01X736595Y648939D02*
X736594Y648944D01*
G01X736596Y648937D02*
X736595Y648939D01*
G01X737571Y649081D02*
X737579Y649055D01*
G01X737561Y649107D02*
X737571Y649081D01*
G01X737550Y649134D02*
X737561Y649107D01*
G01X723187Y660163D02*
X723206Y660157D01*
G01X723174Y660175D02*
X723187Y660163D01*
G01X723167Y660193D02*
X723174Y660175D01*
G01X724146Y658171D02*
X724139Y658180D01*
G01X724150Y658161D02*
X724146Y658171D01*
G01X724152Y658150D02*
X724150Y658161D01*
G01X724146Y651872D02*
X724139Y651880D01*
G01X724151Y651861D02*
X724146Y651872D01*
G01X724152Y651850D02*
X724151Y651861D01*
G01X724146Y655021D02*
X724139Y655030D01*
G01X724151Y655011D02*
X724146Y655021D01*
G01X724152Y655000D02*
X724151Y655011D01*
G01X724146Y661320D02*
X724139Y661329D01*
G01X724151Y661310D02*
X724146Y661320D01*
G01X724152Y661299D02*
X724151Y661310D01*
G01X724146Y664470D02*
X724139Y664479D01*
G01X724151Y664460D02*
X724146Y664470D01*
G01X724152Y664449D02*
X724151Y664460D01*
G01X724146Y667620D02*
X724139Y667628D01*
G01X724151Y667609D02*
X724146Y667620D01*
G01X724152Y667598D02*
X724151Y667609D01*
G01X737546Y649035D02*
X737550Y649134D01*
G01X737540Y648963D02*
X737546Y649035D01*
G01X737542Y648937D02*
X737540Y648963D01*
G01X737546Y674035D02*
X737550Y674134D01*
G01X737540Y673963D02*
X737546Y674035D01*
G01X737542Y673937D02*
X737540Y673963D01*
G01X737546Y679035D02*
X737550Y679134D01*
G01X737540Y678963D02*
X737546Y679035D01*
G01X737542Y678937D02*
X737540Y678963D01*
G01X737546Y684035D02*
X737550Y684134D01*
G01X737540Y683963D02*
X737546Y684035D01*
G01X737542Y683937D02*
X737540Y683963D01*
G01X737546Y689035D02*
X737550Y689134D01*
G01X737540Y688963D02*
X737546Y689035D01*
G01X737542Y688937D02*
X737540Y688963D01*
G01X737546Y694035D02*
X737550Y694134D01*
G01X737540Y693963D02*
X737546Y694035D01*
G01X737542Y693937D02*
X737540Y693963D01*
G01X723169Y663341D02*
Y663333D01*
G01X723168Y663345D02*
X723169Y663341D01*
G01Y663336D02*
X723168Y663345D01*
G01X723209Y670972D02*
Y670984D01*
G01X723206Y670959D02*
X723209Y670972D01*
G01X723206Y670945D02*
Y670959D01*
G01X723209Y667822D02*
Y667835D01*
G01X723206Y667809D02*
X723209Y667822D01*
G01X723206Y667796D02*
Y667809D01*
G01X723209Y664673D02*
Y664685D01*
G01X723206Y664660D02*
X723209Y664673D01*
G01X723206Y664646D02*
Y664660D01*
G01X723209Y661523D02*
Y661535D01*
G01X723206Y661510D02*
X723209Y661523D01*
G01X723206Y661496D02*
Y661510D01*
G01X723209Y658374D02*
Y658386D01*
G01X723206Y658361D02*
X723209Y658374D01*
G01X723206Y658347D02*
Y658361D01*
G01X723209Y655224D02*
Y655236D01*
G01X723206Y655211D02*
X723209Y655224D01*
G01X723206Y655197D02*
Y655211D01*
G01X723209Y652074D02*
Y652087D01*
G01X723206Y652061D02*
X723209Y652074D01*
G01X723206Y652048D02*
Y652061D01*
G01X736595Y692557D02*
X736596Y692559D01*
G01X736594Y692552D02*
X736595Y692557D01*
G01X736594Y692543D02*
Y692552D01*
G01X736595Y687557D02*
X736596Y687559D01*
G01X736594Y687552D02*
X736595Y687557D01*
G01X736594Y687543D02*
Y687552D01*
G01X736595Y682557D02*
X736596Y682559D01*
G01X736594Y682552D02*
X736595Y682557D01*
G01X736594Y682543D02*
Y682552D01*
G01X736595Y677557D02*
X736596Y677559D01*
G01X736594Y677552D02*
X736595Y677557D01*
G01X736594Y677543D02*
Y677552D01*
G01X736595Y672557D02*
X736596Y672559D01*
G01X736594Y672552D02*
X736595Y672557D01*
G01X736594Y672543D02*
Y672552D01*
G01X723169Y669640D02*
Y669632D01*
G01X723168Y669644D02*
X723169Y669640D01*
G01X723168Y669637D02*
Y669644D01*
G01X723206Y669435D02*
X723205Y669448D01*
G01X723209Y669422D02*
X723206Y669435D01*
G01X723209Y669409D02*
Y669422D01*
G01X723206Y666285D02*
X723205Y666299D01*
G01X723209Y666272D02*
X723206Y666285D01*
G01X723209Y666260D02*
Y666272D01*
G01X723206Y663136D02*
X723205Y663149D01*
G01X723209Y663123D02*
X723206Y663136D01*
G01X723209Y663110D02*
Y663123D01*
G01X723206Y659986D02*
X723205Y660000D01*
G01X723209Y659973D02*
X723206Y659986D01*
G01X723209Y659961D02*
Y659973D01*
G01X723206Y656837D02*
X723205Y656850D01*
G01X723209Y656824D02*
X723206Y656837D01*
G01X723209Y656811D02*
Y656824D01*
G01X723206Y653687D02*
X723205Y653700D01*
G01X723209Y653674D02*
X723206Y653687D01*
G01X723209Y653661D02*
Y653674D01*
G01X723206Y650537D02*
X723205Y650551D01*
G01X723209Y650524D02*
X723206Y650537D01*
G01X723209Y650512D02*
Y650524D01*
G01X724117Y670959D02*
X724118Y670945D01*
G01X724113Y670972D02*
X724117Y670959D01*
G01X724114Y670984D02*
X724113Y670972D01*
G01X724117Y667809D02*
X724118Y667796D01*
G01X724113Y667822D02*
X724117Y667809D01*
G01X724114Y667835D02*
X724113Y667822D01*
G01X724117Y664659D02*
X724118Y664646D01*
G01X724113Y664672D02*
X724117Y664659D01*
G01X724114Y664685D02*
X724113Y664672D01*
G01X724117Y661510D02*
X724118Y661496D01*
G01X724113Y661523D02*
X724117Y661510D01*
G01X724114Y661535D02*
X724113Y661523D01*
G01X724117Y658360D02*
X724118Y658347D01*
G01X724113Y658373D02*
X724117Y658360D01*
G01X724114Y658386D02*
X724113Y658373D01*
G01X724117Y655211D02*
X724118Y655197D01*
G01X724113Y655224D02*
X724117Y655211D01*
G01X724114Y655236D02*
X724113Y655224D01*
G01X724117Y652061D02*
X724118Y652048D01*
G01X724113Y652074D02*
X724117Y652061D01*
G01X724114Y652087D02*
X724113Y652074D01*
G01X723169Y657041D02*
Y657034D01*
G01X723168Y657046D02*
X723169Y657041D01*
G01X723168Y657039D02*
Y657046D01*
G01X723169Y666490D02*
Y666483D01*
G01X723168Y666495D02*
X723169Y666490D01*
G01X723168Y666488D02*
Y666495D01*
G01X724113Y669422D02*
X724114Y669409D01*
G01X724116Y669435D02*
X724113Y669422D01*
G01X724117Y669448D02*
X724116Y669435D01*
G01X724113Y666272D02*
X724114Y666260D01*
G01X724116Y666285D02*
X724113Y666272D01*
G01X724117Y666299D02*
X724116Y666285D01*
G01X724113Y663123D02*
X724114Y663110D01*
G01X724116Y663136D02*
X724113Y663123D01*
G01X724117Y663149D02*
X724116Y663136D01*
G01X724113Y659973D02*
X724114Y659961D01*
G01X724116Y659986D02*
X724113Y659973D01*
G01X724117Y660000D02*
X724116Y659986D01*
G01X724113Y656824D02*
X724114Y656811D01*
G01X724116Y656837D02*
X724113Y656824D01*
G01X724117Y656850D02*
X724116Y656837D01*
G01X724113Y653674D02*
X724114Y653661D01*
G01X724116Y653687D02*
X724113Y653674D01*
G01X724117Y653700D02*
X724116Y653687D01*
G01X724113Y650524D02*
X724114Y650512D01*
G01X724116Y650537D02*
X724113Y650524D01*
G01X724117Y650551D02*
X724116Y650537D01*
G01X723169Y650743D02*
Y650735D01*
G01X723168Y650747D02*
X723169Y650743D01*
G01X723168Y650741D02*
Y650747D01*
G01X723182Y670779D02*
X723206Y670787D01*
G01X723171Y670765D02*
X723182Y670779D01*
G01X723169Y670758D02*
X723171Y670765D01*
G01X723182Y667630D02*
X723206Y667638D01*
G01X723171Y667615D02*
X723182Y667630D01*
G01X723169Y667608D02*
X723171Y667615D01*
G01X723182Y664480D02*
X723206Y664488D01*
G01X723171Y664465D02*
X723182Y664480D01*
G01X723169Y664459D02*
X723171Y664465D01*
G01X723182Y661330D02*
X723206Y661339D01*
G01X723171Y661316D02*
X723182Y661330D01*
G01X723169Y661309D02*
X723171Y661316D01*
G01X723182Y658181D02*
X723206Y658189D01*
G01X723171Y658166D02*
X723182Y658181D01*
G01X723169Y658159D02*
X723171Y658166D01*
G01X723182Y655031D02*
X723206Y655039D01*
G01X723171Y655017D02*
X723182Y655031D01*
G01X723169Y655010D02*
X723171Y655017D01*
G01X723182Y651881D02*
X723206Y651890D01*
G01X723171Y651867D02*
X723182Y651881D01*
G01X723169Y651860D02*
X723171Y651867D01*
G01X724154Y670754D02*
Y670761D01*
G01X724153Y670750D02*
X724154Y670754D01*
G01X724152Y670748D02*
X724153Y670750D01*
G01X724154Y667605D02*
Y667612D01*
G01X724153Y667600D02*
X724154Y667605D01*
G01X724152Y667598D02*
X724153Y667600D01*
G01X724154Y664455D02*
Y664462D01*
G01X724153Y664451D02*
X724154Y664455D01*
G01X724152Y664449D02*
X724153Y664451D01*
G01X724154Y661306D02*
Y661313D01*
G01X724153Y661301D02*
X724154Y661306D01*
G01X724152Y661299D02*
X724153Y661301D01*
G01X724154Y658156D02*
Y658163D01*
G01X724153Y658152D02*
X724154Y658156D01*
G01X724152Y658150D02*
X724153Y658152D01*
G01X724154Y655006D02*
Y655013D01*
G01X724153Y655002D02*
X724154Y655006D01*
G01X724152Y655000D02*
X724153Y655002D01*
G01X724154Y651857D02*
Y651864D01*
G01X724153Y651852D02*
X724154Y651857D01*
G01X724152Y651850D02*
X724153Y651852D01*
G01X723169Y660191D02*
Y660183D01*
G01X723168Y660196D02*
X723169Y660191D01*
G01X723167Y660193D02*
X723168Y660196D01*
G01X723169Y653888D02*
Y653884D01*
G01X723171Y653882D02*
X723169Y653888D01*
G01X723183Y653867D02*
X723171Y653882D01*
G01X723207Y653858D02*
X723183Y653867D01*
G01X723169Y657038D02*
Y657034D01*
G01X723171Y657031D02*
X723169Y657038D01*
G01X723182Y657016D02*
X723171Y657031D01*
G01X723207Y657008D02*
X723182Y657016D01*
G01X723169Y663337D02*
Y663333D01*
G01X723171Y663331D02*
X723169Y663337D01*
G01X723182Y663315D02*
X723171Y663331D01*
G01X723207Y663307D02*
X723182Y663315D01*
G01X723169Y666487D02*
Y666483D01*
G01X723171Y666480D02*
X723169Y666487D01*
G01X723182Y666465D02*
X723171Y666480D01*
G01X723207Y666457D02*
X723182Y666465D01*
G01X723169Y650739D02*
Y650735D01*
G01X723171Y650732D02*
X723169Y650739D01*
G01X723182Y650717D02*
X723171Y650732D01*
G01X723207Y650709D02*
X723182Y650717D01*
G01X723169Y669636D02*
Y669632D01*
G01X723171Y669630D02*
X723169Y669636D01*
G01X723182Y669615D02*
X723171Y669630D01*
G01X723207Y669606D02*
X723182Y669615D01*
G01X737566Y648929D02*
X737577Y648913D01*
G01X737542Y648937D02*
X737566Y648929D01*
G01Y673929D02*
X737577Y673913D01*
G01X737542Y673937D02*
X737566Y673929D01*
G01Y678929D02*
X737577Y678913D01*
G01X737542Y678937D02*
X737566Y678929D01*
G01Y683929D02*
X737577Y683913D01*
G01X737542Y683937D02*
X737566Y683929D01*
G01X723169Y660187D02*
Y660183D01*
G01X723170Y660182D02*
X723169Y660187D01*
G01X723181Y660167D02*
X723170Y660182D01*
G01X723204Y660158D02*
X723181Y660167D01*
G01X724122Y658188D02*
X724113Y658189D01*
G01X724131Y658185D02*
X724122Y658188D01*
G01X724139Y658180D02*
X724131Y658185D01*
G01X724122Y651889D02*
X724113Y651890D01*
G01X724131Y651885D02*
X724122Y651889D01*
G01X724139Y651880D02*
X724131Y651885D01*
G01X724122Y655038D02*
X724113Y655039D01*
G01X724131Y655035D02*
X724122Y655038D01*
G01X724139Y655030D02*
X724131Y655035D01*
G01X724122Y661337D02*
X724113Y661339D01*
G01X724131Y661334D02*
X724122Y661337D01*
G01X724139Y661329D02*
X724131Y661334D01*
G01X724122Y664487D02*
X724113Y664488D01*
G01X724131Y664484D02*
X724122Y664487D01*
G01X724139Y664479D02*
X724131Y664484D01*
G01X724122Y667637D02*
X724113Y667638D01*
G01X724131Y667633D02*
X724122Y667637D01*
G01X724139Y667628D02*
X724131Y667633D01*
G01X724122Y670786D02*
X724113Y670787D01*
G01X724131Y670783D02*
X724122Y670786D01*
G01X724139Y670778D02*
X724131Y670783D01*
G01X723208Y657003D02*
X723209Y656997D01*
G01X723207Y657007D02*
X723208Y657003D01*
G01X723206Y657008D02*
X723207Y657007D01*
G01X723208Y660153D02*
X723209Y660146D01*
G01X723207Y660156D02*
X723208Y660153D01*
G01X723206Y660157D02*
X723207Y660156D01*
G01X723208Y663302D02*
X723209Y663296D01*
G01X723207Y663306D02*
X723208Y663302D01*
G01X723206Y663307D02*
X723207Y663306D01*
G01X723208Y666452D02*
X723209Y666446D01*
G01X723207Y666456D02*
X723208Y666452D01*
G01X723206Y666457D02*
X723207Y666456D01*
G01X723208Y669602D02*
X723209Y669595D01*
G01X723207Y669605D02*
X723208Y669602D01*
G01X723206Y669606D02*
X723207Y669605D01*
G01X737579Y673904D02*
Y673911D01*
G01X737580Y673900D02*
X737579Y673904D01*
G01X737581Y673898D02*
X737580Y673900D01*
G01X737579Y678904D02*
Y678911D01*
G01X737580Y678900D02*
X737579Y678904D01*
G01X737581Y678898D02*
X737580Y678900D01*
G01X737579Y683904D02*
Y683911D01*
G01X737580Y683900D02*
X737579Y683904D01*
G01X737581Y683898D02*
X737580Y683900D01*
G01X737579Y688904D02*
Y688911D01*
G01X737580Y688900D02*
X737579Y688904D01*
G01X737581Y688898D02*
X737580Y688900D01*
G01X737579Y693904D02*
Y693911D01*
G01X737580Y693900D02*
X737579Y693904D01*
G01X737581Y693898D02*
X737580Y693900D01*
G01X736594Y673944D02*
Y673954D01*
G01X736595Y673939D02*
X736594Y673944D01*
G01X736596Y673937D02*
X736595Y673939D01*
G01X736594Y678944D02*
Y678954D01*
G01X736595Y678939D02*
X736594Y678944D01*
G01X736596Y678937D02*
X736595Y678939D01*
G01X736594Y683944D02*
Y683954D01*
G01X736595Y683939D02*
X736594Y683944D01*
G01X736596Y683937D02*
X736595Y683939D01*
G01X736594Y688944D02*
Y688954D01*
G01X736595Y688939D02*
X736594Y688944D01*
G01X736596Y688937D02*
X736595Y688939D01*
G01X736594Y693944D02*
Y693954D01*
G01X736595Y693939D02*
X736594Y693944D01*
G01X736596Y693937D02*
X736595Y693939D01*
G01X737571Y674081D02*
X737579Y674055D01*
G01X737561Y674107D02*
X737571Y674081D01*
G01X737550Y674134D02*
X737561Y674107D01*
G01X737571Y679081D02*
X737579Y679055D01*
G01X737561Y679107D02*
X737571Y679081D01*
G01X737550Y679134D02*
X737561Y679107D01*
G01X737571Y684081D02*
X737579Y684055D01*
G01X737561Y684107D02*
X737571Y684081D01*
G01X737550Y684134D02*
X737561Y684107D01*
G01X737571Y689081D02*
X737579Y689055D01*
G01X737561Y689107D02*
X737571Y689081D01*
G01X737550Y689134D02*
X737561Y689107D01*
G01X737571Y694081D02*
X737579Y694055D01*
G01X737561Y694107D02*
X737571Y694081D01*
G01X737550Y694134D02*
X737561Y694107D01*
G01Y648932D02*
X737542Y648937D01*
G01X737576Y648918D02*
X737561Y648932D01*
G01X737581Y648898D02*
X737576Y648918D01*
G01X737561Y673932D02*
X737542Y673937D01*
G01X737576Y673918D02*
X737561Y673932D01*
G01X737581Y673898D02*
X737576Y673918D01*
G01X737561Y678932D02*
X737542Y678937D01*
G01X737576Y678918D02*
X737561Y678932D01*
G01X737581Y678898D02*
X737576Y678918D01*
G01X737561Y683932D02*
X737542Y683937D01*
G01X737576Y683918D02*
X737561Y683932D01*
G01X737581Y683898D02*
X737576Y683918D01*
G01X737561Y688932D02*
X737542Y688937D01*
G01X737576Y688918D02*
X737561Y688932D01*
G01X737581Y688898D02*
X737576Y688918D01*
G01X737561Y693932D02*
X737542Y693937D01*
G01X737576Y693918D02*
X737561Y693932D01*
G01X737581Y693898D02*
X737576Y693918D01*
G01X724146Y670769D02*
X724139Y670778D01*
G01X724151Y670759D02*
X724146Y670769D01*
G01X724152Y670748D02*
X724151Y670759D01*
G01X723169Y653892D02*
Y653884D01*
G01X723168Y653896D02*
X723169Y653892D01*
G01X723167Y653894D02*
X723168Y653896D01*
G01X724114Y670793D02*
Y670799D01*
G01X724113Y670789D02*
X724114Y670793D01*
G01X724113Y670787D02*
Y670789D01*
G01X724114Y667643D02*
Y667649D01*
G01X724113Y667639D02*
X724114Y667643D01*
G01X724113Y667638D02*
Y667639D01*
G01X724114Y664493D02*
Y664500D01*
G01X724113Y664490D02*
X724114Y664493D01*
G01X724113Y664488D02*
Y664490D01*
G01X724114Y661344D02*
Y661350D01*
G01X724113Y661340D02*
X724114Y661344D01*
G01X724113Y661339D02*
Y661340D01*
G01X724114Y658194D02*
Y658200D01*
G01X724113Y658191D02*
X724114Y658194D01*
G01X724113Y658189D02*
Y658191D01*
G01X724114Y655044D02*
Y655051D01*
G01X724113Y655041D02*
X724114Y655044D01*
G01X724113Y655039D02*
Y655041D01*
G01X724114Y651895D02*
Y651901D01*
G01X724113Y651891D02*
X724114Y651895D01*
G01X724113Y651890D02*
Y651891D01*
G01X737579Y692552D02*
Y692543D01*
G01X737580Y692557D02*
X737579Y692552D01*
G01X737581Y692559D02*
X737580Y692557D01*
G01X737579Y687552D02*
Y687543D01*
G01X737580Y687557D02*
X737579Y687552D01*
G01X737581Y687559D02*
X737580Y687557D01*
G01X737579Y682552D02*
Y682543D01*
G01X737580Y682557D02*
X737579Y682552D01*
G01X737581Y682559D02*
X737580Y682557D01*
G01X737579Y677552D02*
Y677543D01*
G01X737580Y677557D02*
X737579Y677552D01*
G01X737581Y677559D02*
X737580Y677557D01*
G01X737579Y672552D02*
Y672543D01*
G01X737580Y672557D02*
X737579Y672552D01*
G01X737581Y672559D02*
X737580Y672557D01*
G01X723169Y670754D02*
Y670762D01*
G01X723168Y670750D02*
X723169Y670754D01*
G01X723167Y670748D02*
X723168Y670750D01*
G01X723169Y667605D02*
Y667612D01*
G01X723168Y667600D02*
X723169Y667605D01*
G01X723167Y667598D02*
X723168Y667600D01*
G01X723169Y664455D02*
Y664463D01*
G01X723168Y664450D02*
X723169Y664455D01*
G01X723167Y664449D02*
X723168Y664450D01*
G01X723169Y661306D02*
Y661313D01*
G01X723168Y661301D02*
X723169Y661306D01*
G01X723167Y661299D02*
X723168Y661301D01*
G01X723169Y658156D02*
Y658163D01*
G01X723168Y658151D02*
X723169Y658156D01*
G01X723167Y658150D02*
X723168Y658151D01*
G01X723169Y655006D02*
Y655014D01*
G01X723168Y655002D02*
X723169Y655006D01*
G01X723167Y655000D02*
X723168Y655002D01*
G01X723169Y651857D02*
Y651864D01*
G01X723168Y651852D02*
X723169Y651857D01*
G01X723167Y651850D02*
X723168Y651852D01*
G01X724153Y666475D02*
X724154Y666483D01*
G01X724150Y666469D02*
X724153Y666475D01*
G01X724147Y666462D02*
X724150Y666469D01*
G01X724142Y666456D02*
X724147Y666462D01*
G01X724136Y666452D02*
X724142Y666456D01*
G01X724129Y666448D02*
X724136Y666452D01*
G01X724122Y666446D02*
X724129Y666448D01*
G01X724114Y666446D02*
X724122D01*
G01X724131Y650701D02*
X724134Y650703D01*
G01X724128Y650700D02*
X724131Y650701D01*
G01X724125Y650699D02*
X724128Y650700D01*
G01X724121Y650698D02*
X724125Y650699D01*
G01X724118Y650698D02*
X724121D01*
G01X724114D02*
X724118D01*
G01X723192Y651898D02*
X723189Y651896D01*
G01X723195Y651899D02*
X723192Y651898D01*
G01X723198Y651900D02*
X723195Y651899D01*
G01X723202Y651900D02*
X723198D01*
G01X723205Y651901D02*
X723202Y651900D01*
G01X723209Y651901D02*
X723205D01*
G01X724131Y653851D02*
X724134Y653852D01*
G01X724128Y653850D02*
X724131Y653851D01*
G01X724125Y653848D02*
X724128Y653850D01*
G01X724121Y653848D02*
X724125D01*
G01X724118Y653847D02*
X724121Y653848D01*
G01X724114Y653847D02*
X724118D01*
G01X723192Y655047D02*
X723189Y655046D01*
G01X723195Y655048D02*
X723192Y655047D01*
G01X723198Y655050D02*
X723195Y655048D01*
G01X723202Y655050D02*
X723198D01*
G01X723205Y655051D02*
X723202Y655050D01*
G01X723209Y655051D02*
X723205D01*
G01X724131Y657000D02*
X724134Y657002D01*
G01X724128Y656999D02*
X724131Y657000D01*
G01X724125Y656998D02*
X724128Y656999D01*
G01X724121Y656997D02*
X724125Y656998D01*
G01X724118Y656997D02*
X724121D01*
G01X724114D02*
X724118D01*
G01X723192Y658197D02*
X723189Y658195D01*
G01X723195Y658198D02*
X723192Y658197D01*
G01X723198Y658199D02*
X723195Y658198D01*
G01X723202Y658200D02*
X723198Y658199D01*
G01X723205Y658200D02*
X723202D01*
G01X723209D02*
X723205D01*
G01X724131Y660150D02*
X724134Y660152D01*
G01X724128Y660149D02*
X724131Y660150D01*
G01X724125Y660148D02*
X724128Y660149D01*
G01X724121Y660147D02*
X724125Y660148D01*
G01X724118Y660146D02*
X724121Y660147D01*
G01X724114Y660146D02*
X724118D01*
G01X723192Y661346D02*
X723189Y661345D01*
G01X723195Y661348D02*
X723192Y661346D01*
G01X723198Y661349D02*
X723195Y661348D01*
G01X723202Y661349D02*
X723198D01*
G01X723205Y661350D02*
X723202Y661349D01*
G01X723209Y661350D02*
X723205D01*
G01X724131Y663300D02*
X724134Y663301D01*
G01X724128Y663298D02*
X724131Y663300D01*
G01X724125Y663297D02*
X724128Y663298D01*
G01X724121Y663296D02*
X724125Y663297D01*
G01X724118Y663296D02*
X724121D01*
G01X724114D02*
X724118D01*
G01X723192Y664496D02*
X723189Y664494D01*
G01X723195Y664497D02*
X723192Y664496D01*
G01X723198Y664498D02*
X723195Y664497D01*
G01X723202Y664499D02*
X723198Y664498D01*
G01X723205Y664500D02*
X723202Y664499D01*
G01X723209Y664500D02*
X723205D01*
G01X723192Y667646D02*
X723189Y667644D01*
G01X723195Y667647D02*
X723192Y667646D01*
G01X723198Y667648D02*
X723195Y667647D01*
G01X723202Y667648D02*
X723198D01*
G01X723205Y667649D02*
X723202Y667648D01*
G01X723209Y667649D02*
X723205D01*
G01X724131Y669599D02*
X724134Y669600D01*
G01X724128Y669598D02*
X724131Y669599D01*
G01X724125Y669596D02*
X724128Y669598D01*
G01X724121Y669596D02*
X724125D01*
G01X724118Y669595D02*
X724121Y669596D01*
G01X724114Y669595D02*
X724118D01*
G01X723192Y670795D02*
X723189Y670794D01*
G01X723195Y670796D02*
X723192Y670795D01*
G01X723198Y670798D02*
X723195Y670796D01*
G01X723202Y670798D02*
X723198D01*
G01X723205Y670799D02*
X723202Y670798D01*
G01X723209Y670799D02*
X723205D01*
G01X722422Y653898D02*
X721988D01*
G01X722796D02*
X722422D01*
G01Y660197D02*
X721988D01*
G01X722796D02*
X722422D01*
G01Y663346D02*
X721988D01*
G01X722795D02*
X722422D01*
G01X724144Y651888D02*
X724148Y651883D01*
G01X724139Y651893D02*
X724144Y651888D01*
G01X724133Y651896D02*
X724139Y651893D01*
G01X724128Y651899D02*
X724133Y651896D01*
G01X724121Y651901D02*
X724128Y651899D01*
G01X724114Y651901D02*
X724121D01*
G01X724144Y655038D02*
X724148Y655033D01*
G01X724139Y655042D02*
X724144Y655038D01*
G01X724133Y655046D02*
X724139Y655042D01*
G01X724128Y655048D02*
X724133Y655046D01*
G01X724121Y655050D02*
X724128Y655048D01*
G01X724114Y655051D02*
X724121Y655050D01*
G01X724144Y658187D02*
X724148Y658182D01*
G01X724139Y658192D02*
X724144Y658187D01*
G01X724133Y658196D02*
X724139Y658192D01*
G01X724128Y658198D02*
X724133Y658196D01*
G01X724121Y658200D02*
X724128Y658198D01*
G01X724114Y658200D02*
X724121D01*
G01X724144Y661337D02*
X724148Y661332D01*
G01X724139Y661341D02*
X724144Y661337D01*
G01X724133Y661345D02*
X724139Y661341D01*
G01X724128Y661348D02*
X724133Y661345D01*
G01X724121Y661350D02*
X724128Y661348D01*
G01X724114Y661350D02*
X724121D01*
G01X724144Y664487D02*
X724148Y664481D01*
G01X724139Y664491D02*
X724144Y664487D01*
G01X724133Y664495D02*
X724139Y664491D01*
G01X724128Y664497D02*
X724133Y664495D01*
G01X724121Y664499D02*
X724128Y664497D01*
G01X724114Y664500D02*
X724121Y664499D01*
G01X724144Y667636D02*
X724148Y667631D01*
G01X724139Y667641D02*
X724144Y667636D01*
G01X724133Y667644D02*
X724139Y667641D01*
G01X724128Y667647D02*
X724133Y667644D01*
G01X724121Y667649D02*
X724128Y667647D01*
G01X724114Y667649D02*
X724121D01*
G01X724144Y670786D02*
X724148Y670781D01*
G01X724139Y670790D02*
X724144Y670786D01*
G01X724133Y670794D02*
X724139Y670790D01*
G01X724128Y670796D02*
X724133Y670794D01*
G01X724121Y670798D02*
X724128Y670796D01*
G01X724114Y670799D02*
X724121Y670798D01*
G01X723170Y650727D02*
X723169Y650735D01*
G01X723172Y650720D02*
X723170Y650727D01*
G01X723176Y650714D02*
X723172Y650720D01*
G01X723181Y650708D02*
X723176Y650714D01*
G01X723187Y650704D02*
X723181Y650708D01*
G01X723194Y650700D02*
X723187Y650704D01*
G01X723201Y650698D02*
X723194Y650700D01*
G01X723209Y650698D02*
X723201D01*
G01X723170Y653877D02*
X723169Y653884D01*
G01X723172Y653870D02*
X723170Y653877D01*
G01X723176Y653864D02*
X723172Y653870D01*
G01X723181Y653858D02*
X723176Y653864D01*
G01X723187Y653853D02*
X723181Y653858D01*
G01X723194Y653850D02*
X723187Y653853D01*
G01X723201Y653848D02*
X723194Y653850D01*
G01X723209Y653847D02*
X723201Y653848D01*
G01X723170Y657026D02*
X723169Y657034D01*
G01X723172Y657020D02*
X723170Y657026D01*
G01X723176Y657013D02*
X723172Y657020D01*
G01X723181Y657007D02*
X723176Y657013D01*
G01X723187Y657003D02*
X723181Y657007D01*
G01X723194Y657000D02*
X723187Y657003D01*
G01X723201Y656998D02*
X723194Y657000D01*
G01X723209Y656997D02*
X723201Y656998D01*
G01X723170Y660176D02*
X723169Y660183D01*
G01X723172Y660169D02*
X723170Y660176D01*
G01X723176Y660163D02*
X723172Y660169D01*
G01X723181Y660157D02*
X723176Y660163D01*
G01X723187Y660152D02*
X723181Y660157D01*
G01X723194Y660149D02*
X723187Y660152D01*
G01X723201Y660147D02*
X723194Y660149D01*
G01X723209Y660146D02*
X723201Y660147D01*
G01X723170Y663326D02*
X723169Y663333D01*
G01X723172Y663319D02*
X723170Y663326D01*
G01X723176Y663313D02*
X723172Y663319D01*
G01X723181Y663307D02*
X723176Y663313D01*
G01X723187Y663302D02*
X723181Y663307D01*
G01X723194Y663299D02*
X723187Y663302D01*
G01X723201Y663297D02*
X723194Y663299D01*
G01X723209Y663296D02*
X723201Y663297D01*
G01X723170Y666475D02*
X723169Y666483D01*
G01X723172Y666469D02*
X723170Y666475D01*
G01X723176Y666462D02*
X723172Y666469D01*
G01X723181Y666456D02*
X723176Y666462D01*
G01X723187Y666452D02*
X723181Y666456D01*
G01X723194Y666448D02*
X723187Y666452D01*
G01X723201Y666446D02*
X723194Y666448D01*
G01X723209Y666446D02*
X723201D01*
G01X723170Y669625D02*
X723169Y669632D01*
G01X723172Y669618D02*
X723170Y669625D01*
G01X723176Y669612D02*
X723172Y669618D01*
G01X723181Y669606D02*
X723176Y669612D01*
G01X723187Y669601D02*
X723181Y669606D01*
G01X723194Y669598D02*
X723187Y669601D01*
G01X723201Y669596D02*
X723194Y669598D01*
G01X723209Y669595D02*
X723201Y669596D01*
G01X724123Y651889D02*
X724133Y651884D01*
G01X724113Y651890D02*
X724123Y651889D01*
G01Y655038D02*
X724133Y655034D01*
G01X724113Y655039D02*
X724123Y655038D01*
G01Y658188D02*
X724133Y658183D01*
G01X724113Y658189D02*
X724123Y658188D01*
G01Y661337D02*
X724133Y661333D01*
G01X724113Y661339D02*
X724123Y661337D01*
G01Y664487D02*
X724133Y664483D01*
G01X724113Y664488D02*
X724123Y664487D01*
G01Y667637D02*
X724133Y667632D01*
G01X724113Y667638D02*
X724123Y667637D01*
G01Y670786D02*
X724133Y670782D01*
G01X724113Y670787D02*
X724123Y670786D01*
G01X737566Y688929D02*
X737577Y688913D01*
G01X737542Y688937D02*
X737566Y688929D01*
G01Y693929D02*
X737577Y693913D01*
G01X737542Y693937D02*
X737566Y693929D01*
G01X724151Y669620D02*
X724154Y669632D01*
G01X724144Y669609D02*
X724151Y669620D01*
G01X724134Y669600D02*
X724144Y669609D01*
G01X724151Y663320D02*
X724154Y663333D01*
G01X724144Y663309D02*
X724151Y663320D01*
G01X724134Y663301D02*
X724144Y663309D01*
G01X724151Y660171D02*
X724154Y660183D01*
G01X724144Y660160D02*
X724151Y660171D01*
G01X724134Y660152D02*
X724144Y660160D01*
G01X724151Y657021D02*
X724154Y657034D01*
G01X724144Y657010D02*
X724151Y657021D01*
G01X724134Y657002D02*
X724144Y657010D01*
G01X724151Y653872D02*
X724154Y653884D01*
G01X724144Y653861D02*
X724151Y653872D01*
G01X724134Y653852D02*
X724144Y653861D01*
G01X724151Y650722D02*
X724154Y650735D01*
G01X724144Y650711D02*
X724151Y650722D01*
G01X724134Y650703D02*
X724144Y650711D01*
G01X723208Y670793D02*
Y670799D01*
G01Y670789D02*
Y670793D01*
G01X723206Y670787D02*
X723208Y670789D01*
G01Y667643D02*
Y667649D01*
G01Y667639D02*
Y667643D01*
G01X723206Y667638D02*
X723208Y667639D01*
G01Y664493D02*
Y664500D01*
G01Y664489D02*
Y664493D01*
G01X723206Y664488D02*
X723208Y664489D01*
G01Y661344D02*
Y661350D01*
G01Y661340D02*
Y661344D01*
G01X723206Y661339D02*
X723208Y661340D01*
G01Y658194D02*
Y658200D01*
G01Y658190D02*
Y658194D01*
G01X723206Y658189D02*
X723208Y658190D01*
G01Y655044D02*
Y655051D01*
G01Y655041D02*
Y655044D01*
G01X723206Y655039D02*
X723208Y655041D01*
G01Y651895D02*
Y651901D01*
G01Y651891D02*
Y651895D01*
G01X723206Y651890D02*
X723208Y651891D01*
G01X723170Y670768D02*
X723169Y670762D01*
G01X723172Y670774D02*
X723170Y670768D01*
G01X723174Y670780D02*
X723172Y670774D01*
G01X723178Y670785D02*
X723174Y670780D01*
G01X723183Y670790D02*
X723178Y670785D01*
G01X723189Y670794D02*
X723183Y670790D01*
G01X723170Y667619D02*
X723169Y667612D01*
G01X723172Y667625D02*
X723170Y667619D01*
G01X723174Y667630D02*
X723172Y667625D01*
G01X723178Y667636D02*
X723174Y667630D01*
G01X723183Y667640D02*
X723178Y667636D01*
G01X723189Y667644D02*
X723183Y667640D01*
G01X723170Y664469D02*
X723169Y664463D01*
G01X723172Y664475D02*
X723170Y664469D01*
G01X723174Y664481D02*
X723172Y664475D01*
G01X723178Y664486D02*
X723174Y664481D01*
G01X723183Y664491D02*
X723178Y664486D01*
G01X723189Y664494D02*
X723183Y664491D01*
G01X723170Y661319D02*
X723169Y661313D01*
G01X723172Y661326D02*
X723170Y661319D01*
G01X723174Y661331D02*
X723172Y661326D01*
G01X723178Y661337D02*
X723174Y661331D01*
G01X723183Y661341D02*
X723178Y661337D01*
G01X723189Y661345D02*
X723183Y661341D01*
G01X723170Y658170D02*
X723169Y658163D01*
G01X723172Y658176D02*
X723170Y658170D01*
G01X723174Y658181D02*
X723172Y658176D01*
G01X723178Y658187D02*
X723174Y658181D01*
G01X723183Y658191D02*
X723178Y658187D01*
G01X723189Y658195D02*
X723183Y658191D01*
G01X723170Y655020D02*
X723169Y655014D01*
G01X723172Y655026D02*
X723170Y655020D01*
G01X723174Y655032D02*
X723172Y655026D01*
G01X723178Y655037D02*
X723174Y655032D01*
G01X723183Y655042D02*
X723178Y655037D01*
G01X723189Y655046D02*
X723183Y655042D01*
G01X723170Y651870D02*
X723169Y651864D01*
G01X723172Y651877D02*
X723170Y651870D01*
G01X723174Y651882D02*
X723172Y651877D01*
G01X723178Y651888D02*
X723174Y651882D01*
G01X723183Y651892D02*
X723178Y651888D01*
G01X723189Y651896D02*
X723183Y651892D01*
G01X724125Y669608D02*
X724113Y669606D01*
G01X724135Y669613D02*
X724125Y669608D01*
G01Y666459D02*
X724113Y666457D01*
G01X724135Y666464D02*
X724125Y666459D01*
G01Y663309D02*
X724113Y663307D01*
G01X724135Y663314D02*
X724125Y663309D01*
G01Y660159D02*
X724113Y660157D01*
G01X724135Y660165D02*
X724125Y660159D01*
G01Y657010D02*
X724113Y657008D01*
G01X724135Y657015D02*
X724125Y657010D01*
G01Y653860D02*
X724113Y653858D01*
G01X724135Y653865D02*
X724125Y653860D01*
G01Y650711D02*
X724113Y650709D01*
G01X724135Y650716D02*
X724125Y650711D01*
G01X723172Y651870D02*
X723167Y651850D01*
G01X723187Y651885D02*
X723172Y651870D01*
G01X723206Y651890D02*
X723187Y651885D01*
G01X723172Y655020D02*
X723167Y655000D01*
G01X723187Y655034D02*
X723172Y655020D01*
G01X723206Y655039D02*
X723187Y655034D01*
G01X723172Y658169D02*
X723167Y658150D01*
G01X723187Y658184D02*
X723172Y658169D01*
G01X723206Y658189D02*
X723187Y658184D01*
G01X723172Y661319D02*
X723167Y661299D01*
G01X723187Y661333D02*
X723172Y661319D01*
G01X723206Y661339D02*
X723187Y661333D01*
G01X723172Y664469D02*
X723167Y664449D01*
G01X723187Y664483D02*
X723172Y664469D01*
G01X723206Y664488D02*
X723187Y664483D01*
G01X723172Y667618D02*
X723167Y667598D01*
G01X723187Y667633D02*
X723172Y667618D01*
G01X723206Y667638D02*
X723187Y667633D01*
G01X723172Y670768D02*
X723167Y670748D01*
G01X723187Y670782D02*
X723172Y670768D01*
G01X723206Y670787D02*
X723187Y670782D01*
G01X724147Y650728D02*
X724152Y650748D01*
G01X724132Y650714D02*
X724147Y650728D01*
G01X724113Y650709D02*
X724132Y650714D01*
G01X724147Y653878D02*
X724152Y653898D01*
G01X724132Y653864D02*
X724147Y653878D01*
G01X724113Y653858D02*
X724132Y653864D01*
G01X724147Y657028D02*
X724152Y657047D01*
G01X724132Y657013D02*
X724147Y657028D01*
G01X724113Y657008D02*
X724132Y657013D01*
G01X724147Y660177D02*
X724152Y660197D01*
G01X724132Y660163D02*
X724147Y660177D01*
G01X724113Y660157D02*
X724132Y660163D01*
G01X724147Y663327D02*
X724152Y663346D01*
G01X724132Y663313D02*
X724147Y663327D01*
G01X724113Y663307D02*
X724132Y663313D01*
G01X724147Y666476D02*
X724152Y666496D01*
G01X724132Y666462D02*
X724147Y666476D01*
G01X724113Y666457D02*
X724132Y666462D01*
G01X724147Y669626D02*
X724152Y669646D01*
G01X724132Y669612D02*
X724147Y669626D01*
G01X724113Y669606D02*
X724132Y669612D01*
G01X723056Y669646D02*
X723168Y669637D01*
G01X723167Y660193D02*
X723056Y660197D01*
G01X723167Y653894D02*
X723056Y653898D01*
G01X723167Y663343D02*
X723056Y663346D01*
G01X737579Y694429D02*
X736594D01*
G01X736596Y693937D02*
X741929D01*
G01Y693898D02*
X737581D01*
G01X741929Y692559D02*
X736596D01*
G01X736594Y692067D02*
X737579D01*
G01Y689429D02*
X736594D01*
G01X736596Y688937D02*
X741929D01*
G01Y688898D02*
X737581D01*
G01X741929Y687559D02*
X736596D01*
G01X736594Y687067D02*
X737579D01*
G01Y684429D02*
X736594D01*
G01X736596Y683937D02*
X741929D01*
G01Y683898D02*
X737581D01*
G01X741929Y682559D02*
X736596D01*
G01X736594Y682067D02*
X737579D01*
G01Y679429D02*
X736594D01*
G01X736596Y678937D02*
X741929D01*
G01Y678898D02*
X737581D01*
G01X741929Y677559D02*
X736596D01*
G01X736594Y677067D02*
X737579D01*
G01Y674429D02*
X736594D01*
G01X736596Y673937D02*
X741929D01*
G01Y673898D02*
X737581D01*
G01X724606Y672953D02*
X721260D01*
G01X741929Y672559D02*
X736596D01*
G01X736594Y672067D02*
X737579D01*
G01X734252Y671791D02*
X738189D01*
G01X724114Y670984D02*
X723209D01*
G01X724154Y670945D02*
X723169D01*
G01X724113Y670787D02*
X718228D01*
G01Y670748D02*
X724152D01*
G01X733071Y670610D02*
X737008D01*
G01X724152Y669646D02*
X718228D01*
G01X724113Y669606D02*
X718228D01*
G01X723169Y669449D02*
X724154D01*
G01X723209Y669409D02*
X724114D01*
G01Y667835D02*
X723209D01*
G01X724154Y667795D02*
X723169D01*
G01X724113Y667638D02*
X718228D01*
G01Y667598D02*
X724152D01*
G01Y666496D02*
X718228D01*
G01X724113Y666457D02*
X718228D01*
G01X723169Y666299D02*
X724154D01*
G01X723209Y666260D02*
X724114D01*
G01Y664685D02*
X723209D01*
G01X724154Y664646D02*
X723169D01*
G01X724113Y664488D02*
X718228D01*
G01Y664449D02*
X724152D01*
G01Y663346D02*
X718228D01*
G01X724113Y663307D02*
X718228D01*
G01X723169Y663150D02*
X724154D01*
G01X723209Y663110D02*
X724114D01*
G01Y661535D02*
X723209D01*
G01X724154Y661496D02*
X723169D01*
G01X724113Y661339D02*
X718228D01*
G01Y661299D02*
X724152D01*
G01Y660197D02*
X718228D01*
G01X724113Y660157D02*
X718228D01*
G01X723169Y660000D02*
X724154D01*
G01X723209Y659961D02*
X724114D01*
G01Y658386D02*
X723209D01*
G01X724154Y658346D02*
X723169D01*
G01X724113Y658189D02*
X718228D01*
G01Y658150D02*
X724152D01*
G01Y657047D02*
X718228D01*
G01X724113Y657008D02*
X718228D01*
G01X723169Y656850D02*
X724154D01*
G01X723209Y656811D02*
X724114D01*
G01Y655236D02*
X723209D01*
G01X724154Y655197D02*
X723169D01*
G01X724113Y655039D02*
X718228D01*
G01Y655000D02*
X724152D01*
G01Y653898D02*
X718228D01*
G01X724113Y653858D02*
X718228D01*
G01X723169Y653701D02*
X724154D01*
G01X723209Y653661D02*
X724114D01*
G01Y652087D02*
X723209D01*
G01X724154Y652047D02*
X723169D01*
G01X724113Y651890D02*
X718228D01*
G01Y651850D02*
X724152D01*
G01X737008Y650886D02*
X733071D01*
G01X724152Y650748D02*
X718228D01*
G01X724113Y650709D02*
X718228D01*
G01X723169Y650551D02*
X724154D01*
G01X723209Y650512D02*
X724114D01*
G01X738189Y649705D02*
X734252D01*
G01X737579Y649429D02*
X736594D01*
G01X736596Y648937D02*
X741929D01*
G01Y648898D02*
X737581D01*
G01X724606Y648543D02*
X721260D01*
G01X736594Y694133D02*
X737550Y694134D01*
G01X737579Y692363D02*
X736594Y692362D01*
G01Y689133D02*
X737550Y689134D01*
G01X737579Y687363D02*
X736594Y687362D01*
G01Y684133D02*
X737550Y684134D01*
G01X737579Y682363D02*
X736594Y682362D01*
G01Y679133D02*
X737550Y679134D01*
G01X737579Y677363D02*
X736594Y677362D01*
G01Y674133D02*
X737550Y674134D01*
G01X737579Y672363D02*
X736594Y672362D01*
G01Y649133D02*
X737550Y649134D01*
G01X737008Y670610D02*
X738189Y671791D01*
G01X733071Y670610D02*
X734252Y671791D01*
G01X737008Y650886D02*
X738189Y649705D01*
G01X724153Y651853D02*
X724154Y651864D01*
G01X724153Y655002D02*
X724154Y655013D01*
G01X724153Y658152D02*
X724154Y658163D01*
G01X724153Y661302D02*
X724154Y661313D01*
G01X724153Y664451D02*
X724154Y664462D01*
G01X724153Y667601D02*
X724154Y667612D01*
G01X724153Y670750D02*
X724154Y670761D01*
G01X737579Y648911D02*
Y648920D01*
G01Y673911D02*
Y673920D01*
G01Y678911D02*
Y678920D01*
G01Y683911D02*
Y683920D01*
G01Y688911D02*
Y688920D01*
G01Y693911D02*
Y693920D01*
G01X741929Y692559D02*
Y693937D01*
G01Y687559D02*
Y688937D01*
G01Y682559D02*
Y683937D01*
G01Y677559D02*
Y678937D01*
G01Y672559D02*
Y673937D01*
G01X738760D02*
Y672559D01*
G01Y678937D02*
Y677559D01*
G01Y683937D02*
Y682559D01*
G01Y688937D02*
Y687559D01*
G01Y693937D02*
Y692559D01*
G01X738189Y671791D02*
Y649705D01*
G01X737579Y692067D02*
Y694429D01*
G01Y687067D02*
Y689429D01*
G01Y682067D02*
Y684429D01*
G01Y677067D02*
Y679429D01*
G01Y672067D02*
Y674429D01*
G01X737008Y670610D02*
Y650886D01*
G01X736594Y674429D02*
Y672067D01*
G01Y679429D02*
Y677067D01*
G01Y684429D02*
Y682067D01*
G01Y689429D02*
Y687067D01*
G01Y694429D02*
Y692067D01*
G01X734252Y748248D02*
Y671791D01*
G01X733071Y747067D02*
Y670610D01*
G01X724606Y751988D02*
Y672953D01*
G01X724154Y669449D02*
Y670945D01*
G01Y666299D02*
Y667795D01*
G01Y663150D02*
Y664646D01*
G01Y660000D02*
Y661496D01*
G01Y656850D02*
Y658346D01*
G01Y653701D02*
Y655197D01*
G01Y650551D02*
Y652047D01*
G01X724114Y650698D02*
Y650551D01*
G01Y652048D02*
Y651901D01*
G01Y656997D02*
Y656850D01*
G01Y653847D02*
Y653700D01*
G01Y655197D02*
Y655051D01*
G01Y660146D02*
Y660000D01*
G01Y661496D02*
Y661350D01*
G01Y658347D02*
Y658200D01*
G01Y666446D02*
Y666299D01*
G01Y663296D02*
Y663149D01*
G01Y664646D02*
Y664500D01*
G01Y669595D02*
Y669448D01*
G01Y670945D02*
Y670799D01*
G01Y667796D02*
Y667649D01*
G01X723209Y669448D02*
Y669595D01*
G01Y670799D02*
Y670946D01*
G01Y667649D02*
Y667796D01*
G01Y666298D02*
Y666446D01*
G01Y663149D02*
Y663296D01*
G01Y664500D02*
Y664646D01*
G01Y659999D02*
Y660146D01*
G01Y661350D02*
Y661497D01*
G01Y658200D02*
Y658347D01*
G01Y656850D02*
Y656997D01*
G01Y653700D02*
Y653847D01*
G01Y655051D02*
Y655198D01*
G01Y650550D02*
Y650698D01*
G01Y651901D02*
Y652048D01*
G01X723169Y652047D02*
Y650551D01*
G01Y655197D02*
Y653701D01*
G01Y661496D02*
Y660000D01*
G01Y658346D02*
Y656850D01*
G01Y664646D02*
Y663150D01*
G01Y670945D02*
Y669449D01*
G01Y667795D02*
Y666299D01*
G01X721988Y651890D02*
Y650709D01*
G01Y658189D02*
Y657008D01*
G01Y655039D02*
Y653858D01*
G01Y661339D02*
Y660157D01*
G01Y667638D02*
Y666457D01*
G01Y664488D02*
Y663307D01*
G01Y670787D02*
Y669606D01*
G01X721654Y672953D02*
Y648543D01*
G01X721260D02*
Y672953D01*
G01X718228Y669606D02*
Y670787D01*
G01Y666457D02*
Y667638D01*
G01Y663307D02*
Y664488D01*
G01Y660157D02*
Y661339D01*
G01Y657008D02*
Y658189D01*
G01Y653858D02*
Y655039D01*
G01Y650709D02*
Y651890D01*
G01X724154Y669632D02*
X724153Y669643D01*
G01X724154Y666483D02*
X724153Y666494D01*
G01X724154Y663333D02*
X724153Y663344D01*
G01X724154Y660183D02*
X724153Y660194D01*
G01X724154Y657034D02*
X724153Y657045D01*
G01X724154Y653884D02*
X724153Y653895D01*
G01X724154Y650735D02*
X724153Y650746D01*
G01X724113Y666457D02*
X724116Y666446D01*
G01X733071Y650886D02*
X734252Y649705D01*
G01X737546Y699035D02*
X737550Y699134D01*
G01X737540Y698963D02*
X737546Y699035D01*
G01X737542Y698937D02*
X737540Y698963D01*
G01X737546Y704035D02*
X737550Y704134D01*
G01X737540Y703963D02*
X737546Y704035D01*
G01X737542Y703937D02*
X737540Y703963D01*
G01X737546Y709035D02*
X737550Y709134D01*
G01X737540Y708963D02*
X737546Y709035D01*
G01X737542Y708937D02*
X737540Y708963D01*
G01X737546Y714035D02*
X737550Y714134D01*
G01X737540Y713963D02*
X737546Y714035D01*
G01X737542Y713937D02*
X737540Y713963D01*
G01X737546Y719035D02*
X737550Y719134D01*
G01X737540Y718963D02*
X737546Y719035D01*
G01X737542Y718937D02*
X737540Y718963D01*
G01X737546Y724035D02*
X737550Y724134D01*
G01X737540Y723963D02*
X737546Y724035D01*
G01X737542Y723937D02*
X737540Y723963D01*
G01X737546Y729035D02*
X737550Y729134D01*
G01X737540Y728963D02*
X737546Y729035D01*
G01X737542Y728937D02*
X737540Y728963D01*
G01X737546Y734035D02*
X737550Y734134D01*
G01X737540Y733963D02*
X737546Y734035D01*
G01X737542Y733937D02*
X737540Y733963D01*
G01X737546Y739035D02*
X737550Y739134D01*
G01X737540Y738963D02*
X737546Y739035D01*
G01X737542Y738937D02*
X737540Y738963D01*
G01X737546Y744035D02*
X737550Y744134D01*
G01X737540Y743963D02*
X737546Y744035D01*
G01X737542Y743937D02*
X737540Y743963D01*
G01X736595Y742557D02*
X736596Y742559D01*
G01X736594Y742552D02*
X736595Y742557D01*
G01X736594Y742543D02*
Y742552D01*
G01X736595Y737557D02*
X736596Y737559D01*
G01X736594Y737552D02*
X736595Y737557D01*
G01X736594Y737543D02*
Y737552D01*
G01X736595Y732557D02*
X736596Y732559D01*
G01X736594Y732552D02*
X736595Y732557D01*
G01X736594Y732543D02*
Y732552D01*
G01X736595Y727557D02*
X736596Y727559D01*
G01X736594Y727552D02*
X736595Y727557D01*
G01X736594Y727543D02*
Y727552D01*
G01X736595Y722557D02*
X736596Y722559D01*
G01X736594Y722552D02*
X736595Y722557D01*
G01X736594Y722543D02*
Y722552D01*
G01X736595Y717557D02*
X736596Y717559D01*
G01X736594Y717552D02*
X736595Y717557D01*
G01X736594Y717543D02*
Y717552D01*
G01X736595Y712557D02*
X736596Y712559D01*
G01X736594Y712552D02*
X736595Y712557D01*
G01X736594Y712543D02*
Y712552D01*
G01X736595Y707557D02*
X736596Y707559D01*
G01X736594Y707552D02*
X736595Y707557D01*
G01X736594Y707543D02*
Y707552D01*
G01X736595Y702557D02*
X736596Y702559D01*
G01X736594Y702552D02*
X736595Y702557D01*
G01X736594Y702543D02*
Y702552D01*
G01X736595Y697557D02*
X736596Y697559D01*
G01X736594Y697552D02*
X736595Y697557D01*
G01X736594Y697543D02*
Y697552D01*
G01X737579Y698904D02*
Y698911D01*
G01X737580Y698900D02*
X737579Y698904D01*
G01X737581Y698898D02*
X737580Y698900D01*
G01X737579Y703904D02*
Y703911D01*
G01X737580Y703900D02*
X737579Y703904D01*
G01X737581Y703898D02*
X737580Y703900D01*
G01X737579Y708904D02*
Y708911D01*
G01X737580Y708900D02*
X737579Y708904D01*
G01X737581Y708898D02*
X737580Y708900D01*
G01X737579Y713904D02*
Y713911D01*
G01X737580Y713900D02*
X737579Y713904D01*
G01X737581Y713898D02*
X737580Y713900D01*
G01X737579Y718904D02*
Y718911D01*
G01X737580Y718900D02*
X737579Y718904D01*
G01X737581Y718898D02*
X737580Y718900D01*
G01X737579Y723904D02*
Y723911D01*
G01X737580Y723900D02*
X737579Y723904D01*
G01X737581Y723898D02*
X737580Y723900D01*
G01X737579Y728904D02*
Y728911D01*
G01X737580Y728900D02*
X737579Y728904D01*
G01X737581Y728898D02*
X737580Y728900D01*
G01X737579Y733904D02*
Y733911D01*
G01X737580Y733900D02*
X737579Y733904D01*
G01X737581Y733898D02*
X737580Y733900D01*
G01X737579Y738904D02*
Y738911D01*
G01X737580Y738900D02*
X737579Y738904D01*
G01X737581Y738898D02*
X737580Y738900D01*
G01X737579Y743904D02*
Y743911D01*
G01X737580Y743900D02*
X737579Y743904D01*
G01X737581Y743898D02*
X737580Y743900D01*
G01X736594Y698944D02*
Y698954D01*
G01X736595Y698939D02*
X736594Y698944D01*
G01X736596Y698937D02*
X736595Y698939D01*
G01X736594Y703944D02*
Y703954D01*
G01X736595Y703939D02*
X736594Y703944D01*
G01X736596Y703937D02*
X736595Y703939D01*
G01X736594Y708944D02*
Y708954D01*
G01X736595Y708939D02*
X736594Y708944D01*
G01X736596Y708937D02*
X736595Y708939D01*
G01X736594Y713944D02*
Y713954D01*
G01X736595Y713939D02*
X736594Y713944D01*
G01X736596Y713937D02*
X736595Y713939D01*
G01X736594Y718944D02*
Y718954D01*
G01X736595Y718939D02*
X736594Y718944D01*
G01X736596Y718937D02*
X736595Y718939D01*
G01X736594Y723944D02*
Y723954D01*
G01X736595Y723939D02*
X736594Y723944D01*
G01X736596Y723937D02*
X736595Y723939D01*
G01X736594Y728944D02*
Y728954D01*
G01X736595Y728939D02*
X736594Y728944D01*
G01X736596Y728937D02*
X736595Y728939D01*
G01X736594Y733944D02*
Y733954D01*
G01X736595Y733939D02*
X736594Y733944D01*
G01X736596Y733937D02*
X736595Y733939D01*
G01X736594Y738944D02*
Y738954D01*
G01X736595Y738939D02*
X736594Y738944D01*
G01X736596Y738937D02*
X736595Y738939D01*
G01X736594Y743944D02*
Y743954D01*
G01X736595Y743939D02*
X736594Y743944D01*
G01X736596Y743937D02*
X736595Y743939D01*
G01X737571Y699081D02*
X737579Y699055D01*
G01X737561Y699107D02*
X737571Y699081D01*
G01X737550Y699134D02*
X737561Y699107D01*
G01X737571Y704081D02*
X737579Y704055D01*
G01X737561Y704107D02*
X737571Y704081D01*
G01X737550Y704134D02*
X737561Y704107D01*
G01X737571Y709081D02*
X737579Y709055D01*
G01X737561Y709107D02*
X737571Y709081D01*
G01X737550Y709134D02*
X737561Y709107D01*
G01X737571Y714081D02*
X737579Y714055D01*
G01X737561Y714107D02*
X737571Y714081D01*
G01X737550Y714134D02*
X737561Y714107D01*
G01X737571Y719081D02*
X737579Y719055D01*
G01X737561Y719107D02*
X737571Y719081D01*
G01X737550Y719134D02*
X737561Y719107D01*
G01X737571Y724081D02*
X737579Y724055D01*
G01X737561Y724107D02*
X737571Y724081D01*
G01X737550Y724134D02*
X737561Y724107D01*
G01X737571Y729081D02*
X737579Y729055D01*
G01X737561Y729107D02*
X737571Y729081D01*
G01X737550Y729134D02*
X737561Y729107D01*
G01X737571Y734081D02*
X737579Y734055D01*
G01X737561Y734107D02*
X737571Y734081D01*
G01X737550Y734134D02*
X737561Y734107D01*
G01X737571Y739081D02*
X737579Y739055D01*
G01X737561Y739107D02*
X737571Y739081D01*
G01X737550Y739134D02*
X737561Y739107D01*
G01X737571Y744081D02*
X737579Y744055D01*
G01X737561Y744107D02*
X737571Y744081D01*
G01X737550Y744134D02*
X737561Y744107D01*
G01Y698932D02*
X737542Y698937D01*
G01X737576Y698918D02*
X737561Y698932D01*
G01X737581Y698898D02*
X737576Y698918D01*
G01X737561Y703932D02*
X737542Y703937D01*
G01X737576Y703918D02*
X737561Y703932D01*
G01X737581Y703898D02*
X737576Y703918D01*
G01X737561Y708932D02*
X737542Y708937D01*
G01X737576Y708918D02*
X737561Y708932D01*
G01X737581Y708898D02*
X737576Y708918D01*
G01X737561Y713932D02*
X737542Y713937D01*
G01X737576Y713918D02*
X737561Y713932D01*
G01X737581Y713898D02*
X737576Y713918D01*
G01X737561Y718932D02*
X737542Y718937D01*
G01X737576Y718918D02*
X737561Y718932D01*
G01X737581Y718898D02*
X737576Y718918D01*
G01X737561Y723932D02*
X737542Y723937D01*
G01X737576Y723918D02*
X737561Y723932D01*
G01X737581Y723898D02*
X737576Y723918D01*
G01X737561Y728932D02*
X737542Y728937D01*
G01X737576Y728918D02*
X737561Y728932D01*
G01X737581Y728898D02*
X737576Y728918D01*
G01X737561Y733932D02*
X737542Y733937D01*
G01X737576Y733918D02*
X737561Y733932D01*
G01X737581Y733898D02*
X737576Y733918D01*
G01X737561Y738932D02*
X737542Y738937D01*
G01X737576Y738918D02*
X737561Y738932D01*
G01X737581Y738898D02*
X737576Y738918D01*
G01X737561Y743932D02*
X737542Y743937D01*
G01X737576Y743918D02*
X737561Y743932D01*
G01X737581Y743898D02*
X737576Y743918D01*
G01X737579Y742552D02*
Y742543D01*
G01X737580Y742557D02*
X737579Y742552D01*
G01X737581Y742559D02*
X737580Y742557D01*
G01X737579Y737552D02*
Y737543D01*
G01X737580Y737557D02*
X737579Y737552D01*
G01X737581Y737559D02*
X737580Y737557D01*
G01X737579Y732552D02*
Y732543D01*
G01X737580Y732557D02*
X737579Y732552D01*
G01X737581Y732559D02*
X737580Y732557D01*
G01X737579Y727552D02*
Y727543D01*
G01X737580Y727557D02*
X737579Y727552D01*
G01X737581Y727559D02*
X737580Y727557D01*
G01X737579Y722552D02*
Y722543D01*
G01X737580Y722557D02*
X737579Y722552D01*
G01X737581Y722559D02*
X737580Y722557D01*
G01X737579Y717552D02*
Y717543D01*
G01X737580Y717557D02*
X737579Y717552D01*
G01X737581Y717559D02*
X737580Y717557D01*
G01X737579Y712552D02*
Y712543D01*
G01X737580Y712557D02*
X737579Y712552D01*
G01X737581Y712559D02*
X737580Y712557D01*
G01X737579Y707552D02*
Y707543D01*
G01X737580Y707557D02*
X737579Y707552D01*
G01X737581Y707559D02*
X737580Y707557D01*
G01X737579Y702552D02*
Y702543D01*
G01X737580Y702557D02*
X737579Y702552D01*
G01X737581Y702559D02*
X737580Y702557D01*
G01X737579Y697552D02*
Y697543D01*
G01X737580Y697557D02*
X737579Y697552D01*
G01X737581Y697559D02*
X737580Y697557D01*
G01X737566Y698929D02*
X737577Y698913D01*
G01X737542Y698937D02*
X737566Y698929D01*
G01Y703929D02*
X737577Y703913D01*
G01X737542Y703937D02*
X737566Y703929D01*
G01Y708929D02*
X737577Y708913D01*
G01X737542Y708937D02*
X737566Y708929D01*
G01Y713929D02*
X737577Y713913D01*
G01X737542Y713937D02*
X737566Y713929D01*
G01Y718929D02*
X737577Y718913D01*
G01X737542Y718937D02*
X737566Y718929D01*
G01Y723929D02*
X737577Y723913D01*
G01X737542Y723937D02*
X737566Y723929D01*
G01Y728929D02*
X737577Y728913D01*
G01X737542Y728937D02*
X737566Y728929D01*
G01Y733929D02*
X737577Y733913D01*
G01X737542Y733937D02*
X737566Y733929D01*
G01Y738929D02*
X737577Y738913D01*
G01X737542Y738937D02*
X737566Y738929D01*
G01Y743929D02*
X737577Y743913D01*
G01X737542Y743937D02*
X737566Y743929D01*
G01X737579Y744429D02*
X736594D01*
G01X736596Y743937D02*
X741929D01*
G01Y743898D02*
X737581D01*
G01X741929Y742559D02*
X736596D01*
G01X736594Y742067D02*
X737579D01*
G01Y739429D02*
X736594D01*
G01X736596Y738937D02*
X741929D01*
G01Y738898D02*
X737581D01*
G01X741929Y737559D02*
X736596D01*
G01X736594Y737067D02*
X737579D01*
G01Y734429D02*
X736594D01*
G01X736596Y733937D02*
X741929D01*
G01Y733898D02*
X737581D01*
G01X741929Y732559D02*
X736596D01*
G01X736594Y732067D02*
X737579D01*
G01Y729429D02*
X736594D01*
G01X736596Y728937D02*
X741929D01*
G01Y728898D02*
X737581D01*
G01X741929Y727559D02*
X736596D01*
G01X736594Y727067D02*
X737579D01*
G01Y724429D02*
X736594D01*
G01X736596Y723937D02*
X741929D01*
G01Y723898D02*
X737581D01*
G01X741929Y722559D02*
X736596D01*
G01X736594Y722067D02*
X737579D01*
G01Y719429D02*
X736594D01*
G01X736596Y718937D02*
X741929D01*
G01Y718898D02*
X737581D01*
G01X741929Y717559D02*
X736596D01*
G01X736594Y717067D02*
X737579D01*
G01Y714429D02*
X736594D01*
G01X736596Y713937D02*
X741929D01*
G01Y713898D02*
X737581D01*
G01X741929Y712559D02*
X736596D01*
G01X736594Y712067D02*
X737579D01*
G01Y709429D02*
X736594D01*
G01X736596Y708937D02*
X741929D01*
G01Y708898D02*
X737581D01*
G01X741929Y707559D02*
X736596D01*
G01X736594Y707067D02*
X737579D01*
G01X736594Y744133D02*
X737550Y744134D01*
G01X737579Y742363D02*
X736594Y742362D01*
G01Y739133D02*
X737550Y739134D01*
G01X737579Y737363D02*
X736594Y737362D01*
G01Y734133D02*
X737550Y734134D01*
G01X737579Y732363D02*
X736594Y732362D01*
G01Y729133D02*
X737550Y729134D01*
G01X737579Y727363D02*
X736594Y727362D01*
G01Y724133D02*
X737550Y724134D01*
G01X737579Y722363D02*
X736594Y722362D01*
G01Y719133D02*
X737550Y719134D01*
G01X737579Y717363D02*
X736594Y717362D01*
G01Y714133D02*
X737550Y714134D01*
G01X737579Y712363D02*
X736594Y712362D01*
G01Y709133D02*
X737550Y709134D01*
G01X737579Y707363D02*
X736594Y707362D01*
G01X737579Y704429D02*
X736594D01*
G01X736596Y703937D02*
X741929D01*
G01Y703898D02*
X737581D01*
G01X741929Y702559D02*
X736596D01*
G01X736594Y702067D02*
X737579D01*
G01Y699429D02*
X736594D01*
G01X736596Y698937D02*
X741929D01*
G01Y698898D02*
X737581D01*
G01X741929Y697559D02*
X736596D01*
G01X736594Y697067D02*
X737579D01*
G01X736594Y704133D02*
X737550Y704134D01*
G01X737579Y702363D02*
X736594Y702362D01*
G01Y699133D02*
X737550Y699134D01*
G01X737579Y697363D02*
X736594Y697362D01*
G01X737579Y698911D02*
Y698920D01*
G01Y703911D02*
Y703920D01*
G01Y708911D02*
Y708920D01*
G01Y713911D02*
Y713920D01*
G01Y718911D02*
Y718920D01*
G01Y723911D02*
Y723920D01*
G01Y728911D02*
Y728920D01*
G01Y733911D02*
Y733920D01*
G01Y738911D02*
Y738920D01*
G01Y743911D02*
Y743920D01*
G01X741929Y742559D02*
Y743937D01*
G01Y737559D02*
Y738937D01*
G01Y732559D02*
Y733937D01*
G01Y727559D02*
Y728937D01*
G01Y722559D02*
Y723937D01*
G01Y717559D02*
Y718937D01*
G01Y712559D02*
Y713937D01*
G01Y707559D02*
Y708937D01*
G01Y702559D02*
Y703937D01*
G01Y697559D02*
Y698937D01*
G01X738760D02*
Y697559D01*
G01Y703937D02*
Y702559D01*
G01Y708937D02*
Y707559D01*
G01Y713937D02*
Y712559D01*
G01Y718937D02*
Y717559D01*
G01Y723937D02*
Y722559D01*
G01Y728937D02*
Y727559D01*
G01Y733937D02*
Y732559D01*
G01Y738937D02*
Y737559D01*
G01Y743937D02*
Y742559D01*
G01X737579Y742067D02*
Y744429D01*
G01Y737067D02*
Y739429D01*
G01Y732067D02*
Y734429D01*
G01Y727067D02*
Y729429D01*
G01Y722067D02*
Y724429D01*
G01Y717067D02*
Y719429D01*
G01Y712067D02*
Y714429D01*
G01Y707067D02*
Y709429D01*
G01Y702067D02*
Y704429D01*
G01Y697067D02*
Y699429D01*
G01X736594D02*
Y697067D01*
G01Y704429D02*
Y702067D01*
G01Y709429D02*
Y707067D01*
G01Y714429D02*
Y712067D01*
G01Y719429D02*
Y717067D01*
G01Y724429D02*
Y722067D01*
G01Y729429D02*
Y727067D01*
G01Y734429D02*
Y732067D01*
G01Y739429D02*
Y737067D01*
G01Y744429D02*
Y742067D01*
G01X736024Y769429D02*
G03X735433Y770020I-591J0D01*
G01X728740D02*
G03X728150Y769429I0J-590D01*
G01X730906Y768248D02*
G03Y766280I0J-984D01*
G01X733268D02*
G03Y768248I0J984D01*
G01X742913Y768839D02*
G03X740945Y770807I-1968J0D01*
G01X723228D02*
G03X721260Y768839I0J-1968D01*
G01X729528Y760335D02*
G03X728346Y759154I-1J-1181D01*
G01X735827D02*
G03X734646Y760335I-1181J0D01*
G01X733976Y755059D02*
G03I-1889J0D01*
G01X734449D02*
G03I-2362J0D01*
G01X740945Y770807D02*
X723228D01*
G01X735433Y770020D02*
X728740D01*
G01X733268Y768248D02*
X730906D01*
G01Y766280D02*
X733268D01*
G01X736024Y764902D02*
X728150D01*
G01Y763327D02*
X736024D01*
G01X742913Y760374D02*
X721260D01*
G01X729528Y760335D02*
X734646D01*
G01X730906Y755650D02*
X733268D01*
G01X730906Y753957D02*
X733268D01*
G01X724606Y751988D02*
X738976D01*
G01X724606Y750610D02*
X728346D01*
G01X738976D02*
X735827D01*
G01X724606Y749744D02*
X739567D01*
G01X726378Y748248D02*
X734252D01*
G01X727559Y747067D02*
X733071D01*
G01X742913Y753091D02*
X739567Y749744D01*
G01X733071Y747067D02*
X734252Y748248D01*
G01X730906Y755650D02*
X728595Y759879D01*
G01X733268Y753957D02*
X734571Y751988D01*
G01X726378Y748248D02*
X727559Y747067D01*
G01X721260Y753091D02*
X724606Y749744D01*
G01X729602Y751988D02*
X730906Y753957D01*
G01X735578Y759879D02*
X733268Y755650D01*
G01X742913Y753091D02*
Y768839D01*
G01X736024Y763327D02*
Y769429D01*
G01X735827Y759154D02*
Y750610D01*
G01X733268Y755650D02*
Y753957D01*
G01X730906D02*
Y755650D01*
G01X728346Y750610D02*
Y759154D01*
G01X728150Y763327D02*
Y769429D01*
G01X721260Y768839D02*
Y753091D01*
G01X726378Y820866D02*
G03I-8268J0D01*
G01X737579Y1080308D02*
Y1080299D01*
G01X737580Y1080313D02*
X737579Y1080308D01*
G01X737581Y1080315D02*
X737580Y1080313D01*
G01X737579Y1075308D02*
Y1075299D01*
G01X737580Y1075313D02*
X737579Y1075308D01*
G01X737581Y1075315D02*
X737580Y1075313D01*
G01X737579Y1070308D02*
Y1070299D01*
G01X737580Y1070313D02*
X737579Y1070308D01*
G01X737581Y1070315D02*
X737580Y1070313D01*
G01X737546Y1071791D02*
X737550Y1071890D01*
G01X737540Y1071719D02*
X737546Y1071791D01*
G01X737542Y1071693D02*
X737540Y1071719D01*
G01X737546Y1076791D02*
X737550Y1076890D01*
G01X737540Y1076719D02*
X737546Y1076791D01*
G01X737542Y1076693D02*
X737540Y1076719D01*
G01X737546Y1081791D02*
X737550Y1081890D01*
G01X737540Y1081719D02*
X737546Y1081791D01*
G01X737542Y1081693D02*
X737540Y1081719D01*
G01X736595Y1080313D02*
X736596Y1080315D01*
G01X736594Y1080308D02*
X736595Y1080313D01*
G01X736594Y1080299D02*
Y1080308D01*
G01X736595Y1075313D02*
X736596Y1075315D01*
G01X736594Y1075308D02*
X736595Y1075313D01*
G01X736594Y1075299D02*
Y1075308D01*
G01X736595Y1070313D02*
X736596Y1070315D01*
G01X736594Y1070308D02*
X736595Y1070313D01*
G01X736594Y1070299D02*
Y1070308D01*
G01Y1071700D02*
Y1071709D01*
G01X736595Y1071695D02*
X736594Y1071700D01*
G01X736596Y1071693D02*
X736595Y1071695D01*
G01X736594Y1076700D02*
Y1076709D01*
G01X736595Y1076695D02*
X736594Y1076700D01*
G01X736596Y1076693D02*
X736595Y1076695D01*
G01X736594Y1081700D02*
Y1081709D01*
G01X736595Y1081695D02*
X736594Y1081700D01*
G01X736596Y1081693D02*
X736595Y1081695D01*
G01X737571Y1071837D02*
X737579Y1071811D01*
G01X737561Y1071863D02*
X737571Y1071837D01*
G01X737550Y1071890D02*
X737561Y1071863D01*
G01X737571Y1076837D02*
X737579Y1076811D01*
G01X737561Y1076863D02*
X737571Y1076837D01*
G01X737550Y1076890D02*
X737561Y1076863D01*
G01X737571Y1081837D02*
X737579Y1081811D01*
G01X737561Y1081863D02*
X737571Y1081837D01*
G01X737550Y1081890D02*
X737561Y1081863D01*
G01Y1071688D02*
X737542Y1071693D01*
G01X737576Y1071674D02*
X737561Y1071688D01*
G01X737581Y1071654D02*
X737576Y1071674D01*
G01X737561Y1076688D02*
X737542Y1076693D01*
G01X737576Y1076674D02*
X737561Y1076688D01*
G01X737581Y1076654D02*
X737576Y1076674D01*
G01X737561Y1081688D02*
X737542Y1081693D01*
G01X737576Y1081674D02*
X737561Y1081688D01*
G01X737581Y1081654D02*
X737576Y1081674D01*
G01X737579Y1071660D02*
Y1071667D01*
G01X737580Y1071656D02*
X737579Y1071660D01*
G01X737581Y1071654D02*
X737580Y1071656D01*
G01X737579Y1076660D02*
Y1076667D01*
G01X737580Y1076656D02*
X737579Y1076660D01*
G01X737581Y1076654D02*
X737580Y1076656D01*
G01X737579Y1081660D02*
Y1081667D01*
G01X737580Y1081656D02*
X737579Y1081660D01*
G01X737581Y1081654D02*
X737580Y1081656D01*
G01X737566Y1071685D02*
X737577Y1071669D01*
G01X737542Y1071693D02*
X737566Y1071685D01*
G01Y1076685D02*
X737577Y1076669D01*
G01X737542Y1076693D02*
X737566Y1076685D01*
G01Y1081685D02*
X737577Y1081669D01*
G01X737542Y1081693D02*
X737566Y1081685D01*
G01X728150Y1044823D02*
G03X728740Y1044232I591J0D01*
G01X735433D02*
G03X736024Y1044823I0J591D01*
G01X733268Y1046004D02*
G03Y1047972I0J984D01*
G01X730906D02*
G03Y1046004I0J-984D01*
G01X733189Y1059193D02*
G03I-1102J0D01*
G01X734646Y1053917D02*
G03X735827Y1055098I0J1181D01*
G01X728346D02*
G03X729528Y1053917I1181J0D01*
G01X733661Y1059193D02*
G03I-1574J0D01*
G01X721260Y1045413D02*
G03X723228Y1043445I1968J0D01*
G01X740945D02*
G03X742913Y1045413I0J1968D01*
G01X737579Y1082185D02*
X736594D01*
G01X736596Y1081693D02*
X741929D01*
G01Y1081654D02*
X737581D01*
G01X741929Y1080315D02*
X736596D01*
G01X736594Y1079823D02*
X737579D01*
G01Y1077185D02*
X736594D01*
G01X736596Y1076693D02*
X741929D01*
G01Y1076654D02*
X737581D01*
G01X741929Y1075315D02*
X736596D01*
G01X736594Y1074823D02*
X737579D01*
G01Y1072185D02*
X736594D01*
G01X736596Y1071693D02*
X741929D01*
G01Y1071654D02*
X737581D01*
G01X741929Y1070315D02*
X736596D01*
G01X736594Y1069823D02*
X737579D01*
G01X733071Y1067185D02*
X727559D01*
G01X734252Y1066004D02*
X726378D01*
G01X739567Y1064508D02*
X724606D01*
G01X736594Y1081889D02*
X737550Y1081890D01*
G01X737579Y1080119D02*
X736594Y1080118D01*
G01Y1076889D02*
X737550Y1076890D01*
G01X737579Y1075119D02*
X736594Y1075118D01*
G01Y1071889D02*
X737550Y1071890D01*
G01X737579Y1070119D02*
X736594Y1070118D01*
G01X735827Y1063642D02*
X738976D01*
G01X728346D02*
X724606D01*
G01Y1062264D02*
X738976D01*
G01X733268Y1060295D02*
X730906D01*
G01X733268Y1058602D02*
X730906D01*
G01X734646Y1053917D02*
X729528D01*
G01X742913Y1053878D02*
X721260D01*
G01X736024Y1050925D02*
X728150D01*
G01Y1049350D02*
X736024D01*
G01X733268Y1047972D02*
X730906D01*
G01Y1046004D02*
X733268D01*
G01X735433Y1044232D02*
X728740D01*
G01X740945Y1043445D02*
X723228D01*
G01X739567Y1064508D02*
X742913Y1061161D01*
G01X733071Y1067185D02*
X734252Y1066004D01*
G01X733268Y1058602D02*
X735578Y1054373D01*
G01X730906Y1060295D02*
X729602Y1062264D01*
G01X737579Y1071667D02*
Y1071676D01*
G01Y1076667D02*
Y1076676D01*
G01Y1081667D02*
Y1081676D01*
G01X742913Y1045413D02*
Y1061161D01*
G01X741929Y1080315D02*
Y1081693D01*
G01Y1075315D02*
Y1076693D01*
G01Y1070315D02*
Y1071693D01*
G01X739567Y1202500D02*
Y1064508D01*
G01X738976Y1204744D02*
Y1062264D01*
G01X738760Y1071693D02*
Y1070315D01*
G01Y1076693D02*
Y1075315D01*
G01Y1081693D02*
Y1080315D01*
G01X737579Y1079823D02*
Y1082185D01*
G01Y1074823D02*
Y1077185D01*
G01Y1069823D02*
Y1072185D01*
G01Y1071667D02*
Y1071811D01*
G01Y1076667D02*
Y1076811D01*
G01Y1081667D02*
Y1081811D01*
G01X736594Y1072185D02*
Y1069823D01*
G01Y1077185D02*
Y1074823D01*
G01Y1082185D02*
Y1079823D01*
G01X736024Y1050925D02*
Y1044823D01*
G01X735827Y1063642D02*
Y1055098D01*
G01X734252Y1102461D02*
Y1066004D01*
G01X733268Y1060295D02*
Y1058602D01*
G01X733071Y1103642D02*
Y1067185D01*
G01X730906Y1058602D02*
Y1060295D01*
G01X728346Y1055098D02*
Y1063642D01*
G01X728150Y1050925D02*
Y1044823D01*
G01X727559Y1067185D02*
Y1199823D01*
G01X726378Y1066004D02*
Y1201004D01*
G01X724606Y1101299D02*
Y1062264D01*
G01X721260Y1061161D02*
Y1045413D01*
G01X728595Y1054373D02*
X730906Y1058602D01*
G01X727559Y1067185D02*
X726378Y1066004D01*
G01X724606Y1064508D02*
X721260Y1061161D01*
G01X734571Y1062264D02*
X733268Y1060295D01*
G01X724154Y1123510D02*
Y1123517D01*
G01X724153Y1123506D02*
X724154Y1123510D01*
G01X724152Y1123504D02*
X724153Y1123506D01*
G01X724154Y1120361D02*
Y1120368D01*
G01X724153Y1120356D02*
X724154Y1120361D01*
G01X724152Y1120354D02*
X724153Y1120356D01*
G01X724154Y1117211D02*
Y1117218D01*
G01X724153Y1117207D02*
X724154Y1117211D01*
G01X724152Y1117205D02*
X724153Y1117207D01*
G01X724154Y1114061D02*
Y1114069D01*
G01X724153Y1114057D02*
X724154Y1114061D01*
G01X724152Y1114055D02*
X724153Y1114057D01*
G01X724154Y1110912D02*
Y1110919D01*
G01X724153Y1110907D02*
X724154Y1110912D01*
G01X724152Y1110906D02*
X724153Y1110907D01*
G01X724154Y1107762D02*
Y1107769D01*
G01X724153Y1107758D02*
X724154Y1107762D01*
G01X724152Y1107756D02*
X724153Y1107758D01*
G01X724154Y1104613D02*
Y1104620D01*
G01X724153Y1104608D02*
X724154Y1104613D01*
G01X724152Y1104606D02*
X724153Y1104608D01*
G01X723169Y1112947D02*
Y1112939D01*
G01X723168Y1112952D02*
X723169Y1112947D01*
G01X723167Y1112949D02*
X723168Y1112952D01*
G01X723169Y1106648D02*
Y1106640D01*
G01X723168Y1106652D02*
X723169Y1106648D01*
G01X723167Y1106650D02*
X723168Y1106652D01*
G01X724114Y1123548D02*
Y1123555D01*
G01X724113Y1123545D02*
X724114Y1123548D01*
G01X724113Y1123543D02*
Y1123545D01*
G01X724114Y1120399D02*
Y1120405D01*
G01X724113Y1120395D02*
X724114Y1120399D01*
G01X724113Y1120394D02*
Y1120395D01*
G01X724114Y1117249D02*
Y1117256D01*
G01X724113Y1117246D02*
X724114Y1117249D01*
G01X724113Y1117244D02*
Y1117246D01*
G01X724114Y1114100D02*
Y1114106D01*
G01X724113Y1114096D02*
X724114Y1114100D01*
G01X724113Y1114094D02*
Y1114096D01*
G01X724114Y1110950D02*
Y1110956D01*
G01X724113Y1110946D02*
X724114Y1110950D01*
G01X724113Y1110945D02*
Y1110946D01*
G01X724114Y1107800D02*
Y1107807D01*
G01X724113Y1107797D02*
X724114Y1107800D01*
G01X724113Y1107795D02*
Y1107797D01*
G01X724114Y1104651D02*
Y1104657D01*
G01X724113Y1104647D02*
X724114Y1104651D01*
G01X724113Y1104646D02*
Y1104647D01*
G01X737579Y1130308D02*
Y1130299D01*
G01X737580Y1130313D02*
X737579Y1130308D01*
G01X737581Y1130315D02*
X737580Y1130313D01*
G01X737579Y1125308D02*
Y1125299D01*
G01X737580Y1125313D02*
X737579Y1125308D01*
G01X737581Y1125315D02*
X737580Y1125313D01*
G01X737579Y1100308D02*
Y1100299D01*
G01X737580Y1100313D02*
X737579Y1100308D01*
G01X737581Y1100315D02*
X737580Y1100313D01*
G01X737579Y1095308D02*
Y1095299D01*
G01X737580Y1095313D02*
X737579Y1095308D01*
G01X737581Y1095315D02*
X737580Y1095313D01*
G01X737579Y1090308D02*
Y1090299D01*
G01X737580Y1090313D02*
X737579Y1090308D01*
G01X737581Y1090315D02*
X737580Y1090313D01*
G01X737579Y1085308D02*
Y1085299D01*
G01X737580Y1085313D02*
X737579Y1085308D01*
G01X737581Y1085315D02*
X737580Y1085313D01*
G01X723169Y1123510D02*
Y1123518D01*
G01X723168Y1123506D02*
X723169Y1123510D01*
G01X723167Y1123504D02*
X723168Y1123506D01*
G01X723169Y1120361D02*
Y1120368D01*
G01X723168Y1120356D02*
X723169Y1120361D01*
G01X723167Y1120354D02*
X723168Y1120356D01*
G01X723169Y1117211D02*
Y1117219D01*
G01X723168Y1117206D02*
X723169Y1117211D01*
G01X723167Y1117205D02*
X723168Y1117206D01*
G01X723169Y1114061D02*
Y1114069D01*
G01X723168Y1114057D02*
X723169Y1114061D01*
G01X723167Y1114055D02*
X723168Y1114057D01*
G01X723169Y1110912D02*
Y1110919D01*
G01X723168Y1110907D02*
X723169Y1110912D01*
G01X723167Y1110906D02*
X723168Y1110907D01*
G01X723169Y1107762D02*
Y1107770D01*
G01X723168Y1107757D02*
X723169Y1107762D01*
G01X723167Y1107756D02*
X723168Y1107757D01*
G01X723169Y1104613D02*
Y1104620D01*
G01X723168Y1104608D02*
X723169Y1104613D01*
G01X723167Y1104606D02*
X723168Y1104608D01*
G01X724151Y1122376D02*
X724154Y1122388D01*
G01X724144Y1122365D02*
X724151Y1122376D01*
G01X724134Y1122356D02*
X724144Y1122365D01*
G01X724151Y1116076D02*
X724154Y1116089D01*
G01X724144Y1116065D02*
X724151Y1116076D01*
G01X724134Y1116057D02*
X724144Y1116065D01*
G01X724151Y1112927D02*
X724154Y1112939D01*
G01X724144Y1112916D02*
X724151Y1112927D01*
G01X724134Y1112907D02*
X724144Y1112916D01*
G01X724151Y1109777D02*
X724154Y1109790D01*
G01X724144Y1109766D02*
X724151Y1109777D01*
G01X724134Y1109758D02*
X724144Y1109766D01*
G01X724151Y1106628D02*
X724154Y1106640D01*
G01X724144Y1106617D02*
X724151Y1106628D01*
G01X724134Y1106608D02*
X724144Y1106617D01*
G01X724151Y1103478D02*
X724154Y1103491D01*
G01X724144Y1103467D02*
X724151Y1103478D01*
G01X724134Y1103459D02*
X724144Y1103467D01*
G01X723208Y1123548D02*
Y1123555D01*
G01Y1123544D02*
Y1123548D01*
G01X723206Y1123543D02*
X723208Y1123544D01*
G01Y1120399D02*
Y1120405D01*
G01Y1120395D02*
Y1120399D01*
G01X723206Y1120394D02*
X723208Y1120395D01*
G01Y1117249D02*
Y1117256D01*
G01Y1117245D02*
Y1117249D01*
G01X723206Y1117244D02*
X723208Y1117245D01*
G01Y1114100D02*
Y1114106D01*
G01Y1114096D02*
Y1114100D01*
G01X723206Y1114094D02*
X723208Y1114096D01*
G01Y1110950D02*
Y1110956D01*
G01Y1110946D02*
Y1110950D01*
G01X723206Y1110945D02*
X723208Y1110946D01*
G01Y1107800D02*
Y1107807D01*
G01Y1107796D02*
Y1107800D01*
G01X723206Y1107795D02*
X723208Y1107796D01*
G01Y1104651D02*
Y1104657D01*
G01Y1104647D02*
Y1104651D01*
G01X723206Y1104646D02*
X723208Y1104647D01*
G01X723170Y1123524D02*
X723169Y1123518D01*
G01X723172Y1123530D02*
X723170Y1123524D01*
G01X723174Y1123536D02*
X723172Y1123530D01*
G01X723178Y1123541D02*
X723174Y1123536D01*
G01X723183Y1123546D02*
X723178Y1123541D01*
G01X723189Y1123550D02*
X723183Y1123546D01*
G01X723170Y1120374D02*
X723169Y1120368D01*
G01X723172Y1120381D02*
X723170Y1120374D01*
G01X723174Y1120386D02*
X723172Y1120381D01*
G01X723178Y1120392D02*
X723174Y1120386D01*
G01X723183Y1120396D02*
X723178Y1120392D01*
G01X723189Y1120400D02*
X723183Y1120396D01*
G01X723170Y1117225D02*
X723169Y1117219D01*
G01X723172Y1117231D02*
X723170Y1117225D01*
G01X723174Y1117237D02*
X723172Y1117231D01*
G01X723178Y1117242D02*
X723174Y1117237D01*
G01X723183Y1117246D02*
X723178Y1117242D01*
G01X723189Y1117250D02*
X723183Y1117246D01*
G01X723170Y1114075D02*
X723169Y1114069D01*
G01X723172Y1114081D02*
X723170Y1114075D01*
G01X723174Y1114087D02*
X723172Y1114081D01*
G01X723178Y1114093D02*
X723174Y1114087D01*
G01X723183Y1114097D02*
X723178Y1114093D01*
G01X723189Y1114101D02*
X723183Y1114097D01*
G01X723170Y1110926D02*
X723169Y1110919D01*
G01X723172Y1110932D02*
X723170Y1110926D01*
G01X723174Y1110937D02*
X723172Y1110932D01*
G01X723178Y1110943D02*
X723174Y1110937D01*
G01X723183Y1110947D02*
X723178Y1110943D01*
G01X723189Y1110951D02*
X723183Y1110947D01*
G01X723170Y1107776D02*
X723169Y1107770D01*
G01X723172Y1107782D02*
X723170Y1107776D01*
G01X723174Y1107788D02*
X723172Y1107782D01*
G01X723178Y1107793D02*
X723174Y1107788D01*
G01X723183Y1107798D02*
X723178Y1107793D01*
G01X723189Y1107802D02*
X723183Y1107798D01*
G01X723170Y1104626D02*
X723169Y1104620D01*
G01X723172Y1104633D02*
X723170Y1104626D01*
G01X723174Y1104638D02*
X723172Y1104633D01*
G01X723178Y1104644D02*
X723174Y1104638D01*
G01X723183Y1104648D02*
X723178Y1104644D01*
G01X723189Y1104652D02*
X723183Y1104648D01*
G01X724125Y1122364D02*
X724113Y1122362D01*
G01X724135Y1122369D02*
X724125Y1122364D01*
G01Y1119215D02*
X724113Y1119213D01*
G01X724135Y1119220D02*
X724125Y1119215D01*
G01Y1116065D02*
X724113Y1116063D01*
G01X724135Y1116070D02*
X724125Y1116065D01*
G01Y1112915D02*
X724113Y1112913D01*
G01X724135Y1112920D02*
X724125Y1112915D01*
G01Y1109766D02*
X724113Y1109764D01*
G01X724135Y1109771D02*
X724125Y1109766D01*
G01Y1106616D02*
X724113Y1106614D01*
G01X724135Y1106621D02*
X724125Y1106616D01*
G01Y1103467D02*
X724113Y1103465D01*
G01X724135Y1103472D02*
X724125Y1103467D01*
G01X723206Y1122191D02*
X723205Y1122204D01*
G01X723209Y1122178D02*
X723206Y1122191D01*
G01X723209Y1122165D02*
Y1122178D01*
G01X723206Y1119041D02*
X723205Y1119055D01*
G01X723209Y1119028D02*
X723206Y1119041D01*
G01X723209Y1119016D02*
Y1119028D01*
G01X723206Y1115892D02*
X723205Y1115905D01*
G01X723209Y1115879D02*
X723206Y1115892D01*
G01X723209Y1115866D02*
Y1115879D01*
G01X723206Y1112742D02*
X723205Y1112756D01*
G01X723209Y1112729D02*
X723206Y1112742D01*
G01X723209Y1112717D02*
Y1112729D01*
G01X723206Y1109593D02*
X723205Y1109606D01*
G01X723209Y1109580D02*
X723206Y1109593D01*
G01X723209Y1109567D02*
Y1109580D01*
G01X723206Y1106443D02*
X723205Y1106456D01*
G01X723209Y1106430D02*
X723206Y1106443D01*
G01X723209Y1106417D02*
Y1106430D01*
G01X723206Y1103293D02*
X723205Y1103307D01*
G01X723209Y1103280D02*
X723206Y1103293D01*
G01X723209Y1103268D02*
Y1103280D01*
G01X724117Y1123715D02*
X724118Y1123701D01*
G01X724113Y1123728D02*
X724117Y1123715D01*
G01X724114Y1123740D02*
X724113Y1123728D01*
G01X724117Y1120565D02*
X724118Y1120552D01*
G01X724113Y1120578D02*
X724117Y1120565D01*
G01X724114Y1120591D02*
X724113Y1120578D01*
G01X724117Y1117415D02*
X724118Y1117402D01*
G01X724113Y1117428D02*
X724117Y1117415D01*
G01X724114Y1117441D02*
X724113Y1117428D01*
G01X724117Y1114266D02*
X724118Y1114252D01*
G01X724113Y1114279D02*
X724117Y1114266D01*
G01X724114Y1114291D02*
X724113Y1114279D01*
G01X724117Y1111116D02*
X724118Y1111103D01*
G01X724113Y1111129D02*
X724117Y1111116D01*
G01X724114Y1111142D02*
X724113Y1111129D01*
G01X724117Y1107967D02*
X724118Y1107953D01*
G01X724113Y1107980D02*
X724117Y1107967D01*
G01X724114Y1107992D02*
X724113Y1107980D01*
G01X724117Y1104817D02*
X724118Y1104804D01*
G01X724113Y1104830D02*
X724117Y1104817D01*
G01X724114Y1104843D02*
X724113Y1104830D01*
G01X723169Y1109797D02*
Y1109790D01*
G01X723168Y1109802D02*
X723169Y1109797D01*
G01X723168Y1109795D02*
Y1109802D01*
G01X723169Y1119246D02*
Y1119239D01*
G01X723168Y1119251D02*
X723169Y1119246D01*
G01X723168Y1119244D02*
Y1119251D01*
G01X724113Y1122178D02*
X724114Y1122165D01*
G01X724116Y1122191D02*
X724113Y1122178D01*
G01X724117Y1122204D02*
X724116Y1122191D01*
G01X724113Y1119028D02*
X724114Y1119016D01*
G01X724116Y1119041D02*
X724113Y1119028D01*
G01X724117Y1119055D02*
X724116Y1119041D01*
G01X724113Y1115879D02*
X724114Y1115866D01*
G01X724116Y1115892D02*
X724113Y1115879D01*
G01X724117Y1115905D02*
X724116Y1115892D01*
G01X724113Y1112729D02*
X724114Y1112717D01*
G01X724116Y1112742D02*
X724113Y1112729D01*
G01X724117Y1112756D02*
X724116Y1112742D01*
G01X724113Y1109580D02*
X724114Y1109567D01*
G01X724116Y1109593D02*
X724113Y1109580D01*
G01X724117Y1109606D02*
X724116Y1109593D01*
G01X724113Y1106430D02*
X724114Y1106417D01*
G01X724116Y1106443D02*
X724113Y1106430D01*
G01X724117Y1106456D02*
X724116Y1106443D01*
G01X724113Y1103280D02*
X724114Y1103268D01*
G01X724116Y1103293D02*
X724113Y1103280D01*
G01X724117Y1103307D02*
X724116Y1103293D01*
G01X723169Y1103498D02*
Y1103491D01*
G01X723168Y1103503D02*
X723169Y1103498D01*
G01X723168Y1103496D02*
Y1103503D01*
G01X723182Y1123535D02*
X723206Y1123543D01*
G01X723171Y1123520D02*
X723182Y1123535D01*
G01X723169Y1123514D02*
X723171Y1123520D01*
G01X723182Y1120385D02*
X723206Y1120394D01*
G01X723171Y1120371D02*
X723182Y1120385D01*
G01X723169Y1120364D02*
X723171Y1120371D01*
G01X723182Y1117236D02*
X723206Y1117244D01*
G01X723171Y1117221D02*
X723182Y1117236D01*
G01X723169Y1117215D02*
X723171Y1117221D01*
G01X723182Y1114086D02*
X723206Y1114094D01*
G01X723171Y1114072D02*
X723182Y1114086D01*
G01X723169Y1114065D02*
X723171Y1114072D01*
G01X723182Y1110937D02*
X723206Y1110945D01*
G01X723171Y1110922D02*
X723182Y1110937D01*
G01X723169Y1110915D02*
X723171Y1110922D01*
G01X723182Y1107787D02*
X723206Y1107795D01*
G01X723171Y1107772D02*
X723182Y1107787D01*
G01X723169Y1107766D02*
X723171Y1107772D01*
G01X723182Y1104637D02*
X723206Y1104646D01*
G01X723171Y1104623D02*
X723182Y1104637D01*
G01X723169Y1104616D02*
X723171Y1104623D01*
G01X737546Y1086791D02*
X737550Y1086890D01*
G01X737540Y1086719D02*
X737546Y1086791D01*
G01X737542Y1086693D02*
X737540Y1086719D01*
G01X737546Y1091791D02*
X737550Y1091890D01*
G01X737540Y1091719D02*
X737546Y1091791D01*
G01X737542Y1091693D02*
X737540Y1091719D01*
G01X737546Y1096791D02*
X737550Y1096890D01*
G01X737540Y1096719D02*
X737546Y1096791D01*
G01X737542Y1096693D02*
X737540Y1096719D01*
G01X737546Y1101791D02*
X737550Y1101890D01*
G01X737540Y1101719D02*
X737546Y1101791D01*
G01X737542Y1101693D02*
X737540Y1101719D01*
G01X737546Y1126791D02*
X737550Y1126890D01*
G01X737540Y1126719D02*
X737546Y1126791D01*
G01X737542Y1126693D02*
X737540Y1126719D01*
G01X723169Y1116096D02*
Y1116089D01*
G01X723168Y1116101D02*
X723169Y1116096D01*
G01Y1116092D02*
X723168Y1116101D01*
G01X723209Y1123728D02*
Y1123740D01*
G01X723206Y1123715D02*
X723209Y1123728D01*
G01X723206Y1123701D02*
Y1123715D01*
G01X723209Y1120578D02*
Y1120591D01*
G01X723206Y1120565D02*
X723209Y1120578D01*
G01X723206Y1120552D02*
Y1120565D01*
G01X723209Y1117429D02*
Y1117441D01*
G01X723206Y1117416D02*
X723209Y1117429D01*
G01X723206Y1117402D02*
Y1117416D01*
G01X723209Y1114279D02*
Y1114291D01*
G01X723206Y1114266D02*
X723209Y1114279D01*
G01X723206Y1114252D02*
Y1114266D01*
G01X723209Y1111130D02*
Y1111142D01*
G01X723206Y1111117D02*
X723209Y1111130D01*
G01X723206Y1111103D02*
Y1111117D01*
G01X723209Y1107980D02*
Y1107992D01*
G01X723206Y1107967D02*
X723209Y1107980D01*
G01X723206Y1107953D02*
Y1107967D01*
G01X723209Y1104830D02*
Y1104843D01*
G01X723206Y1104817D02*
X723209Y1104830D01*
G01X723206Y1104804D02*
Y1104817D01*
G01X736595Y1130313D02*
X736596Y1130315D01*
G01X736594Y1130308D02*
X736595Y1130313D01*
G01X736594Y1130299D02*
Y1130308D01*
G01X736595Y1125313D02*
X736596Y1125315D01*
G01X736594Y1125308D02*
X736595Y1125313D01*
G01X736594Y1125299D02*
Y1125308D01*
G01X736595Y1100313D02*
X736596Y1100315D01*
G01X736594Y1100308D02*
X736595Y1100313D01*
G01X736594Y1100299D02*
Y1100308D01*
G01X736595Y1095313D02*
X736596Y1095315D01*
G01X736594Y1095308D02*
X736595Y1095313D01*
G01X736594Y1095299D02*
Y1095308D01*
G01X736595Y1090313D02*
X736596Y1090315D01*
G01X736594Y1090308D02*
X736595Y1090313D01*
G01X736594Y1090299D02*
Y1090308D01*
G01X736595Y1085313D02*
X736596Y1085315D01*
G01X736594Y1085308D02*
X736595Y1085313D01*
G01X736594Y1085299D02*
Y1085308D01*
G01X723169Y1122396D02*
Y1122388D01*
G01X723168Y1122400D02*
X723169Y1122396D01*
G01X723168Y1122393D02*
Y1122400D01*
G01X724146Y1110927D02*
X724139Y1110935D01*
G01X724150Y1110917D02*
X724146Y1110927D01*
G01X724152Y1110906D02*
X724150Y1110917D01*
G01X724146Y1104628D02*
X724139Y1104636D01*
G01X724151Y1104617D02*
X724146Y1104628D01*
G01X724152Y1104606D02*
X724151Y1104617D01*
G01X724146Y1107777D02*
X724139Y1107786D01*
G01X724151Y1107767D02*
X724146Y1107777D01*
G01X724152Y1107756D02*
X724151Y1107767D01*
G01X724146Y1114076D02*
X724139Y1114085D01*
G01X724151Y1114066D02*
X724146Y1114076D01*
G01X724152Y1114055D02*
X724151Y1114066D01*
G01X724146Y1117226D02*
X724139Y1117235D01*
G01X724151Y1117216D02*
X724146Y1117226D01*
G01X724152Y1117205D02*
X724151Y1117216D01*
G01X724146Y1120376D02*
X724139Y1120384D01*
G01X724151Y1120365D02*
X724146Y1120376D01*
G01X724152Y1120354D02*
X724151Y1120365D01*
G01X724146Y1123525D02*
X724139Y1123534D01*
G01X724151Y1123515D02*
X724146Y1123525D01*
G01X724152Y1123504D02*
X724151Y1123515D01*
G01X724115Y1103459D02*
Y1103454D01*
G01X724113Y1103463D02*
X724115Y1103459D01*
G01X724113Y1103465D02*
Y1103463D01*
G01X724115Y1106609D02*
Y1106603D01*
G01X724113Y1106613D02*
X724115Y1106609D01*
G01X724113Y1106614D02*
Y1106613D01*
G01X724115Y1109759D02*
Y1109753D01*
G01X724113Y1109763D02*
X724115Y1109759D01*
G01X724113Y1109764D02*
Y1109763D01*
G01X724115Y1112908D02*
Y1112902D01*
G01X724113Y1112912D02*
X724115Y1112908D01*
G01X724113Y1112913D02*
Y1112912D01*
G01X724115Y1116058D02*
Y1116052D01*
G01X724113Y1116062D02*
X724115Y1116058D01*
G01X724113Y1116063D02*
Y1116062D01*
G01X736594Y1086700D02*
Y1086709D01*
G01X736595Y1086695D02*
X736594Y1086700D01*
G01X736596Y1086693D02*
X736595Y1086695D01*
G01X736594Y1091700D02*
Y1091709D01*
G01X736595Y1091695D02*
X736594Y1091700D01*
G01X736596Y1091693D02*
X736595Y1091695D01*
G01X736594Y1096700D02*
Y1096709D01*
G01X736595Y1096695D02*
X736594Y1096700D01*
G01X736596Y1096693D02*
X736595Y1096695D01*
G01X736594Y1101700D02*
Y1101709D01*
G01X736595Y1101695D02*
X736594Y1101700D01*
G01X736596Y1101693D02*
X736595Y1101695D01*
G01X737571Y1086837D02*
X737579Y1086811D01*
G01X737561Y1086863D02*
X737571Y1086837D01*
G01X737550Y1086890D02*
X737561Y1086863D01*
G01X737571Y1091837D02*
X737579Y1091811D01*
G01X737561Y1091863D02*
X737571Y1091837D01*
G01X737550Y1091890D02*
X737561Y1091863D01*
G01X737571Y1096837D02*
X737579Y1096811D01*
G01X737561Y1096863D02*
X737571Y1096837D01*
G01X737550Y1096890D02*
X737561Y1096863D01*
G01X737571Y1101837D02*
X737579Y1101811D01*
G01X737561Y1101863D02*
X737571Y1101837D01*
G01X737550Y1101890D02*
X737561Y1101863D01*
G01X723187Y1112919D02*
X723206Y1112913D01*
G01X723174Y1112931D02*
X723187Y1112919D01*
G01X723167Y1112949D02*
X723174Y1112931D01*
G01X737561Y1086688D02*
X737542Y1086693D01*
G01X737576Y1086674D02*
X737561Y1086688D01*
G01X737581Y1086654D02*
X737576Y1086674D01*
G01X737561Y1091688D02*
X737542Y1091693D01*
G01X737576Y1091674D02*
X737561Y1091688D01*
G01X737581Y1091654D02*
X737576Y1091674D01*
G01X737561Y1096688D02*
X737542Y1096693D01*
G01X737576Y1096674D02*
X737561Y1096688D01*
G01X737581Y1096654D02*
X737576Y1096674D01*
G01X737561Y1101688D02*
X737542Y1101693D01*
G01X737576Y1101674D02*
X737561Y1101688D01*
G01X737581Y1101654D02*
X737576Y1101674D01*
G01X737561Y1126688D02*
X737542Y1126693D01*
G01X737576Y1126674D02*
X737561Y1126688D01*
G01X737581Y1126654D02*
X737576Y1126674D01*
G01X737579Y1086660D02*
Y1086667D01*
G01X737580Y1086656D02*
X737579Y1086660D01*
G01X737581Y1086654D02*
X737580Y1086656D01*
G01X737579Y1091660D02*
Y1091667D01*
G01X737580Y1091656D02*
X737579Y1091660D01*
G01X737581Y1091654D02*
X737580Y1091656D01*
G01X737579Y1096660D02*
Y1096667D01*
G01X737580Y1096656D02*
X737579Y1096660D01*
G01X737581Y1096654D02*
X737580Y1096656D01*
G01X737579Y1101660D02*
Y1101667D01*
G01X737580Y1101656D02*
X737579Y1101660D01*
G01X737581Y1101654D02*
X737580Y1101656D01*
G01X723192Y1106617D02*
X723206Y1106614D01*
G01X723181Y1106624D02*
X723192Y1106617D01*
G01X723169Y1106643D02*
X723181Y1106624D01*
G01X723192Y1116066D02*
X723206Y1116063D01*
G01X723180Y1116073D02*
X723192Y1116066D01*
G01X723169Y1116091D02*
X723180Y1116073D01*
G01X723192Y1109767D02*
X723206Y1109764D01*
G01X723180Y1109774D02*
X723192Y1109767D01*
G01X723168Y1109794D02*
X723180Y1109774D01*
G01X723192Y1119215D02*
X723206Y1119213D01*
G01X723180Y1119223D02*
X723192Y1119215D01*
G01X723168Y1119243D02*
X723180Y1119223D01*
G01X724154Y1103498D02*
Y1103491D01*
G01X724153Y1103503D02*
X724154Y1103498D01*
G01X724152Y1103504D02*
X724153Y1103503D01*
G01X724154Y1106648D02*
Y1106640D01*
G01X724153Y1106652D02*
X724154Y1106648D01*
G01X724152Y1106654D02*
X724153Y1106652D01*
G01X724154Y1109797D02*
Y1109790D01*
G01X724153Y1109802D02*
X724154Y1109797D01*
G01X724152Y1109803D02*
X724153Y1109802D01*
G01X724154Y1112947D02*
Y1112939D01*
G01X724153Y1112952D02*
X724154Y1112947D01*
G01X724152Y1112953D02*
X724153Y1112952D01*
G01X724154Y1116096D02*
Y1116089D01*
G01X724153Y1116101D02*
X724154Y1116096D01*
G01X724152Y1116102D02*
X724153Y1116101D01*
G01X724154Y1119246D02*
Y1119239D01*
G01X724153Y1119251D02*
X724154Y1119246D01*
G01X724152Y1119252D02*
X724153Y1119251D01*
G01X724154Y1122396D02*
Y1122388D01*
G01X724153Y1122400D02*
X724154Y1122396D01*
G01X724152Y1122402D02*
X724153Y1122400D01*
G01X723192Y1122365D02*
X723206Y1122362D01*
G01X723179Y1122373D02*
X723192Y1122365D01*
G01X723168Y1122393D02*
X723179Y1122373D01*
G01X723191Y1103468D02*
X723206Y1103465D01*
G01X723178Y1103476D02*
X723191Y1103468D01*
G01X723168Y1103496D02*
X723178Y1103476D01*
G01X724153Y1104627D02*
X724154Y1104620D01*
G01X724151Y1104633D02*
X724153Y1104627D01*
G01X724148Y1104639D02*
X724151Y1104633D01*
G01X724153Y1107776D02*
X724154Y1107770D01*
G01X724151Y1107783D02*
X724153Y1107776D01*
G01X724148Y1107789D02*
X724151Y1107783D01*
G01X724153Y1110926D02*
X724154Y1110919D01*
G01X724151Y1110932D02*
X724153Y1110926D01*
G01X724148Y1110938D02*
X724151Y1110932D01*
G01X724153Y1114076D02*
X724154Y1114069D01*
G01X724151Y1114082D02*
X724153Y1114076D01*
G01X724148Y1114088D02*
X724151Y1114082D01*
G01X724153Y1117225D02*
X724154Y1117219D01*
G01X724151Y1117231D02*
X724153Y1117225D01*
G01X724148Y1117237D02*
X724151Y1117231D01*
G01X724153Y1120375D02*
X724154Y1120368D01*
G01X724151Y1120381D02*
X724153Y1120375D01*
G01X724148Y1120387D02*
X724151Y1120381D01*
G01X724153Y1123524D02*
X724154Y1123518D01*
G01X724151Y1123531D02*
X724153Y1123524D01*
G01X724148Y1123537D02*
X724151Y1123531D01*
G01X724115Y1122357D02*
Y1122351D01*
G01X724113Y1122361D02*
X724115Y1122357D01*
G01X724113Y1122362D02*
Y1122361D01*
G01X736594Y1126700D02*
Y1126709D01*
G01X736595Y1126695D02*
X736594Y1126700D01*
G01X736596Y1126693D02*
X736595Y1126695D01*
G01X737571Y1126837D02*
X737579Y1126811D01*
G01X737561Y1126863D02*
X737571Y1126837D01*
G01X737550Y1126890D02*
X737561Y1126863D01*
G01X723208Y1103460D02*
X723209Y1103454D01*
G01X723207Y1103463D02*
X723208Y1103460D01*
G01X723206Y1103465D02*
X723207Y1103463D01*
G01X723208Y1106609D02*
X723209Y1106603D01*
G01X723207Y1106613D02*
X723208Y1106609D01*
G01X723206Y1106614D02*
X723207Y1106613D01*
G01X723208Y1109759D02*
X723209Y1109753D01*
G01X723207Y1109763D02*
X723208Y1109759D01*
G01X723206Y1109764D02*
X723207Y1109763D01*
G01X723208Y1112909D02*
X723209Y1112902D01*
G01X723207Y1112912D02*
X723208Y1112909D01*
G01X723206Y1112913D02*
X723207Y1112912D01*
G01X723208Y1116058D02*
X723209Y1116052D01*
G01X723207Y1116062D02*
X723208Y1116058D01*
G01X723206Y1116063D02*
X723207Y1116062D01*
G01X723208Y1119208D02*
X723209Y1119202D01*
G01X723207Y1119211D02*
X723208Y1119208D01*
G01X723206Y1119213D02*
X723207Y1119211D01*
G01X723208Y1122357D02*
X723209Y1122351D01*
G01X723207Y1122361D02*
X723208Y1122357D01*
G01X723206Y1122362D02*
X723207Y1122361D01*
G01X737579Y1126660D02*
Y1126667D01*
G01X737580Y1126656D02*
X737579Y1126660D01*
G01X737581Y1126654D02*
X737580Y1126656D01*
G01X724122Y1110944D02*
X724113Y1110945D01*
G01X724131Y1110941D02*
X724122Y1110944D01*
G01X724139Y1110935D02*
X724131Y1110941D01*
G01X724122Y1104644D02*
X724113Y1104646D01*
G01X724131Y1104641D02*
X724122Y1104644D01*
G01X724139Y1104636D02*
X724131Y1104641D01*
G01X724122Y1107794D02*
X724113Y1107795D01*
G01X724131Y1107791D02*
X724122Y1107794D01*
G01X724139Y1107786D02*
X724131Y1107791D01*
G01X724122Y1114093D02*
X724113Y1114094D01*
G01X724131Y1114090D02*
X724122Y1114093D01*
G01X724139Y1114085D02*
X724131Y1114090D01*
G01X724122Y1117243D02*
X724113Y1117244D01*
G01X724131Y1117240D02*
X724122Y1117243D01*
G01X724139Y1117235D02*
X724131Y1117240D01*
G01X724122Y1120393D02*
X724113Y1120394D01*
G01X724131Y1120389D02*
X724122Y1120393D01*
G01X724139Y1120384D02*
X724131Y1120389D01*
G01X724122Y1123542D02*
X724113Y1123543D01*
G01X724131Y1123539D02*
X724122Y1123542D01*
G01X724139Y1123534D02*
X724131Y1123539D01*
G01X723169Y1106644D02*
Y1106640D01*
G01X723171Y1106638D02*
X723169Y1106644D01*
G01X723183Y1106622D02*
X723171Y1106638D01*
G01X723207Y1106614D02*
X723183Y1106622D01*
G01X723169Y1109794D02*
Y1109790D01*
G01X723171Y1109787D02*
X723169Y1109794D01*
G01X723182Y1109772D02*
X723171Y1109787D01*
G01X723207Y1109764D02*
X723182Y1109772D01*
G01X723169Y1116093D02*
Y1116089D01*
G01X723171Y1116087D02*
X723169Y1116093D01*
G01X723182Y1116071D02*
X723171Y1116087D01*
G01X723207Y1116063D02*
X723182Y1116071D01*
G01X723169Y1119243D02*
Y1119239D01*
G01X723171Y1119236D02*
X723169Y1119243D01*
G01X723182Y1119221D02*
X723171Y1119236D01*
G01X723207Y1119213D02*
X723182Y1119221D01*
G01X723169Y1103494D02*
Y1103491D01*
G01X723171Y1103488D02*
X723169Y1103494D01*
G01X723182Y1103473D02*
X723171Y1103488D01*
G01X723207Y1103465D02*
X723182Y1103473D01*
G01X723169Y1122392D02*
Y1122388D01*
G01X723171Y1122386D02*
X723169Y1122392D01*
G01X723182Y1122370D02*
X723171Y1122386D01*
G01X723207Y1122362D02*
X723182Y1122370D01*
G01X737566Y1086685D02*
X737577Y1086669D01*
G01X737542Y1086693D02*
X737566Y1086685D01*
G01Y1091685D02*
X737577Y1091669D01*
G01X737542Y1091693D02*
X737566Y1091685D01*
G01Y1096685D02*
X737577Y1096669D01*
G01X737542Y1096693D02*
X737566Y1096685D01*
G01Y1101685D02*
X737577Y1101669D01*
G01X737542Y1101693D02*
X737566Y1101685D01*
G01Y1126685D02*
X737577Y1126669D01*
G01X737542Y1126693D02*
X737566Y1126685D01*
G01X723169Y1112943D02*
Y1112939D01*
G01X723170Y1112938D02*
X723169Y1112943D01*
G01X723181Y1112923D02*
X723170Y1112938D01*
G01X723204Y1112914D02*
X723181Y1112923D01*
G01X724153Y1119231D02*
X724154Y1119239D01*
G01X724150Y1119224D02*
X724153Y1119231D01*
G01X724147Y1119218D02*
X724150Y1119224D01*
G01X724142Y1119212D02*
X724147Y1119218D01*
G01X724136Y1119207D02*
X724142Y1119212D01*
G01X724129Y1119204D02*
X724136Y1119207D01*
G01X724122Y1119202D02*
X724129Y1119204D01*
G01X724114Y1119202D02*
X724122D01*
G01X724131Y1103457D02*
X724134Y1103459D01*
G01X724128Y1103456D02*
X724131Y1103457D01*
G01X724125Y1103455D02*
X724128Y1103456D01*
G01X724121Y1103454D02*
X724125Y1103455D01*
G01X724118Y1103454D02*
X724121D01*
G01X724114D02*
X724118D01*
G01X723192Y1104654D02*
X723189Y1104652D01*
G01X723195Y1104655D02*
X723192Y1104654D01*
G01X723198Y1104656D02*
X723195Y1104655D01*
G01X723202Y1104656D02*
X723198D01*
G01X723205Y1104657D02*
X723202Y1104656D01*
G01X723209Y1104657D02*
X723205D01*
G01X724131Y1106607D02*
X724134Y1106608D01*
G01X724128Y1106606D02*
X724131Y1106607D01*
G01X724125Y1106604D02*
X724128Y1106606D01*
G01X724121Y1106604D02*
X724125D01*
G01X724118Y1106603D02*
X724121Y1106604D01*
G01X724114Y1106603D02*
X724118D01*
G01X723192Y1107803D02*
X723189Y1107802D01*
G01X723195Y1107804D02*
X723192Y1107803D01*
G01X723198Y1107806D02*
X723195Y1107804D01*
G01X723202Y1107806D02*
X723198D01*
G01X723205Y1107807D02*
X723202Y1107806D01*
G01X723209Y1107807D02*
X723205D01*
G01X724131Y1109756D02*
X724134Y1109758D01*
G01X724128Y1109755D02*
X724131Y1109756D01*
G01X724125Y1109754D02*
X724128Y1109755D01*
G01X724121Y1109753D02*
X724125Y1109754D01*
G01X724118Y1109753D02*
X724121D01*
G01X724114D02*
X724118D01*
G01X723192Y1110953D02*
X723189Y1110951D01*
G01X723195Y1110954D02*
X723192Y1110953D01*
G01X723198Y1110955D02*
X723195Y1110954D01*
G01X723202Y1110956D02*
X723198Y1110955D01*
G01X723205Y1110956D02*
X723202D01*
G01X723209D02*
X723205D01*
G01X724131Y1112906D02*
X724134Y1112907D01*
G01X724128Y1112905D02*
X724131Y1112906D01*
G01X724125Y1112904D02*
X724128Y1112905D01*
G01X724121Y1112903D02*
X724125Y1112904D01*
G01X724118Y1112902D02*
X724121Y1112903D01*
G01X724114Y1112902D02*
X724118D01*
G01X723192Y1114102D02*
X723189Y1114101D01*
G01X723195Y1114104D02*
X723192Y1114102D01*
G01X723198Y1114105D02*
X723195Y1114104D01*
G01X723202Y1114105D02*
X723198D01*
G01X723205Y1114106D02*
X723202Y1114105D01*
G01X723209Y1114106D02*
X723205D01*
G01X724131Y1116056D02*
X724134Y1116057D01*
G01X724128Y1116054D02*
X724131Y1116056D01*
G01X724125Y1116053D02*
X724128Y1116054D01*
G01X724121Y1116052D02*
X724125Y1116053D01*
G01X724118Y1116052D02*
X724121D01*
G01X724114D02*
X724118D01*
G01X723192Y1117252D02*
X723189Y1117250D01*
G01X723195Y1117253D02*
X723192Y1117252D01*
G01X723198Y1117254D02*
X723195Y1117253D01*
G01X723202Y1117255D02*
X723198Y1117254D01*
G01X723205Y1117256D02*
X723202Y1117255D01*
G01X723209Y1117256D02*
X723205D01*
G01X723192Y1120402D02*
X723189Y1120400D01*
G01X723195Y1120403D02*
X723192Y1120402D01*
G01X723198Y1120404D02*
X723195Y1120403D01*
G01X723202Y1120404D02*
X723198D01*
G01X723205Y1120405D02*
X723202Y1120404D01*
G01X723209Y1120405D02*
X723205D01*
G01X724131Y1122355D02*
X724134Y1122356D01*
G01X724128Y1122354D02*
X724131Y1122355D01*
G01X724125Y1122352D02*
X724128Y1122354D01*
G01X724121Y1122352D02*
X724125D01*
G01X724118Y1122351D02*
X724121Y1122352D01*
G01X724114Y1122351D02*
X724118D01*
G01X723192Y1123551D02*
X723189Y1123550D01*
G01X723195Y1123552D02*
X723192Y1123551D01*
G01X723198Y1123554D02*
X723195Y1123552D01*
G01X723202Y1123554D02*
X723198D01*
G01X723205Y1123555D02*
X723202Y1123554D01*
G01X723209Y1123555D02*
X723205D01*
G01X722422Y1106654D02*
X721988D01*
G01X722796D02*
X722422D01*
G01Y1112953D02*
X721988D01*
G01X722796D02*
X722422D01*
G01Y1116102D02*
X721988D01*
G01X722795D02*
X722422D01*
G01X724144Y1104644D02*
X724148Y1104639D01*
G01X724139Y1104648D02*
X724144Y1104644D01*
G01X724133Y1104652D02*
X724139Y1104648D01*
G01X724128Y1104655D02*
X724133Y1104652D01*
G01X724121Y1104657D02*
X724128Y1104655D01*
G01X724114Y1104657D02*
X724121D01*
G01X724144Y1107794D02*
X724148Y1107789D01*
G01X724139Y1107798D02*
X724144Y1107794D01*
G01X724133Y1107802D02*
X724139Y1107798D01*
G01X724128Y1107804D02*
X724133Y1107802D01*
G01X724121Y1107806D02*
X724128Y1107804D01*
G01X724114Y1107807D02*
X724121Y1107806D01*
G01X724144Y1110943D02*
X724148Y1110938D01*
G01X724139Y1110948D02*
X724144Y1110943D01*
G01X724133Y1110952D02*
X724139Y1110948D01*
G01X724128Y1110954D02*
X724133Y1110952D01*
G01X724121Y1110956D02*
X724128Y1110954D01*
G01X724114Y1110956D02*
X724121D01*
G01X724144Y1114093D02*
X724148Y1114088D01*
G01X724139Y1114097D02*
X724144Y1114093D01*
G01X724133Y1114101D02*
X724139Y1114097D01*
G01X724128Y1114104D02*
X724133Y1114101D01*
G01X724121Y1114106D02*
X724128Y1114104D01*
G01X724114Y1114106D02*
X724121D01*
G01X724144Y1117243D02*
X724148Y1117237D01*
G01X724139Y1117247D02*
X724144Y1117243D01*
G01X724133Y1117251D02*
X724139Y1117247D01*
G01X724128Y1117253D02*
X724133Y1117251D01*
G01X724121Y1117255D02*
X724128Y1117253D01*
G01X724114Y1117256D02*
X724121Y1117255D01*
G01X724144Y1120392D02*
X724148Y1120387D01*
G01X724139Y1120396D02*
X724144Y1120392D01*
G01X724133Y1120400D02*
X724139Y1120396D01*
G01X724128Y1120403D02*
X724133Y1120400D01*
G01X724121Y1120405D02*
X724128Y1120403D01*
G01X724114Y1120405D02*
X724121D01*
G01X724144Y1123542D02*
X724148Y1123537D01*
G01X724139Y1123546D02*
X724144Y1123542D01*
G01X724133Y1123550D02*
X724139Y1123546D01*
G01X724128Y1123552D02*
X724133Y1123550D01*
G01X724121Y1123554D02*
X724128Y1123552D01*
G01X724114Y1123555D02*
X724121Y1123554D01*
G01X723170Y1103483D02*
X723169Y1103491D01*
G01X723172Y1103476D02*
X723170Y1103483D01*
G01X723176Y1103470D02*
X723172Y1103476D01*
G01X723181Y1103464D02*
X723176Y1103470D01*
G01X723187Y1103459D02*
X723181Y1103464D01*
G01X723194Y1103456D02*
X723187Y1103459D01*
G01X723201Y1103454D02*
X723194Y1103456D01*
G01X723209Y1103454D02*
X723201D01*
G01X723170Y1106633D02*
X723169Y1106640D01*
G01X723172Y1106626D02*
X723170Y1106633D01*
G01X723176Y1106620D02*
X723172Y1106626D01*
G01X723181Y1106614D02*
X723176Y1106620D01*
G01X723187Y1106609D02*
X723181Y1106614D01*
G01X723194Y1106606D02*
X723187Y1106609D01*
G01X723201Y1106604D02*
X723194Y1106606D01*
G01X723209Y1106603D02*
X723201Y1106604D01*
G01X723170Y1109782D02*
X723169Y1109790D01*
G01X723172Y1109776D02*
X723170Y1109782D01*
G01X723176Y1109769D02*
X723172Y1109776D01*
G01X723181Y1109763D02*
X723176Y1109769D01*
G01X723187Y1109759D02*
X723181Y1109763D01*
G01X723194Y1109756D02*
X723187Y1109759D01*
G01X723201Y1109754D02*
X723194Y1109756D01*
G01X723209Y1109753D02*
X723201Y1109754D01*
G01X723170Y1112932D02*
X723169Y1112939D01*
G01X723172Y1112925D02*
X723170Y1112932D01*
G01X723176Y1112919D02*
X723172Y1112925D01*
G01X723181Y1112913D02*
X723176Y1112919D01*
G01X723187Y1112908D02*
X723181Y1112913D01*
G01X723194Y1112905D02*
X723187Y1112908D01*
G01X723201Y1112903D02*
X723194Y1112905D01*
G01X723209Y1112902D02*
X723201Y1112903D01*
G01X723170Y1116081D02*
X723169Y1116089D01*
G01X723172Y1116075D02*
X723170Y1116081D01*
G01X723176Y1116069D02*
X723172Y1116075D01*
G01X723181Y1116063D02*
X723176Y1116069D01*
G01X723187Y1116058D02*
X723181Y1116063D01*
G01X723194Y1116055D02*
X723187Y1116058D01*
G01X723201Y1116053D02*
X723194Y1116055D01*
G01X723209Y1116052D02*
X723201Y1116053D01*
G01X723170Y1119231D02*
X723169Y1119239D01*
G01X723172Y1119224D02*
X723170Y1119231D01*
G01X723176Y1119218D02*
X723172Y1119224D01*
G01X723181Y1119212D02*
X723176Y1119218D01*
G01X723187Y1119207D02*
X723181Y1119212D01*
G01X723194Y1119204D02*
X723187Y1119207D01*
G01X723201Y1119202D02*
X723194Y1119204D01*
G01X723209Y1119202D02*
X723201D01*
G01X723170Y1122381D02*
X723169Y1122388D01*
G01X723172Y1122374D02*
X723170Y1122381D01*
G01X723176Y1122368D02*
X723172Y1122374D01*
G01X723181Y1122362D02*
X723176Y1122368D01*
G01X723187Y1122357D02*
X723181Y1122362D01*
G01X723194Y1122354D02*
X723187Y1122357D01*
G01X723201Y1122352D02*
X723194Y1122354D01*
G01X723209Y1122351D02*
X723201Y1122352D01*
G01X724123Y1104644D02*
X724133Y1104640D01*
G01X724113Y1104646D02*
X724123Y1104644D01*
G01Y1107794D02*
X724133Y1107790D01*
G01X724113Y1107795D02*
X724123Y1107794D01*
G01Y1110944D02*
X724133Y1110939D01*
G01X724113Y1110945D02*
X724123Y1110944D01*
G01Y1114093D02*
X724133Y1114089D01*
G01X724113Y1114094D02*
X724123Y1114093D01*
G01Y1117243D02*
X724133Y1117239D01*
G01X724113Y1117244D02*
X724123Y1117243D01*
G01Y1120393D02*
X724133Y1120388D01*
G01X724113Y1120394D02*
X724123Y1120393D01*
G01Y1123542D02*
X724133Y1123538D01*
G01X724113Y1123543D02*
X724123Y1123542D01*
G01X723172Y1104626D02*
X723167Y1104606D01*
G01X723187Y1104641D02*
X723172Y1104626D01*
G01X723206Y1104646D02*
X723187Y1104641D01*
G01X723172Y1107776D02*
X723167Y1107756D01*
G01X723187Y1107790D02*
X723172Y1107776D01*
G01X723206Y1107795D02*
X723187Y1107790D01*
G01X723172Y1110925D02*
X723167Y1110906D01*
G01X723187Y1110940D02*
X723172Y1110925D01*
G01X723206Y1110945D02*
X723187Y1110940D01*
G01X723172Y1114075D02*
X723167Y1114055D01*
G01X723187Y1114089D02*
X723172Y1114075D01*
G01X723206Y1114094D02*
X723187Y1114089D01*
G01X723172Y1117224D02*
X723167Y1117205D01*
G01X723187Y1117239D02*
X723172Y1117224D01*
G01X723206Y1117244D02*
X723187Y1117239D01*
G01X723172Y1120374D02*
X723167Y1120354D01*
G01X723187Y1120389D02*
X723172Y1120374D01*
G01X723206Y1120394D02*
X723187Y1120389D01*
G01X723172Y1123524D02*
X723167Y1123504D01*
G01X723187Y1123538D02*
X723172Y1123524D01*
G01X723206Y1123543D02*
X723187Y1123538D01*
G01X724147Y1103484D02*
X724152Y1103504D01*
G01X724132Y1103470D02*
X724147Y1103484D01*
G01X724113Y1103465D02*
X724132Y1103470D01*
G01X724147Y1106634D02*
X724152Y1106654D01*
G01X724132Y1106620D02*
X724147Y1106634D01*
G01X724113Y1106614D02*
X724132Y1106620D01*
G01X724147Y1109783D02*
X724152Y1109803D01*
G01X724132Y1109769D02*
X724147Y1109783D01*
G01X724113Y1109764D02*
X724132Y1109769D01*
G01X724147Y1112933D02*
X724152Y1112953D01*
G01X724132Y1112919D02*
X724147Y1112933D01*
G01X724113Y1112913D02*
X724132Y1112919D01*
G01X724147Y1116083D02*
X724152Y1116102D01*
G01X724132Y1116069D02*
X724147Y1116083D01*
G01X724113Y1116063D02*
X724132Y1116069D01*
G01X724147Y1119232D02*
X724152Y1119252D01*
G01X724132Y1119218D02*
X724147Y1119232D01*
G01X724113Y1119213D02*
X724132Y1119218D01*
G01X724147Y1122382D02*
X724152Y1122402D01*
G01X724132Y1122368D02*
X724147Y1122382D01*
G01X724113Y1122362D02*
X724132Y1122368D01*
G01X723056Y1122402D02*
X723168Y1122393D01*
G01X723167Y1112949D02*
X723056Y1112953D01*
G01X723167Y1106650D02*
X723056Y1106654D01*
G01X723167Y1116099D02*
X723056Y1116102D01*
G01X741929Y1130315D02*
X736596D01*
G01X736594Y1129823D02*
X737579D01*
G01Y1127185D02*
X736594D01*
G01X736596Y1126693D02*
X741929D01*
G01Y1126654D02*
X737581D01*
G01X724606Y1125709D02*
X721260D01*
G01X741929Y1125315D02*
X736596D01*
G01X736594Y1124823D02*
X737579D01*
G01X734252Y1124547D02*
X738189D01*
G01X724114Y1123740D02*
X723209D01*
G01X724154Y1123701D02*
X723169D01*
G01X724113Y1123543D02*
X718228D01*
G01Y1123504D02*
X724152D01*
G01X733071Y1123366D02*
X737008D01*
G01X724152Y1122402D02*
X718228D01*
G01X724113Y1122362D02*
X718228D01*
G01X723169Y1122205D02*
X724154D01*
G01X723209Y1122165D02*
X724114D01*
G01Y1120591D02*
X723209D01*
G01X724154Y1120551D02*
X723169D01*
G01X724113Y1120394D02*
X718228D01*
G01Y1120354D02*
X724152D01*
G01Y1119252D02*
X718228D01*
G01X724113Y1119213D02*
X718228D01*
G01X723169Y1119055D02*
X724154D01*
G01X723209Y1119016D02*
X724114D01*
G01Y1117441D02*
X723209D01*
G01X724154Y1117402D02*
X723169D01*
G01X724113Y1117244D02*
X718228D01*
G01Y1117205D02*
X724152D01*
G01Y1116102D02*
X718228D01*
G01X724113Y1116063D02*
X718228D01*
G01X723169Y1115906D02*
X724154D01*
G01X723209Y1115866D02*
X724114D01*
G01Y1114291D02*
X723209D01*
G01X724154Y1114252D02*
X723169D01*
G01X724113Y1114094D02*
X718228D01*
G01Y1114055D02*
X724152D01*
G01Y1112953D02*
X718228D01*
G01X724113Y1112913D02*
X718228D01*
G01X723169Y1112756D02*
X724154D01*
G01X723209Y1112717D02*
X724114D01*
G01Y1111142D02*
X723209D01*
G01X724154Y1111102D02*
X723169D01*
G01X724113Y1110945D02*
X718228D01*
G01Y1110906D02*
X724152D01*
G01Y1109803D02*
X718228D01*
G01X724113Y1109764D02*
X718228D01*
G01X723169Y1109606D02*
X724154D01*
G01X723209Y1109567D02*
X724114D01*
G01Y1107992D02*
X723209D01*
G01X724154Y1107953D02*
X723169D01*
G01X724113Y1107795D02*
X718228D01*
G01Y1107756D02*
X724152D01*
G01Y1106654D02*
X718228D01*
G01X724113Y1106614D02*
X718228D01*
G01X723169Y1106457D02*
X724154D01*
G01X723209Y1106417D02*
X724114D01*
G01Y1104843D02*
X723209D01*
G01X724154Y1104803D02*
X723169D01*
G01X724113Y1104646D02*
X718228D01*
G01Y1104606D02*
X724152D01*
G01X737008Y1103642D02*
X733071D01*
G01X724152Y1103504D02*
X718228D01*
G01X724113Y1103465D02*
X718228D01*
G01X723169Y1103307D02*
X724154D01*
G01X723209Y1103268D02*
X724114D01*
G01X738189Y1102461D02*
X734252D01*
G01X737579Y1102185D02*
X736594D01*
G01X736596Y1101693D02*
X741929D01*
G01Y1101654D02*
X737581D01*
G01X724606Y1101299D02*
X721260D01*
G01X741929Y1100315D02*
X736596D01*
G01X736594Y1099823D02*
X737579D01*
G01Y1097185D02*
X736594D01*
G01X736596Y1096693D02*
X741929D01*
G01Y1096654D02*
X737581D01*
G01X741929Y1095315D02*
X736596D01*
G01X736594Y1094823D02*
X737579D01*
G01Y1092185D02*
X736594D01*
G01X736596Y1091693D02*
X741929D01*
G01Y1091654D02*
X737581D01*
G01X741929Y1090315D02*
X736596D01*
G01X736594Y1089823D02*
X737579D01*
G01Y1087185D02*
X736594D01*
G01X736596Y1086693D02*
X741929D01*
G01Y1086654D02*
X737581D01*
G01X741929Y1085315D02*
X736596D01*
G01X736594Y1084823D02*
X737579D01*
G01Y1130119D02*
X736594Y1130118D01*
G01Y1126889D02*
X737550Y1126890D01*
G01X737579Y1125119D02*
X736594Y1125118D01*
G01Y1101889D02*
X737550Y1101890D01*
G01X737579Y1100119D02*
X736594Y1100118D01*
G01Y1096889D02*
X737550Y1096890D01*
G01X737579Y1095119D02*
X736594Y1095118D01*
G01Y1091889D02*
X737550Y1091890D01*
G01X737579Y1090119D02*
X736594Y1090118D01*
G01Y1086889D02*
X737550Y1086890D01*
G01X737579Y1085119D02*
X736594Y1085118D01*
G01X737008Y1103642D02*
X738189Y1102461D01*
G01X733071Y1103642D02*
X734252Y1102461D01*
G01X724113Y1119213D02*
X724116Y1119202D01*
G01X724153Y1104609D02*
X724154Y1104620D01*
G01X724153Y1107758D02*
X724154Y1107769D01*
G01X724153Y1110908D02*
X724154Y1110919D01*
G01X724153Y1114057D02*
X724154Y1114069D01*
G01X724153Y1117207D02*
X724154Y1117218D01*
G01X724153Y1120357D02*
X724154Y1120368D01*
G01X724153Y1123506D02*
X724154Y1123517D01*
G01X737579Y1086667D02*
Y1086676D01*
G01Y1091667D02*
Y1091676D01*
G01Y1096667D02*
Y1096676D01*
G01Y1101667D02*
Y1101676D01*
G01Y1126667D02*
Y1126676D01*
G01X741929Y1130315D02*
Y1131693D01*
G01Y1125315D02*
Y1126693D01*
G01Y1100315D02*
Y1101693D01*
G01Y1095315D02*
Y1096693D01*
G01Y1090315D02*
Y1091693D01*
G01Y1085315D02*
Y1086693D01*
G01X738760D02*
Y1085315D01*
G01Y1091693D02*
Y1090315D01*
G01Y1096693D02*
Y1095315D01*
G01Y1101693D02*
Y1100315D01*
G01Y1126693D02*
Y1125315D01*
G01Y1131693D02*
Y1130315D01*
G01X738189Y1124547D02*
Y1102461D01*
G01X737579Y1129823D02*
Y1132185D01*
G01Y1124823D02*
Y1127185D01*
G01Y1099823D02*
Y1102185D01*
G01Y1094823D02*
Y1097185D01*
G01Y1089823D02*
Y1092185D01*
G01Y1084823D02*
Y1087185D01*
G01Y1086667D02*
Y1086811D01*
G01Y1091667D02*
Y1091811D01*
G01Y1096667D02*
Y1096811D01*
G01Y1101667D02*
Y1101811D01*
G01Y1126667D02*
Y1126811D01*
G01X737008Y1123366D02*
Y1103642D01*
G01X736594Y1087185D02*
Y1084823D01*
G01Y1092185D02*
Y1089823D01*
G01Y1097185D02*
Y1094823D01*
G01Y1102185D02*
Y1099823D01*
G01Y1127185D02*
Y1124823D01*
G01Y1132185D02*
Y1129823D01*
G01X734252Y1201004D02*
Y1124547D01*
G01X733071Y1199823D02*
Y1123366D01*
G01X724606Y1204744D02*
Y1125709D01*
G01X724154Y1122205D02*
Y1123701D01*
G01Y1119055D02*
Y1120551D01*
G01Y1115906D02*
Y1117402D01*
G01Y1112756D02*
Y1114252D01*
G01Y1109606D02*
Y1111102D01*
G01Y1106457D02*
Y1107953D01*
G01Y1103307D02*
Y1104803D01*
G01X724114Y1106603D02*
Y1106456D01*
G01Y1103454D02*
Y1103307D01*
G01Y1104804D02*
Y1104657D01*
G01Y1109753D02*
Y1109606D01*
G01Y1111103D02*
Y1110956D01*
G01Y1107953D02*
Y1107807D01*
G01Y1116052D02*
Y1115905D01*
G01Y1112902D02*
Y1112756D01*
G01Y1114252D02*
Y1114106D01*
G01Y1119202D02*
Y1119055D01*
G01Y1120552D02*
Y1120405D01*
G01Y1117402D02*
Y1117256D01*
G01Y1122351D02*
Y1122204D01*
G01Y1123701D02*
Y1123555D01*
G01X723209Y1122204D02*
Y1122351D01*
G01Y1123555D02*
Y1123702D01*
G01Y1119054D02*
Y1119202D01*
G01Y1120405D02*
Y1120552D01*
G01Y1117256D02*
Y1117402D01*
G01Y1115905D02*
Y1116052D01*
G01Y1112755D02*
Y1112902D01*
G01Y1114106D02*
Y1114253D01*
G01Y1109606D02*
Y1109753D01*
G01Y1110956D02*
Y1111103D01*
G01Y1107807D02*
Y1107954D01*
G01Y1106456D02*
Y1106603D01*
G01Y1103306D02*
Y1103454D01*
G01Y1104657D02*
Y1104804D01*
G01X723169Y1104803D02*
Y1103307D01*
G01Y1111102D02*
Y1109606D01*
G01Y1107953D02*
Y1106457D01*
G01Y1114252D02*
Y1112756D01*
G01Y1120551D02*
Y1119055D01*
G01Y1117402D02*
Y1115906D01*
G01Y1123701D02*
Y1122205D01*
G01X721988Y1107795D02*
Y1106614D01*
G01Y1104646D02*
Y1103465D01*
G01Y1110945D02*
Y1109764D01*
G01Y1117244D02*
Y1116063D01*
G01Y1114094D02*
Y1112913D01*
G01Y1120394D02*
Y1119213D01*
G01Y1123543D02*
Y1122362D01*
G01X721654Y1125709D02*
Y1101299D01*
G01X721260D02*
Y1125709D01*
G01X718228Y1122362D02*
Y1123543D01*
G01Y1119213D02*
Y1120394D01*
G01Y1116063D02*
Y1117244D01*
G01Y1112913D02*
Y1114094D01*
G01Y1109764D02*
Y1110945D01*
G01Y1106614D02*
Y1107795D01*
G01Y1103465D02*
Y1104646D01*
G01X724154Y1122388D02*
X724153Y1122399D01*
G01X724154Y1119239D02*
X724153Y1119250D01*
G01X724154Y1116089D02*
X724153Y1116100D01*
G01X724154Y1112939D02*
X724153Y1112950D01*
G01X724154Y1109790D02*
X724153Y1109801D01*
G01X724154Y1106640D02*
X724153Y1106651D01*
G01X724154Y1103491D02*
X724153Y1103502D01*
G01X737008Y1123366D02*
X738189Y1124547D01*
G01X733071Y1123366D02*
X734252Y1124547D01*
G01X737579Y1175308D02*
Y1175299D01*
G01X737580Y1175313D02*
X737579Y1175308D01*
G01X737581Y1175315D02*
X737580Y1175313D01*
G01X737579Y1170308D02*
Y1170299D01*
G01X737580Y1170313D02*
X737579Y1170308D01*
G01X737581Y1170315D02*
X737580Y1170313D01*
G01X737579Y1165308D02*
Y1165299D01*
G01X737580Y1165313D02*
X737579Y1165308D01*
G01X737581Y1165315D02*
X737580Y1165313D01*
G01X737579Y1160308D02*
Y1160299D01*
G01X737580Y1160313D02*
X737579Y1160308D01*
G01X737581Y1160315D02*
X737580Y1160313D01*
G01X737579Y1155308D02*
Y1155299D01*
G01X737580Y1155313D02*
X737579Y1155308D01*
G01X737581Y1155315D02*
X737580Y1155313D01*
G01X737579Y1150308D02*
Y1150299D01*
G01X737580Y1150313D02*
X737579Y1150308D01*
G01X737581Y1150315D02*
X737580Y1150313D01*
G01X737579Y1145308D02*
Y1145299D01*
G01X737580Y1145313D02*
X737579Y1145308D01*
G01X737581Y1145315D02*
X737580Y1145313D01*
G01X737579Y1140308D02*
Y1140299D01*
G01X737580Y1140313D02*
X737579Y1140308D01*
G01X737581Y1140315D02*
X737580Y1140313D01*
G01X737579Y1135308D02*
Y1135299D01*
G01X737580Y1135313D02*
X737579Y1135308D01*
G01X737581Y1135315D02*
X737580Y1135313D01*
G01X737546Y1131791D02*
X737550Y1131890D01*
G01X737540Y1131719D02*
X737546Y1131791D01*
G01X737542Y1131693D02*
X737540Y1131719D01*
G01X737546Y1136791D02*
X737550Y1136890D01*
G01X737540Y1136719D02*
X737546Y1136791D01*
G01X737542Y1136693D02*
X737540Y1136719D01*
G01X737546Y1141791D02*
X737550Y1141890D01*
G01X737540Y1141719D02*
X737546Y1141791D01*
G01X737542Y1141693D02*
X737540Y1141719D01*
G01X737546Y1146791D02*
X737550Y1146890D01*
G01X737540Y1146719D02*
X737546Y1146791D01*
G01X737542Y1146693D02*
X737540Y1146719D01*
G01X737546Y1151791D02*
X737550Y1151890D01*
G01X737540Y1151719D02*
X737546Y1151791D01*
G01X737542Y1151693D02*
X737540Y1151719D01*
G01X737546Y1156791D02*
X737550Y1156890D01*
G01X737540Y1156719D02*
X737546Y1156791D01*
G01X737542Y1156693D02*
X737540Y1156719D01*
G01X737546Y1161791D02*
X737550Y1161890D01*
G01X737540Y1161719D02*
X737546Y1161791D01*
G01X737542Y1161693D02*
X737540Y1161719D01*
G01X737546Y1166791D02*
X737550Y1166890D01*
G01X737540Y1166719D02*
X737546Y1166791D01*
G01X737542Y1166693D02*
X737540Y1166719D01*
G01X737546Y1171791D02*
X737550Y1171890D01*
G01X737540Y1171719D02*
X737546Y1171791D01*
G01X737542Y1171693D02*
X737540Y1171719D01*
G01X737546Y1176791D02*
X737550Y1176890D01*
G01X737540Y1176719D02*
X737546Y1176791D01*
G01X737542Y1176693D02*
X737540Y1176719D01*
G01X736595Y1175313D02*
X736596Y1175315D01*
G01X736594Y1175308D02*
X736595Y1175313D01*
G01X736594Y1175299D02*
Y1175308D01*
G01X736595Y1170313D02*
X736596Y1170315D01*
G01X736594Y1170308D02*
X736595Y1170313D01*
G01X736594Y1170299D02*
Y1170308D01*
G01X736595Y1165313D02*
X736596Y1165315D01*
G01X736594Y1165308D02*
X736595Y1165313D01*
G01X736594Y1165299D02*
Y1165308D01*
G01X736595Y1160313D02*
X736596Y1160315D01*
G01X736594Y1160308D02*
X736595Y1160313D01*
G01X736594Y1160299D02*
Y1160308D01*
G01X736595Y1155313D02*
X736596Y1155315D01*
G01X736594Y1155308D02*
X736595Y1155313D01*
G01X736594Y1155299D02*
Y1155308D01*
G01X736595Y1150313D02*
X736596Y1150315D01*
G01X736594Y1150308D02*
X736595Y1150313D01*
G01X736594Y1150299D02*
Y1150308D01*
G01X736595Y1145313D02*
X736596Y1145315D01*
G01X736594Y1145308D02*
X736595Y1145313D01*
G01X736594Y1145299D02*
Y1145308D01*
G01X736595Y1140313D02*
X736596Y1140315D01*
G01X736594Y1140308D02*
X736595Y1140313D01*
G01X736594Y1140299D02*
Y1140308D01*
G01X736595Y1135313D02*
X736596Y1135315D01*
G01X736594Y1135308D02*
X736595Y1135313D01*
G01X736594Y1135299D02*
Y1135308D01*
G01X737561Y1131688D02*
X737542Y1131693D01*
G01X737576Y1131674D02*
X737561Y1131688D01*
G01X737581Y1131654D02*
X737576Y1131674D01*
G01X737561Y1136688D02*
X737542Y1136693D01*
G01X737576Y1136674D02*
X737561Y1136688D01*
G01X737581Y1136654D02*
X737576Y1136674D01*
G01X737561Y1141688D02*
X737542Y1141693D01*
G01X737576Y1141674D02*
X737561Y1141688D01*
G01X737581Y1141654D02*
X737576Y1141674D01*
G01X737561Y1146688D02*
X737542Y1146693D01*
G01X737576Y1146674D02*
X737561Y1146688D01*
G01X737581Y1146654D02*
X737576Y1146674D01*
G01X737561Y1151688D02*
X737542Y1151693D01*
G01X737576Y1151674D02*
X737561Y1151688D01*
G01X737581Y1151654D02*
X737576Y1151674D01*
G01X737561Y1156688D02*
X737542Y1156693D01*
G01X737576Y1156674D02*
X737561Y1156688D01*
G01X737581Y1156654D02*
X737576Y1156674D01*
G01X737561Y1161688D02*
X737542Y1161693D01*
G01X737576Y1161674D02*
X737561Y1161688D01*
G01X737581Y1161654D02*
X737576Y1161674D01*
G01X737561Y1166688D02*
X737542Y1166693D01*
G01X737576Y1166674D02*
X737561Y1166688D01*
G01X737581Y1166654D02*
X737576Y1166674D01*
G01X737561Y1171688D02*
X737542Y1171693D01*
G01X737576Y1171674D02*
X737561Y1171688D01*
G01X737581Y1171654D02*
X737576Y1171674D01*
G01X737561Y1176688D02*
X737542Y1176693D01*
G01X737576Y1176674D02*
X737561Y1176688D01*
G01X737581Y1176654D02*
X737576Y1176674D01*
G01X736594Y1131700D02*
Y1131709D01*
G01X736595Y1131695D02*
X736594Y1131700D01*
G01X736596Y1131693D02*
X736595Y1131695D01*
G01X736594Y1136700D02*
Y1136709D01*
G01X736595Y1136695D02*
X736594Y1136700D01*
G01X736596Y1136693D02*
X736595Y1136695D01*
G01X736594Y1141700D02*
Y1141709D01*
G01X736595Y1141695D02*
X736594Y1141700D01*
G01X736596Y1141693D02*
X736595Y1141695D01*
G01X736594Y1146700D02*
Y1146709D01*
G01X736595Y1146695D02*
X736594Y1146700D01*
G01X736596Y1146693D02*
X736595Y1146695D01*
G01X736594Y1151700D02*
Y1151709D01*
G01X736595Y1151695D02*
X736594Y1151700D01*
G01X736596Y1151693D02*
X736595Y1151695D01*
G01X736594Y1156700D02*
Y1156709D01*
G01X736595Y1156695D02*
X736594Y1156700D01*
G01X736596Y1156693D02*
X736595Y1156695D01*
G01X736594Y1161700D02*
Y1161709D01*
G01X736595Y1161695D02*
X736594Y1161700D01*
G01X736596Y1161693D02*
X736595Y1161695D01*
G01X736594Y1166700D02*
Y1166709D01*
G01X736595Y1166695D02*
X736594Y1166700D01*
G01X736596Y1166693D02*
X736595Y1166695D01*
G01X736594Y1171700D02*
Y1171709D01*
G01X736595Y1171695D02*
X736594Y1171700D01*
G01X736596Y1171693D02*
X736595Y1171695D01*
G01X736594Y1176700D02*
Y1176709D01*
G01X736595Y1176695D02*
X736594Y1176700D01*
G01X736596Y1176693D02*
X736595Y1176695D01*
G01X737571Y1131837D02*
X737579Y1131811D01*
G01X737561Y1131863D02*
X737571Y1131837D01*
G01X737550Y1131890D02*
X737561Y1131863D01*
G01X737571Y1136837D02*
X737579Y1136811D01*
G01X737561Y1136863D02*
X737571Y1136837D01*
G01X737550Y1136890D02*
X737561Y1136863D01*
G01X737571Y1141837D02*
X737579Y1141811D01*
G01X737561Y1141863D02*
X737571Y1141837D01*
G01X737550Y1141890D02*
X737561Y1141863D01*
G01X737571Y1146837D02*
X737579Y1146811D01*
G01X737561Y1146863D02*
X737571Y1146837D01*
G01X737550Y1146890D02*
X737561Y1146863D01*
G01X737571Y1151837D02*
X737579Y1151811D01*
G01X737561Y1151863D02*
X737571Y1151837D01*
G01X737550Y1151890D02*
X737561Y1151863D01*
G01X737571Y1156837D02*
X737579Y1156811D01*
G01X737561Y1156863D02*
X737571Y1156837D01*
G01X737550Y1156890D02*
X737561Y1156863D01*
G01X737571Y1161837D02*
X737579Y1161811D01*
G01X737561Y1161863D02*
X737571Y1161837D01*
G01X737550Y1161890D02*
X737561Y1161863D01*
G01X737571Y1166837D02*
X737579Y1166811D01*
G01X737561Y1166863D02*
X737571Y1166837D01*
G01X737550Y1166890D02*
X737561Y1166863D01*
G01X737571Y1171837D02*
X737579Y1171811D01*
G01X737561Y1171863D02*
X737571Y1171837D01*
G01X737550Y1171890D02*
X737561Y1171863D01*
G01X737571Y1176837D02*
X737579Y1176811D01*
G01X737561Y1176863D02*
X737571Y1176837D01*
G01X737550Y1176890D02*
X737561Y1176863D01*
G01X737579Y1131660D02*
Y1131667D01*
G01X737580Y1131656D02*
X737579Y1131660D01*
G01X737581Y1131654D02*
X737580Y1131656D01*
G01X737579Y1136660D02*
Y1136667D01*
G01X737580Y1136656D02*
X737579Y1136660D01*
G01X737581Y1136654D02*
X737580Y1136656D01*
G01X737579Y1141660D02*
Y1141667D01*
G01X737580Y1141656D02*
X737579Y1141660D01*
G01X737581Y1141654D02*
X737580Y1141656D01*
G01X737579Y1146660D02*
Y1146667D01*
G01X737580Y1146656D02*
X737579Y1146660D01*
G01X737581Y1146654D02*
X737580Y1146656D01*
G01X737579Y1151660D02*
Y1151667D01*
G01X737580Y1151656D02*
X737579Y1151660D01*
G01X737581Y1151654D02*
X737580Y1151656D01*
G01X737579Y1156660D02*
Y1156667D01*
G01X737580Y1156656D02*
X737579Y1156660D01*
G01X737581Y1156654D02*
X737580Y1156656D01*
G01X737579Y1161660D02*
Y1161667D01*
G01X737580Y1161656D02*
X737579Y1161660D01*
G01X737581Y1161654D02*
X737580Y1161656D01*
G01X737579Y1166660D02*
Y1166667D01*
G01X737580Y1166656D02*
X737579Y1166660D01*
G01X737581Y1166654D02*
X737580Y1166656D01*
G01X737579Y1171660D02*
Y1171667D01*
G01X737580Y1171656D02*
X737579Y1171660D01*
G01X737581Y1171654D02*
X737580Y1171656D01*
G01X737579Y1176660D02*
Y1176667D01*
G01X737580Y1176656D02*
X737579Y1176660D01*
G01X737581Y1176654D02*
X737580Y1176656D01*
G01X737566Y1131685D02*
X737577Y1131669D01*
G01X737542Y1131693D02*
X737566Y1131685D01*
G01Y1136685D02*
X737577Y1136669D01*
G01X737542Y1136693D02*
X737566Y1136685D01*
G01Y1141685D02*
X737577Y1141669D01*
G01X737542Y1141693D02*
X737566Y1141685D01*
G01Y1146685D02*
X737577Y1146669D01*
G01X737542Y1146693D02*
X737566Y1146685D01*
G01Y1151685D02*
X737577Y1151669D01*
G01X737542Y1151693D02*
X737566Y1151685D01*
G01Y1156685D02*
X737577Y1156669D01*
G01X737542Y1156693D02*
X737566Y1156685D01*
G01Y1161685D02*
X737577Y1161669D01*
G01X737542Y1161693D02*
X737566Y1161685D01*
G01Y1166685D02*
X737577Y1166669D01*
G01X737542Y1166693D02*
X737566Y1166685D01*
G01Y1171685D02*
X737577Y1171669D01*
G01X737542Y1171693D02*
X737566Y1171685D01*
G01Y1176685D02*
X737577Y1176669D01*
G01X737542Y1176693D02*
X737566Y1176685D01*
G01X737579Y1177185D02*
X736594D01*
G01X736596Y1176693D02*
X741929D01*
G01Y1176654D02*
X737581D01*
G01X741929Y1175315D02*
X736596D01*
G01X736594Y1174823D02*
X737579D01*
G01Y1172185D02*
X736594D01*
G01X736596Y1171693D02*
X741929D01*
G01Y1171654D02*
X737581D01*
G01X741929Y1170315D02*
X736596D01*
G01X736594Y1169823D02*
X737579D01*
G01Y1167185D02*
X736594D01*
G01X736596Y1166693D02*
X741929D01*
G01Y1166654D02*
X737581D01*
G01X741929Y1165315D02*
X736596D01*
G01X736594Y1164823D02*
X737579D01*
G01Y1162185D02*
X736594D01*
G01X736596Y1161693D02*
X741929D01*
G01Y1161654D02*
X737581D01*
G01X741929Y1160315D02*
X736596D01*
G01X736594Y1159823D02*
X737579D01*
G01Y1157185D02*
X736594D01*
G01X736596Y1156693D02*
X741929D01*
G01Y1156654D02*
X737581D01*
G01X741929Y1155315D02*
X736596D01*
G01X736594Y1154823D02*
X737579D01*
G01X736594Y1176889D02*
X737550Y1176890D01*
G01X737579Y1175119D02*
X736594Y1175118D01*
G01Y1171889D02*
X737550Y1171890D01*
G01X737579Y1170119D02*
X736594Y1170118D01*
G01Y1166889D02*
X737550Y1166890D01*
G01X737579Y1165119D02*
X736594Y1165118D01*
G01Y1161889D02*
X737550Y1161890D01*
G01X737579Y1160119D02*
X736594Y1160118D01*
G01Y1156889D02*
X737550Y1156890D01*
G01X737579Y1155119D02*
X736594Y1155118D01*
G01X737579Y1152185D02*
X736594D01*
G01X736596Y1151693D02*
X741929D01*
G01Y1151654D02*
X737581D01*
G01X741929Y1150315D02*
X736596D01*
G01X736594Y1149823D02*
X737579D01*
G01Y1147185D02*
X736594D01*
G01X736596Y1146693D02*
X741929D01*
G01Y1146654D02*
X737581D01*
G01X741929Y1145315D02*
X736596D01*
G01X736594Y1144823D02*
X737579D01*
G01Y1142185D02*
X736594D01*
G01X736596Y1141693D02*
X741929D01*
G01Y1141654D02*
X737581D01*
G01X741929Y1140315D02*
X736596D01*
G01X736594Y1139823D02*
X737579D01*
G01Y1137185D02*
X736594D01*
G01X736596Y1136693D02*
X741929D01*
G01Y1136654D02*
X737581D01*
G01X741929Y1135315D02*
X736596D01*
G01X736594Y1134823D02*
X737579D01*
G01Y1132185D02*
X736594D01*
G01X736596Y1131693D02*
X741929D01*
G01Y1131654D02*
X737581D01*
G01X736594Y1151889D02*
X737550Y1151890D01*
G01X737579Y1150119D02*
X736594Y1150118D01*
G01Y1146889D02*
X737550Y1146890D01*
G01X737579Y1145119D02*
X736594Y1145118D01*
G01Y1141889D02*
X737550Y1141890D01*
G01X737579Y1140119D02*
X736594Y1140118D01*
G01Y1136889D02*
X737550Y1136890D01*
G01X737579Y1135119D02*
X736594Y1135118D01*
G01Y1131889D02*
X737550Y1131890D01*
G01X737579Y1131667D02*
Y1131676D01*
G01Y1136667D02*
Y1136676D01*
G01Y1141667D02*
Y1141676D01*
G01Y1146667D02*
Y1146676D01*
G01Y1151667D02*
Y1151676D01*
G01Y1156667D02*
Y1156676D01*
G01Y1161667D02*
Y1161676D01*
G01Y1166667D02*
Y1166676D01*
G01Y1171667D02*
Y1171676D01*
G01Y1176667D02*
Y1176676D01*
G01X741929Y1175315D02*
Y1176693D01*
G01Y1170315D02*
Y1171693D01*
G01Y1165315D02*
Y1166693D01*
G01Y1160315D02*
Y1161693D01*
G01Y1155315D02*
Y1156693D01*
G01Y1150315D02*
Y1151693D01*
G01Y1145315D02*
Y1146693D01*
G01Y1140315D02*
Y1141693D01*
G01Y1135315D02*
Y1136693D01*
G01X738760D02*
Y1135315D01*
G01Y1141693D02*
Y1140315D01*
G01Y1146693D02*
Y1145315D01*
G01Y1151693D02*
Y1150315D01*
G01Y1156693D02*
Y1155315D01*
G01Y1161693D02*
Y1160315D01*
G01Y1166693D02*
Y1165315D01*
G01Y1171693D02*
Y1170315D01*
G01Y1176693D02*
Y1175315D01*
G01X737579Y1174823D02*
Y1177185D01*
G01Y1169823D02*
Y1172185D01*
G01Y1164823D02*
Y1167185D01*
G01Y1159823D02*
Y1162185D01*
G01Y1154823D02*
Y1157185D01*
G01Y1149823D02*
Y1152185D01*
G01Y1144823D02*
Y1147185D01*
G01Y1139823D02*
Y1142185D01*
G01Y1134823D02*
Y1137185D01*
G01Y1131667D02*
Y1131811D01*
G01Y1136667D02*
Y1136811D01*
G01Y1141667D02*
Y1141811D01*
G01Y1146667D02*
Y1146811D01*
G01Y1151667D02*
Y1151811D01*
G01Y1156667D02*
Y1156811D01*
G01Y1161667D02*
Y1161811D01*
G01Y1166667D02*
Y1166811D01*
G01Y1171667D02*
Y1171811D01*
G01Y1176667D02*
Y1176811D01*
G01X736594Y1137185D02*
Y1134823D01*
G01Y1142185D02*
Y1139823D01*
G01Y1147185D02*
Y1144823D01*
G01Y1152185D02*
Y1149823D01*
G01Y1157185D02*
Y1154823D01*
G01Y1162185D02*
Y1159823D01*
G01Y1167185D02*
Y1164823D01*
G01Y1172185D02*
Y1169823D01*
G01Y1177185D02*
Y1174823D01*
G01X737579Y1195308D02*
Y1195299D01*
G01X737580Y1195313D02*
X737579Y1195308D01*
G01X737581Y1195315D02*
X737580Y1195313D01*
G01X737579Y1190308D02*
Y1190299D01*
G01X737580Y1190313D02*
X737579Y1190308D01*
G01X737581Y1190315D02*
X737580Y1190313D01*
G01X737579Y1185308D02*
Y1185299D01*
G01X737580Y1185313D02*
X737579Y1185308D01*
G01X737581Y1185315D02*
X737580Y1185313D01*
G01X737579Y1180308D02*
Y1180299D01*
G01X737580Y1180313D02*
X737579Y1180308D01*
G01X737581Y1180315D02*
X737580Y1180313D01*
G01X737546Y1181791D02*
X737550Y1181890D01*
G01X737540Y1181719D02*
X737546Y1181791D01*
G01X737542Y1181693D02*
X737540Y1181719D01*
G01X737546Y1186791D02*
X737550Y1186890D01*
G01X737540Y1186719D02*
X737546Y1186791D01*
G01X737542Y1186693D02*
X737540Y1186719D01*
G01X737546Y1191791D02*
X737550Y1191890D01*
G01X737540Y1191719D02*
X737546Y1191791D01*
G01X737542Y1191693D02*
X737540Y1191719D01*
G01X737546Y1196791D02*
X737550Y1196890D01*
G01X737540Y1196719D02*
X737546Y1196791D01*
G01X737542Y1196693D02*
X737540Y1196719D01*
G01X736595Y1195313D02*
X736596Y1195315D01*
G01X736594Y1195308D02*
X736595Y1195313D01*
G01X736594Y1195299D02*
Y1195308D01*
G01X736595Y1190313D02*
X736596Y1190315D01*
G01X736594Y1190308D02*
X736595Y1190313D01*
G01X736594Y1190299D02*
Y1190308D01*
G01X736595Y1185313D02*
X736596Y1185315D01*
G01X736594Y1185308D02*
X736595Y1185313D01*
G01X736594Y1185299D02*
Y1185308D01*
G01X736595Y1180313D02*
X736596Y1180315D01*
G01X736594Y1180308D02*
X736595Y1180313D01*
G01X736594Y1180299D02*
Y1180308D01*
G01X737561Y1181688D02*
X737542Y1181693D01*
G01X737576Y1181674D02*
X737561Y1181688D01*
G01X737581Y1181654D02*
X737576Y1181674D01*
G01X737561Y1186688D02*
X737542Y1186693D01*
G01X737576Y1186674D02*
X737561Y1186688D01*
G01X737581Y1186654D02*
X737576Y1186674D01*
G01X737561Y1191688D02*
X737542Y1191693D01*
G01X737576Y1191674D02*
X737561Y1191688D01*
G01X737581Y1191654D02*
X737576Y1191674D01*
G01X737561Y1196688D02*
X737542Y1196693D01*
G01X737576Y1196674D02*
X737561Y1196688D01*
G01X737581Y1196654D02*
X737576Y1196674D01*
G01X736594Y1181700D02*
Y1181709D01*
G01X736595Y1181695D02*
X736594Y1181700D01*
G01X736596Y1181693D02*
X736595Y1181695D01*
G01X736594Y1186700D02*
Y1186709D01*
G01X736595Y1186695D02*
X736594Y1186700D01*
G01X736596Y1186693D02*
X736595Y1186695D01*
G01X736594Y1191700D02*
Y1191709D01*
G01X736595Y1191695D02*
X736594Y1191700D01*
G01X736596Y1191693D02*
X736595Y1191695D01*
G01X736594Y1196700D02*
Y1196709D01*
G01X736595Y1196695D02*
X736594Y1196700D01*
G01X736596Y1196693D02*
X736595Y1196695D01*
G01X737571Y1181837D02*
X737579Y1181811D01*
G01X737561Y1181863D02*
X737571Y1181837D01*
G01X737550Y1181890D02*
X737561Y1181863D01*
G01X737571Y1186837D02*
X737579Y1186811D01*
G01X737561Y1186863D02*
X737571Y1186837D01*
G01X737550Y1186890D02*
X737561Y1186863D01*
G01X737571Y1191837D02*
X737579Y1191811D01*
G01X737561Y1191863D02*
X737571Y1191837D01*
G01X737550Y1191890D02*
X737561Y1191863D01*
G01X737571Y1196837D02*
X737579Y1196811D01*
G01X737561Y1196863D02*
X737571Y1196837D01*
G01X737550Y1196890D02*
X737561Y1196863D01*
G01X737579Y1181660D02*
Y1181667D01*
G01X737580Y1181656D02*
X737579Y1181660D01*
G01X737581Y1181654D02*
X737580Y1181656D01*
G01X737579Y1186660D02*
Y1186667D01*
G01X737580Y1186656D02*
X737579Y1186660D01*
G01X737581Y1186654D02*
X737580Y1186656D01*
G01X737579Y1191660D02*
Y1191667D01*
G01X737580Y1191656D02*
X737579Y1191660D01*
G01X737581Y1191654D02*
X737580Y1191656D01*
G01X737579Y1196660D02*
Y1196667D01*
G01X737580Y1196656D02*
X737579Y1196660D01*
G01X737581Y1196654D02*
X737580Y1196656D01*
G01X737566Y1181685D02*
X737577Y1181669D01*
G01X737542Y1181693D02*
X737566Y1181685D01*
G01Y1186685D02*
X737577Y1186669D01*
G01X737542Y1186693D02*
X737566Y1186685D01*
G01Y1191685D02*
X737577Y1191669D01*
G01X737542Y1191693D02*
X737566Y1191685D01*
G01Y1196685D02*
X737577Y1196669D01*
G01X737542Y1196693D02*
X737566Y1196685D01*
G01X736024Y1222185D02*
G03X735433Y1222776I-591J0D01*
G01X728740D02*
G03X728150Y1222185I1J-591D01*
G01X730906Y1221004D02*
G03Y1219035I0J-985D01*
G01X733268D02*
G03Y1221004I0J985D01*
G01X742913Y1221594D02*
G03X740945Y1223563I-1968J1D01*
G01X723228D02*
G03X721260Y1221594I0J-1968D01*
G01X729528Y1213091D02*
G03X728346Y1211909I-1J-1181D01*
G01X735827D02*
G03X734646Y1213091I-1181J1D01*
G01X733976Y1207815D02*
G03I-1889J0D01*
G01X734449D02*
G03I-2362J0D01*
G01X740945Y1223563D02*
X723228D01*
G01X735433Y1222776D02*
X728740D01*
G01X733268Y1221004D02*
X730906D01*
G01Y1219035D02*
X733268D01*
G01X736024Y1217657D02*
X728150D01*
G01Y1216083D02*
X736024D01*
G01X742913Y1213130D02*
X721260D01*
G01X729528Y1213091D02*
X734646D01*
G01X730906Y1208406D02*
X733268D01*
G01X730906Y1206713D02*
X733268D01*
G01X724606Y1204744D02*
X738976D01*
G01X724606Y1203366D02*
X728346D01*
G01X738976D02*
X735827D01*
G01X724606Y1202500D02*
X739567D01*
G01X726378Y1201004D02*
X734252D01*
G01X727559Y1199823D02*
X733071D01*
G01X737579Y1197185D02*
X736594D01*
G01X736596Y1196693D02*
X741929D01*
G01Y1196654D02*
X737581D01*
G01X741929Y1195315D02*
X736596D01*
G01X736594Y1194823D02*
X737579D01*
G01Y1192185D02*
X736594D01*
G01X736596Y1191693D02*
X741929D01*
G01Y1191654D02*
X737581D01*
G01X741929Y1190315D02*
X736596D01*
G01X736594Y1189823D02*
X737579D01*
G01Y1187185D02*
X736594D01*
G01X736596Y1186693D02*
X741929D01*
G01Y1186654D02*
X737581D01*
G01X741929Y1185315D02*
X736596D01*
G01X736594Y1184823D02*
X737579D01*
G01Y1182185D02*
X736594D01*
G01X736596Y1181693D02*
X741929D01*
G01Y1181654D02*
X737581D01*
G01X741929Y1180315D02*
X736596D01*
G01X736594Y1179823D02*
X737579D01*
G01X736594Y1196889D02*
X737550Y1196890D01*
G01X737579Y1195119D02*
X736594Y1195118D01*
G01Y1191889D02*
X737550Y1191890D01*
G01X737579Y1190119D02*
X736594Y1190118D01*
G01Y1186889D02*
X737550Y1186890D01*
G01X737579Y1185119D02*
X736594Y1185118D01*
G01Y1181889D02*
X737550Y1181890D01*
G01X737579Y1180119D02*
X736594Y1180118D01*
G01X726378Y1201004D02*
X727559Y1199823D01*
G01X721260Y1205846D02*
X724606Y1202500D01*
G01X733268Y1206713D02*
X734571Y1204744D01*
G01X730906Y1208406D02*
X728595Y1212635D01*
G01X737579Y1181667D02*
Y1181676D01*
G01Y1186667D02*
Y1186676D01*
G01Y1191667D02*
Y1191676D01*
G01Y1196667D02*
Y1196676D01*
G01X742913Y1205846D02*
Y1221594D01*
G01X741929Y1195315D02*
Y1196693D01*
G01Y1190315D02*
Y1191693D01*
G01Y1185315D02*
Y1186693D01*
G01Y1180315D02*
Y1181693D01*
G01X738760D02*
Y1180315D01*
G01Y1186693D02*
Y1185315D01*
G01Y1191693D02*
Y1190315D01*
G01Y1196693D02*
Y1195315D01*
G01X737579Y1194823D02*
Y1197185D01*
G01Y1189823D02*
Y1192185D01*
G01Y1184823D02*
Y1187185D01*
G01Y1179823D02*
Y1182185D01*
G01Y1181667D02*
Y1181811D01*
G01Y1186667D02*
Y1186811D01*
G01Y1191667D02*
Y1191811D01*
G01Y1196667D02*
Y1196811D01*
G01X736594Y1182185D02*
Y1179823D01*
G01Y1187185D02*
Y1184823D01*
G01Y1192185D02*
Y1189823D01*
G01Y1197185D02*
Y1194823D01*
G01X736024Y1216083D02*
Y1222185D01*
G01X735827Y1211909D02*
Y1203366D01*
G01X733268Y1208406D02*
Y1206713D01*
G01X730906D02*
Y1208406D01*
G01X728346Y1203366D02*
Y1211909D01*
G01X728150Y1216083D02*
Y1222185D01*
G01X721260Y1221594D02*
Y1205846D01*
G01X729602Y1204744D02*
X730906Y1206713D01*
G01X735578Y1212635D02*
X733268Y1208406D01*
G01X742913Y1205846D02*
X739567Y1202500D01*
G01X733071Y1199823D02*
X734252Y1201004D01*
G01X723228Y1382677D02*
G03Y1374803I0J-3937D01*
G01Y1382677D02*
X742913D01*
G01Y1464567D02*
Y1382677D01*
G01X746850Y1374803D02*
G03X750787Y1378740I0J3937D01*
G01X723228Y1382677D02*
X742913D01*
G01X723228D02*
G03Y1374803I0J-3937D01*
G01X742913Y1464567D02*
Y1382677D01*
G01X746850Y1374803D02*
G03X750787Y1378740I0J3937D01*
G01X754724Y1476378D02*
G03X742913Y1464567I0J-11811D01*
G01X754724Y1476378D02*
G03X742913Y1464567I0J-11811D01*
G01X759905Y-335933D02*
Y-354870D01*
G01X780203Y-7874D02*
G03X791339Y-15748I11136J3937D01*
G01X858268D02*
X791339D01*
G01Y-7874D02*
X862205D01*
G01X787402Y-3937D02*
G03X791339Y-7874I3937J0D01*
G01X787402Y-3937D02*
G03X783465Y0I-3937J0D01*
G01X858268Y-15748D02*
X791339D01*
G01X780203Y-7874D02*
G03X791339Y-15748I11136J3937D01*
G01X793556Y13773D02*
G03X792769Y12986I0J-787D01*
G01Y12789D02*
G03X793556Y12002I787J0D01*
G01X793950Y10427D02*
G03Y12002I0J787D01*
G01X793556Y10427D02*
G03X792769Y9639I0J-787D01*
G01Y9443D02*
G03X793556Y8655I787J-1D01*
G01X787402Y-3937D02*
G03X783465Y0I-3937J0D01*
G01X787402Y-3937D02*
G03X791339Y-7874I3937J0D01*
G01X798031Y9055D02*
X797638Y8661D01*
G01X797099Y8970D02*
X796981Y8852D01*
G01X796260Y9055D02*
X795866Y8661D01*
G01X796241Y10237D02*
X795846Y8661D01*
G01X797099Y13780D02*
Y8655D01*
G01X797067Y10236D02*
Y15709D01*
G01X796312D02*
Y8655D01*
G01X796260Y20472D02*
Y9055D01*
G01X796240Y15709D02*
Y10236D01*
G01X795276Y26772D02*
Y8661D01*
G01X793504Y15669D02*
Y13751D01*
G01X792769Y9639D02*
Y9443D01*
G01Y12986D02*
Y12789D01*
G01X797461Y8661D02*
X797067Y10236D01*
G01X793504Y13751D02*
X795276Y11220D01*
G01X796430Y8852D02*
X796312Y8970D01*
G01X797067Y15709D02*
X796240D01*
G01X795276Y15669D02*
X793504D01*
G01X796312Y14610D02*
X797067D01*
G01Y14567D02*
X796240D01*
G01X797067Y14488D02*
X796240D01*
G01X797067Y14094D02*
X796240D01*
G01X797067Y13780D02*
X798504D01*
G01X796240D02*
X795276D01*
G01Y13778D02*
X796240D01*
G01X797067Y13773D02*
X793556D01*
G01X793950Y12002D02*
X793556D01*
G01X797067Y11313D02*
X796312D01*
G01X797067Y11181D02*
X796240D01*
G01X793950Y10427D02*
X793556D01*
G01X797067Y10354D02*
X796240D01*
G01X796312Y10338D02*
X797067D01*
G01X796240Y10237D02*
X797067D01*
G01X796260Y9055D02*
X801969D01*
G01X796312Y9049D02*
X797099D01*
G01Y8891D02*
X796312D01*
G01X796981Y8852D02*
X796430D01*
G01X795276Y8661D02*
X884252D01*
G01X793556Y8655D02*
X797099D01*
G01X862205Y-7874D02*
X791339D01*
G01X796063Y26772D02*
Y26575D01*
G01X880315Y26772D02*
X795276D01*
G01X800394Y26575D02*
X796063D01*
G01X800394Y25197D02*
X795276D01*
G01X883268Y20472D02*
X796260D01*
G01X779551Y264712D02*
G03X813362I16905J-13531D01*
G01X779551D02*
G03X813362I16905J-13531D01*
G01X806437Y277843D02*
G03X786476I-9981J-3040D01*
G01X779551Y264712D02*
G03X786476Y277843I-30737J24602D01*
G01X806437D02*
G03X786476I-9981J-3040D01*
G01X779551Y264712D02*
G03X786476Y277843I-30737J24601D01*
G01X779551Y737153D02*
G03X813362I16905J-13531D01*
G01X779551Y737154D02*
G03X786476Y750284I-30736J24602D01*
G01X779551Y737153D02*
G03X813362I16905J-13531D01*
G01X779551D02*
G03X786476Y750284I-30737J24601D01*
G01X806437D02*
G03X786476I-9981J-3040D01*
G01X806437D02*
G03X786476I-9981J-3040D01*
G01X750787Y1464567D02*
Y1378740D01*
G01Y1464567D02*
Y1378740D01*
G01X754724Y1468504D02*
G03X750787Y1464567I0J-3937D01*
G01X783465Y1468504D02*
X754724D01*
G01X783465D02*
G03X787402Y1472441I0J3937D01*
G01X783465Y1468504D02*
G03X787402Y1472441I0J3937D01*
G01X754724Y1468504D02*
G03X750787Y1464567I0J-3937D01*
G01X783465Y1468504D02*
X754724D01*
G01X779528Y1476378D02*
X754724D01*
G01X779528Y1596063D02*
Y1476378D01*
G01X787402Y1654331D02*
Y1472441D01*
G01X779528Y1596063D02*
Y1476378D01*
G01D02*
X754724D01*
G01X787402Y1654331D02*
Y1472441D01*
G01Y1596063D02*
G03X779528I-3937J0D01*
G01X787402D02*
G03X779528I-3937J0D01*
G01Y1654331D02*
G03X775591Y1658268I-3937J0D01*
G01X779528Y1626772D02*
G03X787402I3937J0D01*
G01X779528Y1654331D02*
Y1626772D01*
G01X791339Y1658268D02*
G03X787402Y1654331I0J-3937D01*
G01X1216535Y1658268D02*
X791339D01*
G01X779528Y1654331D02*
G03X775591Y1658268I-3937J0D01*
G01X779528Y1626772D02*
G03X787402I3937J0D01*
G01X779528Y1654331D02*
Y1626772D01*
G01X791339Y1658268D02*
G03X787402Y1654331I0J-3937D01*
G01X1216535Y1658268D02*
X791339D01*
G01X759905Y1841823D02*
Y1822886D01*
G01X844665Y8661D02*
X845256Y9252D01*
G01X840728Y8661D02*
X841319Y9252D01*
G01X836791Y8661D02*
X837382Y9252D01*
G01X832854Y8661D02*
X833445Y9252D01*
G01X828917Y8661D02*
X829508Y9252D01*
G01X824980Y8661D02*
X825571Y9252D01*
G01X821043Y8661D02*
X821634Y9252D01*
G01X817106Y8661D02*
X817697Y9252D01*
G01X813169Y8661D02*
X813760Y9252D01*
G01X809232Y8661D02*
X809823Y9252D01*
G01X805295Y8661D02*
X805886Y9252D01*
G01X801358Y8661D02*
X801949Y9252D01*
G01X845957Y12198D02*
X846115Y12986D01*
G01X842020Y12198D02*
X842178Y12986D01*
G01X838083Y12198D02*
X838241Y12986D01*
G01X834146Y12198D02*
X834304Y12986D01*
G01X830209Y12198D02*
X830367Y12986D01*
G01X826272Y12198D02*
X826430Y12986D01*
G01X845957Y12041D02*
X846115Y12848D01*
G01X842020Y12041D02*
X842178Y12848D01*
G01X838083Y12041D02*
X838241Y12848D01*
G01X834146Y12041D02*
X834304Y12848D01*
G01X830209Y12041D02*
X830367Y12848D01*
G01X822335Y12198D02*
X822493Y12986D01*
G01X818398Y12198D02*
X818556Y12986D01*
G01X814461Y12198D02*
X814619Y12986D01*
G01X810524Y12198D02*
X810682Y12986D01*
G01X806587Y12198D02*
X806745Y12986D01*
G01X802650Y12198D02*
X802808Y12986D01*
G01X826272Y12041D02*
X826430Y12848D01*
G01X822335Y12041D02*
X822493Y12848D01*
G01X818398Y12041D02*
X818556Y12848D01*
G01X814461Y12041D02*
X814619Y12848D01*
G01X810524Y12041D02*
X810682Y12848D01*
G01X806587Y12041D02*
X806745Y12848D01*
G01X802650Y12041D02*
X802808Y12848D01*
G01X846115Y10999D02*
Y20472D01*
G01Y4915D02*
Y9220D01*
G01X846083Y22047D02*
Y9252D01*
G01X845328Y22047D02*
Y4915D01*
G01X845256Y22047D02*
Y9252D01*
G01X842178Y10999D02*
Y20472D01*
G01Y4915D02*
Y9220D01*
G01X842146Y22047D02*
Y9252D01*
G01X842126Y8660D02*
Y20472D01*
G01X841391Y22047D02*
Y4915D01*
G01X841319Y22047D02*
Y9252D01*
G01X838241Y10999D02*
Y20472D01*
G01Y4915D02*
Y9220D01*
G01X838209Y22047D02*
Y9252D01*
G01X837454Y22047D02*
Y4915D01*
G01X837402Y20472D02*
Y8660D01*
G01X837382Y22047D02*
Y9252D01*
G01X834304Y10999D02*
Y20472D01*
G01Y4915D02*
Y9220D01*
G01X834272Y22047D02*
Y9252D01*
G01X833517Y22047D02*
Y4915D01*
G01X833445Y22047D02*
Y9252D01*
G01X830367Y10999D02*
Y20472D01*
G01Y4915D02*
Y9220D01*
G01X830335Y22047D02*
Y9252D01*
G01X829580Y22047D02*
Y4915D01*
G01X829508Y22047D02*
Y9252D01*
G01X826430Y10999D02*
Y20472D01*
G01Y4915D02*
Y9220D01*
G01X826398Y22047D02*
Y9252D01*
G01X825643Y22047D02*
Y4915D01*
G01X825571Y22047D02*
Y9252D01*
G01X822493Y10999D02*
Y20472D01*
G01Y4915D02*
Y9220D01*
G01X822461Y22047D02*
Y9252D01*
G01X821706Y22047D02*
Y4915D01*
G01X821634Y22047D02*
Y9252D01*
G01X818556Y10999D02*
Y20472D01*
G01Y4915D02*
Y9220D01*
G01X818524Y22047D02*
Y9252D01*
G01X817769Y22047D02*
Y4915D01*
G01X817697Y22047D02*
Y9252D01*
G01X814619Y10999D02*
Y20472D01*
G01Y4915D02*
Y9220D01*
G01X814587Y22047D02*
Y9252D01*
G01X813831Y22047D02*
Y4915D01*
G01X813760Y22047D02*
Y9252D01*
G01X810682Y10999D02*
Y20472D01*
G01Y4915D02*
Y9220D01*
G01X810650Y22047D02*
Y9252D01*
G01X809894Y22047D02*
Y4915D01*
G01X809823Y22047D02*
Y9252D01*
G01X806745Y10999D02*
Y20472D01*
G01Y4915D02*
Y9220D01*
G01X806713Y22047D02*
Y9252D01*
G01X806693Y8660D02*
Y20472D01*
G01X805957Y22047D02*
Y4915D01*
G01X805886Y22047D02*
Y9252D01*
G01X802808Y10999D02*
Y20472D01*
G01Y4915D02*
Y9220D01*
G01X802776Y22047D02*
Y9252D01*
G01X802020Y22047D02*
Y4915D01*
G01X801969Y20472D02*
Y8660D01*
G01X801949Y22047D02*
Y9252D01*
G01X800394Y25197D02*
Y8661D01*
G01X800000Y20472D02*
Y8661D01*
G01X798504Y13780D02*
Y8661D01*
G01X798031Y20472D02*
Y9055D01*
G01X845485Y12041D02*
X845328Y12848D01*
G01X841391D02*
X841548Y12041D01*
G01X837454Y12848D02*
X837611Y12041D01*
G01X833517Y12848D02*
X833674Y12041D01*
G01X829580Y12848D02*
X829737Y12041D01*
G01X825643Y12848D02*
X825800Y12041D01*
G01X821706Y12848D02*
X821863Y12041D01*
G01X817769Y12848D02*
X817926Y12041D01*
G01X813831Y12848D02*
X813989Y12041D01*
G01X809894Y12848D02*
X810052Y12041D01*
G01X805957Y12848D02*
X806115Y12041D01*
G01X802020Y12848D02*
X802178Y12041D01*
G01X845328Y12986D02*
X845485Y12198D01*
G01X841391Y12986D02*
X841548Y12198D01*
G01X837454Y12986D02*
X837611Y12198D01*
G01X833517Y12986D02*
X833674Y12198D01*
G01X829580Y12986D02*
X829737Y12198D01*
G01X825643Y12986D02*
X825800Y12198D01*
G01X821706Y12986D02*
X821863Y12198D01*
G01X817769Y12986D02*
X817926Y12198D01*
G01X813831Y12986D02*
X813989Y12198D01*
G01X809894Y12986D02*
X810052Y12198D01*
G01X805957Y12986D02*
X806115Y12198D01*
G01X802020Y12986D02*
X802178Y12198D01*
G01X846083Y9252D02*
X846673Y8661D01*
G01X842146Y9252D02*
X842736Y8661D01*
G01X838209Y9252D02*
X838799Y8661D01*
G01X834272Y9252D02*
X834862Y8661D01*
G01X830335Y9252D02*
X830925Y8661D01*
G01X826398Y9252D02*
X826988Y8661D01*
G01X822461Y9252D02*
X823051Y8661D01*
G01X818524Y9252D02*
X819114Y8661D01*
G01X814587Y9252D02*
X815177Y8661D01*
G01X810650Y9252D02*
X811240Y8661D01*
G01X806713Y9252D02*
X807303Y8661D01*
G01X802776Y9252D02*
X803366Y8661D01*
G01X845256Y16520D02*
X846083D01*
G01X841319D02*
X842146D01*
G01X837382D02*
X838209D01*
G01X833445D02*
X834272D01*
G01X829508D02*
X830335D01*
G01X821634D02*
X822461D01*
G01X825571D02*
X826398D01*
G01X817697D02*
X818524D01*
G01X813760D02*
X814587D01*
G01X809823D02*
X810650D01*
G01X805886D02*
X806713D01*
G01X801949D02*
X802776D01*
G01X802808Y16093D02*
X802020D01*
G01X806745D02*
X805957D01*
G01X810682D02*
X809894D01*
G01X814619D02*
X813831D01*
G01X818556D02*
X817769D01*
G01X826430D02*
X825643D01*
G01X822493D02*
X821706D01*
G01X830367D02*
X829580D01*
G01X834304D02*
X833517D01*
G01X838241D02*
X837454D01*
G01X842178D02*
X841391D01*
G01X846115D02*
X845328D01*
G01X806745Y16065D02*
X806713D01*
G01X802808D02*
X802776D01*
G01X810682D02*
X810650D01*
G01X814619D02*
X814587D01*
G01X818556D02*
X818524D01*
G01X822493D02*
X822461D01*
G01X830367D02*
X830335D01*
G01X826430D02*
X826398D01*
G01X834304D02*
X834272D01*
G01X838241D02*
X838209D01*
G01X842178D02*
X842146D01*
G01X846115D02*
X846083D01*
G01X802776Y16056D02*
X802020D01*
G01X806713D02*
X805957D01*
G01X810650D02*
X809894D01*
G01X814587D02*
X813831D01*
G01X818524D02*
X817769D01*
G01X826398D02*
X825643D01*
G01X822461D02*
X821706D01*
G01X830335D02*
X829580D01*
G01X834272D02*
X833517D01*
G01X838209D02*
X837454D01*
G01X842146D02*
X841391D01*
G01X846083D02*
X845328D01*
G01Y15896D02*
X846115D01*
G01X841391D02*
X842178D01*
G01X837454D02*
X838241D01*
G01X833517D02*
X834304D01*
G01X829580D02*
X830367D01*
G01X825643D02*
X826430D01*
G01X821706D02*
X822493D01*
G01X817769D02*
X818556D01*
G01X813831D02*
X814619D01*
G01X809894D02*
X810682D01*
G01X805957D02*
X806745D01*
G01X802020D02*
X802808D01*
G01X845328Y15489D02*
X846083D01*
G01X841391D02*
X842146D01*
G01X837454D02*
X838209D01*
G01X833517D02*
X834272D01*
G01X829580D02*
X830335D01*
G01X825643D02*
X826398D01*
G01X821706D02*
X822461D01*
G01X817769D02*
X818524D01*
G01X813831D02*
X814587D01*
G01X809894D02*
X810650D01*
G01X805957D02*
X806713D01*
G01X802020D02*
X802776D01*
G01Y15411D02*
X802020D01*
G01X806713D02*
X805957D01*
G01X810650D02*
X809894D01*
G01X814587D02*
X813831D01*
G01X818524D02*
X817769D01*
G01X826398D02*
X825643D01*
G01X822461D02*
X821706D01*
G01X830335D02*
X829580D01*
G01X834272D02*
X833517D01*
G01X838209D02*
X837454D01*
G01X842146D02*
X841391D01*
G01X846083D02*
X845328D01*
G01X802776Y15329D02*
X802020D01*
G01X806713D02*
X805957D01*
G01X810650D02*
X809894D01*
G01X814587D02*
X813831D01*
G01X818524D02*
X817769D01*
G01X826398D02*
X825643D01*
G01X822461D02*
X821706D01*
G01X830335D02*
X829580D01*
G01X834272D02*
X833517D01*
G01X838209D02*
X837454D01*
G01X842146D02*
X841391D01*
G01X846083D02*
X845328D01*
G01X802776Y15311D02*
X802020D01*
G01X806713D02*
X805957D01*
G01X810650D02*
X809894D01*
G01X814587D02*
X813831D01*
G01X818524D02*
X817769D01*
G01X826398D02*
X825643D01*
G01X822461D02*
X821706D01*
G01X830335D02*
X829580D01*
G01X834272D02*
X833517D01*
G01X838209D02*
X837454D01*
G01X842146D02*
X841391D01*
G01X846083D02*
X845328D01*
G01X802776Y15292D02*
X802020D01*
G01X806713D02*
X805957D01*
G01X810650D02*
X809894D01*
G01X814587D02*
X813831D01*
G01X818524D02*
X817769D01*
G01X826398D02*
X825643D01*
G01X822461D02*
X821706D01*
G01X830335D02*
X829580D01*
G01X834272D02*
X833517D01*
G01X838209D02*
X837454D01*
G01X842146D02*
X841391D01*
G01X846083D02*
X845328D01*
G01X845256Y15217D02*
X845328D01*
G01X841319D02*
X841391D01*
G01X837382D02*
X837454D01*
G01X833445D02*
X833517D01*
G01X829508D02*
X829580D01*
G01X821634D02*
X821706D01*
G01X825571D02*
X825643D01*
G01X817697D02*
X817769D01*
G01X813760D02*
X813831D01*
G01X809823D02*
X809894D01*
G01X805886D02*
X805957D01*
G01X801949D02*
X802020D01*
G01X802808Y13183D02*
X802020D01*
G01X806745D02*
X805957D01*
G01X810682D02*
X809894D01*
G01X814619D02*
X813831D01*
G01X818556D02*
X817769D01*
G01X826430D02*
X825643D01*
G01X822493D02*
X821706D01*
G01X830367D02*
X829580D01*
G01X834304D02*
X833517D01*
G01X838241D02*
X837454D01*
G01X842178D02*
X841391D01*
G01X846115D02*
X845328D01*
G01X802808Y12848D02*
X802020D01*
G01X806745D02*
X805957D01*
G01X810682D02*
X809894D01*
G01X814619D02*
X813831D01*
G01X818556D02*
X817769D01*
G01X826430D02*
X825643D01*
G01X822493D02*
X821706D01*
G01X830367D02*
X829580D01*
G01X834304D02*
X833517D01*
G01X838241D02*
X837454D01*
G01X842178D02*
X841391D01*
G01X846115D02*
X845328D01*
G01X802650Y12198D02*
X802178D01*
G01X806587D02*
X806115D01*
G01X810524D02*
X810052D01*
G01X814461D02*
X813989D01*
G01X818398D02*
X817926D01*
G01X826272D02*
X825800D01*
G01X822335D02*
X821863D01*
G01X830209D02*
X829737D01*
G01X834146D02*
X833674D01*
G01X838083D02*
X837611D01*
G01X842020D02*
X841548D01*
G01X845957D02*
X845485D01*
G01X845328Y12161D02*
X846083D01*
G01X841391D02*
X842146D01*
G01X837454D02*
X838209D01*
G01X833517D02*
X834272D01*
G01X829580D02*
X830335D01*
G01X825643D02*
X826398D01*
G01X821706D02*
X822461D01*
G01X817769D02*
X818524D01*
G01X813831D02*
X814587D01*
G01X809894D02*
X810650D01*
G01X805957D02*
X806713D01*
G01X802020D02*
X802776D01*
G01X845485Y12041D02*
X845957D01*
G01X841548D02*
X842020D01*
G01X837611D02*
X838083D01*
G01X833674D02*
X834146D01*
G01X829737D02*
X830209D01*
G01X825800D02*
X826272D01*
G01X821863D02*
X822335D01*
G01X817926D02*
X818398D01*
G01X813989D02*
X814461D01*
G01X810052D02*
X810524D01*
G01X806115D02*
X806587D01*
G01X802178D02*
X802650D01*
G01X802776Y11939D02*
X802020D01*
G01X806713D02*
X805957D01*
G01X810650D02*
X809894D01*
G01X814587D02*
X813831D01*
G01X818524D02*
X817769D01*
G01X826398D02*
X825643D01*
G01X822461D02*
X821706D01*
G01X830335D02*
X829580D01*
G01X834272D02*
X833517D01*
G01X838209D02*
X837454D01*
G01X842146D02*
X841391D01*
G01X846083D02*
X845328D01*
G01X802808Y11512D02*
X802020D01*
G01X806745D02*
X805957D01*
G01X810682D02*
X809894D01*
G01X814619D02*
X813831D01*
G01X818556D02*
X817769D01*
G01X826430D02*
X825643D01*
G01X822493D02*
X821706D01*
G01X830367D02*
X829580D01*
G01X834304D02*
X833517D01*
G01X838241D02*
X837454D01*
G01X842178D02*
X841391D01*
G01X846115D02*
X845328D01*
G01X806745Y10999D02*
X806713D01*
G01X802808D02*
X802776D01*
G01X810682D02*
X810650D01*
G01X814619D02*
X814587D01*
G01X818556D02*
X818524D01*
G01X822493D02*
X822461D01*
G01X830367D02*
X830335D01*
G01X826430D02*
X826398D01*
G01X834304D02*
X834272D01*
G01X838241D02*
X838209D01*
G01X842178D02*
X842146D01*
G01X846115D02*
X846083D01*
G01X845328Y10950D02*
X846083D01*
G01X841391D02*
X842146D01*
G01X837454D02*
X838209D01*
G01X833517D02*
X834272D01*
G01X829580D02*
X830335D01*
G01X825643D02*
X826398D01*
G01X821706D02*
X822461D01*
G01X817769D02*
X818524D01*
G01X813831D02*
X814587D01*
G01X809894D02*
X810650D01*
G01X805957D02*
X806713D01*
G01X802020D02*
X802776D01*
G01Y10137D02*
X802020D01*
G01X806713D02*
X805957D01*
G01X810650D02*
X809894D01*
G01X814587D02*
X813831D01*
G01X818524D02*
X817769D01*
G01X826398D02*
X825643D01*
G01X822461D02*
X821706D01*
G01X830335D02*
X829580D01*
G01X834272D02*
X833517D01*
G01X838209D02*
X837454D01*
G01X842146D02*
X841391D01*
G01X846083D02*
X845328D01*
G01X837402Y9646D02*
X842126D01*
G01X801969D02*
X806693D01*
G01X842126Y9055D02*
X872835D01*
G01X806693D02*
X837402D01*
G01X806693Y8939D02*
X801969D01*
G01X842126D02*
X837402D01*
G01X802808Y8443D02*
X802020D01*
G01X806745D02*
X805957D01*
G01X810682D02*
X809894D01*
G01X814619D02*
X813831D01*
G01X818556D02*
X817769D01*
G01X826430D02*
X825643D01*
G01X822493D02*
X821706D01*
G01X830367D02*
X829580D01*
G01X834304D02*
X833517D01*
G01X838241D02*
X837454D01*
G01X842178D02*
X841391D01*
G01X846115D02*
X845328D01*
G01Y8193D02*
X846115D01*
G01X841391D02*
X842178D01*
G01X837454D02*
X838241D01*
G01X833517D02*
X834304D01*
G01X829580D02*
X830367D01*
G01X825643D02*
X826430D01*
G01X821706D02*
X822493D01*
G01X817769D02*
X818556D01*
G01X813831D02*
X814619D01*
G01X809894D02*
X810682D01*
G01X805957D02*
X806745D01*
G01X802020D02*
X802808D01*
G01Y7426D02*
X802020D01*
G01X806745D02*
X805957D01*
G01X810682D02*
X809894D01*
G01X814619D02*
X813831D01*
G01X818556D02*
X817769D01*
G01X826430D02*
X825643D01*
G01X822493D02*
X821706D01*
G01X830367D02*
X829580D01*
G01X834304D02*
X833517D01*
G01X838241D02*
X837454D01*
G01X842178D02*
X841391D01*
G01X846115D02*
X845328D01*
G01Y7205D02*
X846115D01*
G01X841391D02*
X842178D01*
G01X837454D02*
X838241D01*
G01X833517D02*
X834304D01*
G01X829580D02*
X830367D01*
G01X825643D02*
X826430D01*
G01X821706D02*
X822493D01*
G01X817769D02*
X818556D01*
G01X813831D02*
X814619D01*
G01X809894D02*
X810682D01*
G01X805957D02*
X806745D01*
G01X802020D02*
X802808D01*
G01Y5112D02*
X802020D01*
G01X806745D02*
X805957D01*
G01X810682D02*
X809894D01*
G01X814619D02*
X813831D01*
G01X818556D02*
X817769D01*
G01X826430D02*
X825643D01*
G01X822493D02*
X821706D01*
G01X830367D02*
X829580D01*
G01X834304D02*
X833517D01*
G01X838241D02*
X837454D01*
G01X842178D02*
X841391D01*
G01X846115D02*
X845328D01*
G01X802808Y4915D02*
X802020D01*
G01X806745D02*
X805957D01*
G01X810682D02*
X809894D01*
G01X814619D02*
X813831D01*
G01X818556D02*
X817769D01*
G01X826430D02*
X825643D01*
G01X822493D02*
X821706D01*
G01X830367D02*
X829580D01*
G01X834304D02*
X833517D01*
G01X838241D02*
X837454D01*
G01X842178D02*
X841391D01*
G01X846115D02*
X845328D01*
G01X846673Y26772D02*
X846083Y26181D01*
G01X842736Y26772D02*
X842146Y26181D01*
G01X838799Y26772D02*
X838209Y26181D01*
G01X834862Y26772D02*
X834272Y26181D01*
G01X830925Y26772D02*
X830335Y26181D01*
G01X826988Y26772D02*
X826398Y26181D01*
G01X823051Y26772D02*
X822461Y26181D01*
G01X819114Y26772D02*
X818524Y26181D01*
G01X815177Y26772D02*
X814587Y26181D01*
G01X811240Y26772D02*
X810650Y26181D01*
G01X807303Y26772D02*
X806713Y26181D01*
G01X803366Y26772D02*
X802776Y26181D01*
G01X846115Y26214D02*
Y30899D01*
G01X846083Y26181D02*
Y24409D01*
G01X845328Y30899D02*
Y24409D01*
G01X845256Y26181D02*
Y24409D01*
G01X842178Y26214D02*
Y30899D01*
G01X842146Y26181D02*
Y24409D01*
G01X841391Y30899D02*
Y24409D01*
G01X841319Y26181D02*
Y24409D01*
G01X838241Y26214D02*
Y30899D01*
G01X838209Y26181D02*
Y24409D01*
G01X837454Y30899D02*
Y24409D01*
G01X837382Y26181D02*
Y24409D01*
G01X834304Y26214D02*
Y30899D01*
G01X834272Y26181D02*
Y24409D01*
G01X833517Y30899D02*
Y24409D01*
G01X833445Y26181D02*
Y24409D01*
G01X830367Y26214D02*
Y30899D01*
G01X830335Y26181D02*
Y24409D01*
G01X829580Y30899D02*
Y24409D01*
G01X829508Y26181D02*
Y24409D01*
G01X826430Y26214D02*
Y30899D01*
G01X826398Y26181D02*
Y24409D01*
G01X825643Y30899D02*
Y24409D01*
G01X825571Y26181D02*
Y24409D01*
G01X822493Y26214D02*
Y30899D01*
G01X822461Y26181D02*
Y24409D01*
G01X821706Y30899D02*
Y24409D01*
G01X821634Y26181D02*
Y24409D01*
G01X818556Y26214D02*
Y30899D01*
G01X818524Y26181D02*
Y24409D01*
G01X817769Y30899D02*
Y24409D01*
G01X817697Y26181D02*
Y24409D01*
G01X814619Y26214D02*
Y30899D01*
G01X814587Y26181D02*
Y24409D01*
G01X813831Y30899D02*
Y24409D01*
G01X813760Y26181D02*
Y24409D01*
G01X810682Y26214D02*
Y30899D01*
G01X810650Y26181D02*
Y24409D01*
G01X809894Y30899D02*
Y24409D01*
G01X809823Y26181D02*
Y24409D01*
G01X806745Y26214D02*
Y30899D01*
G01X806713Y26181D02*
Y24409D01*
G01X805957Y30899D02*
Y24409D01*
G01X805886Y26181D02*
Y24409D01*
G01X802808Y26214D02*
Y30899D01*
G01X802776Y26181D02*
Y24409D01*
G01X802020Y30899D02*
Y24409D01*
G01X801949Y26181D02*
Y24409D01*
G01X800394Y26772D02*
Y26575D01*
G01X845256Y26181D02*
X844665Y26772D01*
G01X841319Y26181D02*
X840728Y26772D01*
G01X837382Y26181D02*
X836791Y26772D01*
G01X833445Y26181D02*
X832854Y26772D01*
G01X829508Y26181D02*
X828917Y26772D01*
G01X825571Y26181D02*
X824980Y26772D01*
G01X821634Y26181D02*
X821043Y26772D01*
G01X817697Y26181D02*
X817106Y26772D01*
G01X813760Y26181D02*
X813169Y26772D01*
G01X809823Y26181D02*
X809232Y26772D01*
G01X805886Y26181D02*
X805295Y26772D01*
G01X801949Y26181D02*
X801358Y26772D01*
G01X845328Y25192D02*
X845256Y25197D01*
G01X841391Y25192D02*
X841319Y25197D01*
G01X837454Y25192D02*
X837382Y25197D01*
G01X833517Y25192D02*
X833445Y25197D01*
G01X829580Y25192D02*
X829508Y25197D01*
G01X825643Y25192D02*
X825571Y25197D01*
G01X821706Y25192D02*
X821634Y25197D01*
G01X817769Y25192D02*
X817697Y25197D01*
G01X813831Y25192D02*
X813760Y25197D01*
G01X809894Y25192D02*
X809823Y25197D01*
G01X805957Y25192D02*
X805886Y25197D01*
G01X802020Y25192D02*
X801949Y25197D01*
G01X802808Y30899D02*
X802020D01*
G01X806745D02*
X805957D01*
G01X810682D02*
X809894D01*
G01X814619D02*
X813831D01*
G01X818556D02*
X817769D01*
G01X826430D02*
X825643D01*
G01X822493D02*
X821706D01*
G01X830367D02*
X829580D01*
G01X834304D02*
X833517D01*
G01X838241D02*
X837454D01*
G01X842178D02*
X841391D01*
G01X846115D02*
X845328D01*
G01Y30506D02*
X846115D01*
G01X841391D02*
X842178D01*
G01X837454D02*
X838241D01*
G01X833517D02*
X834304D01*
G01X829580D02*
X830367D01*
G01X825643D02*
X826430D01*
G01X821706D02*
X822493D01*
G01X817769D02*
X818556D01*
G01X813831D02*
X814619D01*
G01X809894D02*
X810682D01*
G01X805957D02*
X806745D01*
G01X802020D02*
X802808D01*
G01Y28781D02*
X802020D01*
G01X806745D02*
X805957D01*
G01X810682D02*
X809894D01*
G01X814619D02*
X813831D01*
G01X818556D02*
X817769D01*
G01X826430D02*
X825643D01*
G01X822493D02*
X821706D01*
G01X830367D02*
X829580D01*
G01X834304D02*
X833517D01*
G01X838241D02*
X837454D01*
G01X842178D02*
X841391D01*
G01X846115D02*
X845328D01*
G01Y28364D02*
X846115D01*
G01X841391D02*
X842178D01*
G01X837454D02*
X838241D01*
G01X833517D02*
X834304D01*
G01X829580D02*
X830367D01*
G01X825643D02*
X826430D01*
G01X821706D02*
X822493D01*
G01X817769D02*
X818556D01*
G01X813831D02*
X814619D01*
G01X809894D02*
X810682D01*
G01X805957D02*
X806745D01*
G01X802020D02*
X802808D01*
G01Y27706D02*
X802020D01*
G01X806745D02*
X805957D01*
G01X810682D02*
X809894D01*
G01X814619D02*
X813831D01*
G01X818556D02*
X817769D01*
G01X826430D02*
X825643D01*
G01X822493D02*
X821706D01*
G01X830367D02*
X829580D01*
G01X834304D02*
X833517D01*
G01X838241D02*
X837454D01*
G01X842178D02*
X841391D01*
G01X846115D02*
X845328D01*
G01Y27419D02*
X846115D01*
G01X841391D02*
X842178D01*
G01X837454D02*
X838241D01*
G01X833517D02*
X834304D01*
G01X829580D02*
X830367D01*
G01X825643D02*
X826430D01*
G01X821706D02*
X822493D01*
G01X817769D02*
X818556D01*
G01X813831D02*
X814619D01*
G01X809894D02*
X810682D01*
G01X805957D02*
X806745D01*
G01X802020D02*
X802808D01*
G01Y26859D02*
X802020D01*
G01X806745D02*
X805957D01*
G01X810682D02*
X809894D01*
G01X814619D02*
X813831D01*
G01X818556D02*
X817769D01*
G01X826430D02*
X825643D01*
G01X822493D02*
X821706D01*
G01X830367D02*
X829580D01*
G01X834304D02*
X833517D01*
G01X838241D02*
X837454D01*
G01X842178D02*
X841391D01*
G01X846115D02*
X845328D01*
G01X802808Y26687D02*
X802020D01*
G01X806745D02*
X805957D01*
G01X810682D02*
X809894D01*
G01X814619D02*
X813831D01*
G01X818556D02*
X817769D01*
G01X826430D02*
X825643D01*
G01X822493D02*
X821706D01*
G01X830367D02*
X829580D01*
G01X834304D02*
X833517D01*
G01X838241D02*
X837454D01*
G01X842178D02*
X841391D01*
G01X846115D02*
X845328D01*
G01X802808Y26608D02*
X802020D01*
G01X806745D02*
X805957D01*
G01X810682D02*
X809894D01*
G01X814619D02*
X813831D01*
G01X818556D02*
X817769D01*
G01X826430D02*
X825643D01*
G01X822493D02*
X821706D01*
G01X830367D02*
X829580D01*
G01X834304D02*
X833517D01*
G01X838241D02*
X837454D01*
G01X842178D02*
X841391D01*
G01X846115D02*
X845328D01*
G01X802808Y26588D02*
X802020D01*
G01X806745D02*
X805957D01*
G01X810682D02*
X809894D01*
G01X814619D02*
X813831D01*
G01X818556D02*
X817769D01*
G01X826430D02*
X825643D01*
G01X822493D02*
X821706D01*
G01X830367D02*
X829580D01*
G01X834304D02*
X833517D01*
G01X838241D02*
X837454D01*
G01X842178D02*
X841391D01*
G01X846115D02*
X845328D01*
G01X802808Y26490D02*
X802020D01*
G01X806745D02*
X805957D01*
G01X810682D02*
X809894D01*
G01X814619D02*
X813831D01*
G01X818556D02*
X817769D01*
G01X826430D02*
X825643D01*
G01X822493D02*
X821706D01*
G01X830367D02*
X829580D01*
G01X834304D02*
X833517D01*
G01X838241D02*
X837454D01*
G01X842178D02*
X841391D01*
G01X846115D02*
X845328D01*
G01X802776Y26181D02*
X801949D01*
G01X806713D02*
X805886D01*
G01X810650D02*
X809823D01*
G01X814587D02*
X813760D01*
G01X818524D02*
X817697D01*
G01X826398D02*
X825571D01*
G01X822461D02*
X821634D01*
G01X830335D02*
X829508D01*
G01X834272D02*
X833445D01*
G01X838209D02*
X837382D01*
G01X842146D02*
X841319D01*
G01X846083D02*
X845256D01*
G01X802776Y25495D02*
X802020D01*
G01X806713D02*
X805957D01*
G01X810650D02*
X809894D01*
G01X814587D02*
X813831D01*
G01X818524D02*
X817769D01*
G01X826398D02*
X825643D01*
G01X822461D02*
X821706D01*
G01X830335D02*
X829580D01*
G01X834272D02*
X833517D01*
G01X838209D02*
X837454D01*
G01X842146D02*
X841391D01*
G01X846083D02*
X845328D01*
G01X802776Y25197D02*
X801949D01*
G01X806713D02*
X805886D01*
G01X810650D02*
X809823D01*
G01X814587D02*
X813760D01*
G01X818524D02*
X817697D01*
G01X826398D02*
X825571D01*
G01X822461D02*
X821634D01*
G01X830335D02*
X829508D01*
G01X834272D02*
X833445D01*
G01X838209D02*
X837382D01*
G01X842146D02*
X841319D01*
G01X846083D02*
X845256D01*
G01X802776Y25191D02*
X802020D01*
G01X806713D02*
X805957D01*
G01X810650D02*
X809894D01*
G01X814587D02*
X813831D01*
G01X818524D02*
X817769D01*
G01X826398D02*
X825643D01*
G01X822461D02*
X821706D01*
G01X830335D02*
X829580D01*
G01X834272D02*
X833517D01*
G01X838209D02*
X837454D01*
G01X842146D02*
X841391D01*
G01X846083D02*
X845328D01*
G01X802776Y24994D02*
X802020D01*
G01X806713D02*
X805957D01*
G01X810650D02*
X809894D01*
G01X814587D02*
X813831D01*
G01X818524D02*
X817769D01*
G01X826398D02*
X825643D01*
G01X822461D02*
X821706D01*
G01X830335D02*
X829580D01*
G01X834272D02*
X833517D01*
G01X838209D02*
X837454D01*
G01X842146D02*
X841391D01*
G01X846083D02*
X845328D01*
G01X802776Y24724D02*
X801949D01*
G01X806713D02*
X805886D01*
G01X810650D02*
X809823D01*
G01X814587D02*
X813760D01*
G01X818524D02*
X817697D01*
G01X826398D02*
X825571D01*
G01X822461D02*
X821634D01*
G01X830335D02*
X829508D01*
G01X834272D02*
X833445D01*
G01X838209D02*
X837382D01*
G01X842146D02*
X841319D01*
G01X846083D02*
X845256D01*
G01X802776Y24600D02*
X802020D01*
G01X806713D02*
X805957D01*
G01X810650D02*
X809894D01*
G01X814587D02*
X813831D01*
G01X818524D02*
X817769D01*
G01X826398D02*
X825643D01*
G01X822461D02*
X821706D01*
G01X830335D02*
X829580D01*
G01X834272D02*
X833517D01*
G01X838209D02*
X837454D01*
G01X842146D02*
X841391D01*
G01X846083D02*
X845328D01*
G01X802776Y24409D02*
X801949D01*
G01X806713D02*
X805886D01*
G01X810650D02*
X809823D01*
G01X814587D02*
X813760D01*
G01X818524D02*
X817697D01*
G01X826398D02*
X825571D01*
G01X822461D02*
X821634D01*
G01X830335D02*
X829508D01*
G01X834272D02*
X833445D01*
G01X838209D02*
X837382D01*
G01X842146D02*
X841319D01*
G01X846083D02*
X845256D01*
G01X802776Y22047D02*
X801949D01*
G01X806713D02*
X805886D01*
G01X810650D02*
X809823D01*
G01X814587D02*
X813760D01*
G01X818524D02*
X817697D01*
G01X822461D02*
X821634D01*
G01X826398D02*
X825571D01*
G01X830335D02*
X829508D01*
G01X834272D02*
X833445D01*
G01X838209D02*
X837382D01*
G01X842146D02*
X841319D01*
G01X846083D02*
X845256D01*
G01X802776Y21541D02*
X802020D01*
G01X806713D02*
X805957D01*
G01X810650D02*
X809894D01*
G01X814587D02*
X813831D01*
G01X818524D02*
X817769D01*
G01X826398D02*
X825643D01*
G01X822461D02*
X821706D01*
G01X830335D02*
X829580D01*
G01X834272D02*
X833517D01*
G01X838209D02*
X837454D01*
G01X842146D02*
X841391D01*
G01X846083D02*
X845328D01*
G01Y21520D02*
X846083D01*
G01X841391D02*
X842146D01*
G01X837454D02*
X838209D01*
G01X833517D02*
X834272D01*
G01X829580D02*
X830335D01*
G01X825643D02*
X826398D01*
G01X821706D02*
X822461D01*
G01X817769D02*
X818524D01*
G01X813831D02*
X814587D01*
G01X809894D02*
X810650D01*
G01X805957D02*
X806713D01*
G01X802020D02*
X802776D01*
G01X845328Y21175D02*
X846083D01*
G01X841391D02*
X842146D01*
G01X837454D02*
X838209D01*
G01X833517D02*
X834272D01*
G01X829580D02*
X830335D01*
G01X825643D02*
X826398D01*
G01X821706D02*
X822461D01*
G01X817769D02*
X818524D01*
G01X813831D02*
X814587D01*
G01X809894D02*
X810650D01*
G01X805957D02*
X806713D01*
G01X802020D02*
X802776D01*
G01Y20702D02*
X802020D01*
G01X806713D02*
X805957D01*
G01X810650D02*
X809894D01*
G01X814587D02*
X813831D01*
G01X818524D02*
X817769D01*
G01X826398D02*
X825643D01*
G01X822461D02*
X821706D01*
G01X830335D02*
X829580D01*
G01X834272D02*
X833517D01*
G01X838209D02*
X837454D01*
G01X842146D02*
X841391D01*
G01X846083D02*
X845328D01*
G01X802776Y20584D02*
X802020D01*
G01X806713D02*
X805957D01*
G01X810650D02*
X809894D01*
G01X814587D02*
X813831D01*
G01X818524D02*
X817769D01*
G01X826398D02*
X825643D01*
G01X822461D02*
X821706D01*
G01X830335D02*
X829580D01*
G01X834272D02*
X833517D01*
G01X838209D02*
X837454D01*
G01X842146D02*
X841391D01*
G01X846083D02*
X845328D01*
G01X802808Y20387D02*
X802020D01*
G01X806745D02*
X805957D01*
G01X810682D02*
X809894D01*
G01X814619D02*
X813831D01*
G01X818556D02*
X817769D01*
G01X826430D02*
X825643D01*
G01X822493D02*
X821706D01*
G01X830367D02*
X829580D01*
G01X834304D02*
X833517D01*
G01X838241D02*
X837454D01*
G01X842178D02*
X841391D01*
G01X846115D02*
X845328D01*
G01X802808Y20309D02*
X802020D01*
G01X806745D02*
X805957D01*
G01X810682D02*
X809894D01*
G01X814619D02*
X813831D01*
G01X818556D02*
X817769D01*
G01X826430D02*
X825643D01*
G01X822493D02*
X821706D01*
G01X830367D02*
X829580D01*
G01X834304D02*
X833517D01*
G01X838241D02*
X837454D01*
G01X842178D02*
X841391D01*
G01X846115D02*
X845328D01*
G01Y20191D02*
X846115D01*
G01X841391D02*
X842178D01*
G01X837454D02*
X838241D01*
G01X833517D02*
X834304D01*
G01X829580D02*
X830367D01*
G01X825643D02*
X826430D01*
G01X821706D02*
X822493D01*
G01X817769D02*
X818556D01*
G01X813831D02*
X814619D01*
G01X809894D02*
X810682D01*
G01X805957D02*
X806745D01*
G01X802020D02*
X802808D01*
G01X806437Y277843D02*
G03X813362Y264712I37662J11471D01*
G01X806437Y277843D02*
G03X813362Y264712I37662J11471D01*
G01X806437Y750284D02*
G03X813362Y737154I37661J11472D01*
G01X806437Y750284D02*
G03X813362Y737153I37662J11471D01*
G01X833496Y1589446D02*
X833578Y1589382D01*
G01X833445Y1589513D02*
X833496Y1589446D01*
G01X833443Y1589575D02*
X833445Y1589513D01*
G01X833493Y1589622D02*
X833443Y1589575D01*
G01X833576Y1589653D02*
X833493Y1589622D01*
G01X833576Y1589384D02*
X833680Y1589323D01*
G01X833493Y1589448D02*
X833576Y1589384D01*
G01X833443Y1589516D02*
X833493Y1589448D01*
G01X833445Y1589578D02*
X833443Y1589516D01*
G01X833496Y1589624D02*
X833445Y1589578D01*
G01X833578Y1589654D02*
X833496Y1589624D01*
G01X826028Y1591630D02*
X826278Y1591929D01*
G01X825879Y1591275D02*
X826028Y1591630D01*
G01X833115D02*
X833365Y1591929D01*
G01X832966Y1591275D02*
X833115Y1591630D01*
G01X840202D02*
X840451Y1591929D01*
G01X840052Y1591275D02*
X840202Y1591630D01*
G01X825852Y1591141D02*
X825843Y1591001D01*
G01X825879Y1591281D02*
X825852Y1591141D01*
G01X832939D02*
X832930Y1591001D01*
G01X832966Y1591281D02*
X832939Y1591141D01*
G01X840026D02*
X840017Y1591001D01*
G01X840052Y1591281D02*
X840026Y1591141D01*
G01X826052Y1591536D02*
X826278Y1591929D01*
G01X825899Y1591060D02*
X826052Y1591536D01*
G01X825843Y1590537D02*
X825899Y1591060D01*
G01X833139Y1591536D02*
X833365Y1591929D01*
G01X832985Y1591060D02*
X833139Y1591536D01*
G01X832930Y1590537D02*
X832985Y1591060D01*
G01X840225Y1591536D02*
X840451Y1591929D01*
G01X840072Y1591060D02*
X840225Y1591536D01*
G01X840017Y1590537D02*
X840072Y1591060D01*
G01X828967Y1591113D02*
X828950Y1591226D01*
G01X828973Y1591001D02*
X828967Y1591113D01*
G01X836054D02*
X836037Y1591226D01*
G01X836060Y1591001D02*
X836054Y1591113D01*
G01X843141D02*
X843123Y1591226D01*
G01X843146Y1591001D02*
X843141Y1591113D01*
G01X828769Y1591527D02*
X828538Y1591929D01*
G01X828919Y1591055D02*
X828769Y1591527D01*
G01X828973Y1590537D02*
X828919Y1591055D01*
G01X835855Y1591527D02*
X835625Y1591929D01*
G01X836005Y1591055D02*
X835855Y1591527D01*
G01X836060Y1590537D02*
X836005Y1591055D01*
G01X842942Y1591527D02*
X842711Y1591929D01*
G01X843092Y1591055D02*
X842942Y1591527D01*
G01X843146Y1590537D02*
X843092Y1591055D01*
G01X834457Y1588954D02*
X834348Y1589023D01*
G01X834549Y1588879D02*
X834457Y1588954D01*
G01X834615Y1588793D02*
X834549Y1588879D01*
G01X834639Y1588701D02*
X834615Y1588793D01*
G01X828867Y1591478D02*
X828950Y1591218D01*
G01X828728Y1591719D02*
X828867Y1591478D01*
G01X828538Y1591929D02*
X828728Y1591719D01*
G01X835954Y1591478D02*
X836037Y1591218D01*
G01X835815Y1591719D02*
X835954Y1591478D01*
G01X835625Y1591929D02*
X835815Y1591719D01*
G01X843041Y1591478D02*
X843123Y1591218D01*
G01X842902Y1591719D02*
X843041Y1591478D01*
G01X842711Y1591929D02*
X842902Y1591719D01*
G01X834457Y1588954D02*
X834549Y1588879D01*
G01X834348Y1589023D02*
X834457Y1588954D01*
G01X834222Y1589088D02*
X834348Y1589023D01*
G01X834083Y1589151D02*
X834222Y1589088D01*
G01X833930Y1589213D02*
X834083Y1589151D01*
G01X835625Y1591929D02*
G03X833365I-1130J-1083D01*
G01X842711D02*
G03X840451I-1130J-1083D01*
G01X843550Y1610157D02*
G03I-1969J0D01*
G01X836463D02*
G03I-1968J0D01*
G01X827480Y1598032D02*
G03I-708J0D01*
G01X828538Y1591929D02*
G03X826278I-1130J-1083D01*
G01X829377Y1610157D02*
G03I-1969J0D01*
G01X843123Y1587205D02*
X843146D01*
G01X836037D02*
X836060D01*
G01X828950D02*
X828973D01*
G01X825879Y1595729D02*
X824147D01*
G01X832966D02*
X828950D01*
G01X840052D02*
X836037D01*
G01X847139D02*
X843123D01*
G01X842711Y1591929D02*
X847538D01*
G01X835625D02*
X840451D01*
G01X828538D02*
X833365D01*
G01X824416D02*
X826278D01*
G01X880289Y1589685D02*
X824147D01*
G01X833930Y1589213D02*
X824147D01*
G01X848103D02*
X834639D01*
G01X827553Y1588780D02*
X826372D01*
G01X834639Y1588386D02*
X833458D01*
G01X824147Y1587205D02*
X915715D01*
G01X824147Y1585630D02*
X880289D01*
G01X915430Y1584843D02*
X824416D01*
G01X828950Y1584449D02*
X825879D01*
G01X836037D02*
X832966D01*
G01X843123D02*
X840052D01*
G01X827769Y1583268D02*
X827060D01*
G01X834856D02*
X834147D01*
G01X841942D02*
X841233D01*
G01X824147Y1582283D02*
X880289D01*
G01X825843Y1587205D02*
X825879D01*
G01X832930D02*
X832966D01*
G01X840017D02*
X840052D01*
G01X833930Y1589685D02*
X833796Y1589682D01*
G01X833798D02*
X833678Y1589672D01*
G01X833680D02*
X833576Y1589653D01*
G01X833678Y1589324D02*
X833798Y1589267D01*
G01X833796D02*
X833930Y1589213D01*
G01X840052Y1584449D02*
X841233Y1583268D01*
G01X832966Y1584449D02*
X834147Y1583268D01*
G01X825879Y1584449D02*
X827060Y1583268D01*
G01X834615Y1588793D02*
X834639Y1588701D01*
G01X843146Y1591001D02*
Y1584843D01*
G01X843123Y1595729D02*
Y1584449D01*
G01X840052Y1595729D02*
Y1584449D01*
G01X840017Y1591001D02*
Y1584843D01*
G01X836060Y1591001D02*
Y1584843D01*
G01X836037Y1595729D02*
Y1584449D01*
G01X834639Y1589685D02*
Y1588386D01*
G01X833458Y1589685D02*
Y1588386D01*
G01X832966Y1595729D02*
Y1584449D01*
G01X832930Y1591001D02*
Y1584843D01*
G01X828973Y1591001D02*
Y1584843D01*
G01X828950Y1595729D02*
Y1584449D01*
G01X827553Y1589685D02*
Y1588780D01*
G01X826372Y1589685D02*
Y1588780D01*
G01X825879Y1595729D02*
Y1584449D01*
G01X825843Y1591001D02*
Y1584843D01*
G01X824416D02*
Y1626713D01*
G01X824147Y1582283D02*
Y1675984D01*
G01X843123Y1584449D02*
X841942Y1583268D01*
G01X836037Y1584449D02*
X834856Y1583268D01*
G01X828950Y1584449D02*
X827769Y1583268D01*
G01X825042Y1660711D02*
X825106Y1660772D01*
G01X824967Y1660691D02*
X825042Y1660711D01*
G01X824891Y1660712D02*
X824967Y1660691D01*
G01X824827Y1660772D02*
X824891Y1660712D01*
G01X824785Y1660861D02*
X824827Y1660772D01*
G01X824770Y1660969D02*
X824785Y1660861D01*
G01X843123Y1642357D02*
G03Y1644137I-1299J890D01*
G01Y1635034D02*
G03Y1636814I-1299J890D01*
G01X836037Y1642357D02*
G03Y1644137I-1299J890D01*
G01X840052D02*
G03Y1642357I1299J-890D01*
G01X836037Y1635034D02*
G03Y1636814I-1299J890D01*
G01X840052D02*
G03Y1635034I1299J-890D01*
G01X842966Y1625348D02*
G03X843950Y1626332I0J984D01*
G01X839226D02*
G03X840210Y1625348I984J0D01*
G01X835879D02*
G03X836863Y1626332I0J984D01*
G01X840017Y1629843D02*
G03X843146I1564J-1D01*
G01X832930D02*
G03X836060I1565J0D01*
G01X832966Y1644137D02*
G03Y1642357I1299J-890D01*
G01Y1636814D02*
G03Y1635034I1299J-890D01*
G01X827480Y1650394D02*
G03I-708J0D01*
G01X828950Y1642357D02*
G03Y1644137I-1299J890D01*
G01Y1635034D02*
G03Y1636814I-1299J890D01*
G01X825879Y1644137D02*
G03Y1642357I1299J-890D01*
G01Y1636814D02*
G03Y1635034I1299J-890D01*
G01X832139Y1626332D02*
G03X833123Y1625348I984J0D01*
G01X828793D02*
G03X829777Y1626332I0J984D01*
G01X825052D02*
G03X826037Y1625348I984J0D01*
G01X827408Y1628278D02*
G03X828973Y1629843I0J1565D01*
G01X825981Y1628278D02*
G03X824416Y1626713I0J-1565D01*
G01X833628Y1662992D02*
X835991D01*
G01X828904D02*
X826542D01*
G01X843077D02*
X840715D01*
G01X828904Y1661417D02*
X826542D01*
G01X835991D02*
X833628D01*
G01X843077D02*
X840715D01*
G01X829002Y1661220D02*
X826443D01*
G01X836089D02*
X833530D01*
G01X843176D02*
X840617D01*
G01X831758Y1660157D02*
X830774D01*
G01X838845D02*
X837861D01*
G01X845931D02*
X844947D01*
G01X830161Y1659646D02*
X825284D01*
G01X837248D02*
X832371D01*
G01X844335D02*
X839457D01*
G01X880289Y1659213D02*
X824147D01*
G01X824770Y1659055D02*
X880282D01*
G01X880289Y1658661D02*
X824147D01*
G01X880289Y1658425D02*
X824147D01*
G01X825879Y1649757D02*
X824147D01*
G01X832966D02*
X828950D01*
G01X840052D02*
X836037D01*
G01X847139D02*
X843123D01*
G01X831542Y1648740D02*
X830361D01*
G01X838629D02*
X837448D01*
G01X845715D02*
X844534D01*
G01X832723Y1646694D02*
X829180D01*
G01X839810D02*
X836267D01*
G01X846896D02*
X843353D01*
G01X828163Y1631436D02*
X826667D01*
G01X835249D02*
X833753D01*
G01X842336D02*
X840840D01*
G01X825981Y1628278D02*
X827408D01*
G01X839226Y1627871D02*
X843950D01*
G01X832139D02*
X836863D01*
G01X825052D02*
X829777D01*
G01X828793Y1625348D02*
X826037D01*
G01X835879D02*
X833123D01*
G01X842966D02*
X840210D01*
G01X843766Y1661828D02*
X844947Y1660157D01*
G01X843766Y1660450D02*
X844335Y1659646D01*
G01X836680Y1661828D02*
X837861Y1660157D01*
G01X836680Y1660450D02*
X837248Y1659646D01*
G01X829593Y1661828D02*
X830774Y1660157D01*
G01X829593Y1660450D02*
X830161Y1659646D01*
G01X845715Y1648740D02*
X847098Y1646345D01*
G01X838629Y1648740D02*
X840011Y1646345D01*
G01X831542Y1648740D02*
X832925Y1646345D01*
G01X840840Y1631436D02*
X840052Y1632800D01*
G01X833753Y1631436D02*
X832966Y1632800D01*
G01X826667Y1631436D02*
X825879Y1632800D01*
G01X843150Y1635074D02*
X843146Y1629843D01*
G01X843154Y1642404D02*
X843150Y1636773D01*
G01X843156Y1646354D02*
X843155Y1644089D01*
G01X836063Y1635074D02*
X836060Y1629843D01*
G01X836067Y1642404D02*
X836064Y1636773D01*
G01X836070Y1646354D02*
X836068Y1644089D01*
G01X845931Y1660157D02*
Y1659055D01*
G01X844947Y1660157D02*
Y1659055D01*
G01X844335Y1659646D02*
Y1659055D01*
G01X843950Y1649757D02*
Y1626332D01*
G01X843766Y1672278D02*
Y1660450D01*
G01X843668Y1672008D02*
Y1658661D01*
G01X843471D02*
Y1670709D01*
G01X843176Y1665551D02*
Y1661220D01*
G01X843123Y1635034D02*
Y1632800D01*
G01Y1642357D02*
Y1636814D01*
G01Y1649757D02*
Y1644137D01*
G01X843077Y1665354D02*
Y1661417D01*
G01X840715Y1665354D02*
Y1661417D01*
G01X840617Y1665551D02*
Y1661220D01*
G01X840321Y1670709D02*
Y1658661D01*
G01X840124Y1672008D02*
Y1658661D01*
G01X840052Y1635034D02*
Y1632800D01*
G01Y1642357D02*
Y1636814D01*
G01Y1649757D02*
Y1644137D01*
G01X840026Y1672278D02*
Y1660450D01*
G01X839457Y1659646D02*
Y1659055D01*
G01X839226Y1649757D02*
Y1626332D01*
G01X838845Y1660157D02*
Y1659055D01*
G01X837861Y1660157D02*
Y1659055D01*
G01X837248Y1659646D02*
Y1659055D01*
G01X836863Y1649757D02*
Y1626332D01*
G01X836680Y1672278D02*
Y1660450D01*
G01X836581Y1672008D02*
Y1658661D01*
G01X836384D02*
Y1670709D01*
G01X836089Y1665551D02*
Y1661220D01*
G01X836037Y1635034D02*
Y1632800D01*
G01Y1642357D02*
Y1636814D01*
G01Y1649757D02*
Y1644137D01*
G01X835991Y1665354D02*
Y1661417D01*
G01X833628Y1665354D02*
Y1661417D01*
G01X833530Y1665551D02*
Y1661220D01*
G01X833235Y1670709D02*
Y1658661D01*
G01X833038Y1672008D02*
Y1658661D01*
G01X832966Y1635034D02*
Y1632800D01*
G01Y1642357D02*
Y1636814D01*
G01Y1649757D02*
Y1644137D01*
G01X832939Y1672278D02*
Y1660450D01*
G01X832371Y1659646D02*
Y1659055D01*
G01X832139Y1649757D02*
Y1626332D01*
G01X831758Y1660157D02*
Y1659055D01*
G01X830774Y1660157D02*
Y1659055D01*
G01X830161Y1659646D02*
Y1659055D01*
G01X829777Y1649757D02*
Y1626332D01*
G01X829593Y1672278D02*
Y1660450D01*
G01X829494Y1672008D02*
Y1658661D01*
G01X829298D02*
Y1670709D01*
G01X829002Y1665551D02*
Y1661220D01*
G01X828973Y1635069D02*
Y1629843D01*
G01Y1642392D02*
Y1636780D01*
G01Y1646348D02*
Y1644102D01*
G01X828950Y1635034D02*
Y1632800D01*
G01Y1642357D02*
Y1636814D01*
G01Y1649757D02*
Y1644137D01*
G01X828904Y1665354D02*
Y1661417D01*
G01X826542Y1665354D02*
Y1661417D01*
G01X826443Y1665551D02*
Y1661220D01*
G01X826148Y1670709D02*
Y1658661D01*
G01X825951Y1672008D02*
Y1658661D01*
G01X825879Y1635034D02*
Y1632800D01*
G01Y1642357D02*
Y1636814D01*
G01Y1649757D02*
Y1644137D01*
G01X825853Y1672278D02*
Y1660450D01*
G01X825284Y1659646D02*
Y1659055D01*
G01X825106Y1660772D02*
Y1659055D01*
G01X825052Y1649757D02*
Y1626332D01*
G01X824770Y1675984D02*
Y1659055D01*
G01X840013Y1635094D02*
X840017Y1629843D01*
G01X840009Y1642424D02*
X840012Y1636753D01*
G01X840007Y1646354D02*
X840008Y1644069D01*
G01X832927Y1635094D02*
X832930Y1629843D01*
G01X832922Y1642424D02*
X832926Y1636753D01*
G01X832920Y1646354D02*
X832921Y1644069D01*
G01X847113Y1661828D02*
X845931Y1660157D01*
G01X840026Y1660450D02*
X839457Y1659646D01*
G01X840026Y1661828D02*
X838845Y1660157D01*
G01X828975Y1646345D02*
X829180Y1646694D01*
G01X843123Y1632800D02*
X842336Y1631436D01*
G01X836037Y1632800D02*
X835249Y1631436D01*
G01X843151Y1646345D02*
X844534Y1648740D01*
G01X828950Y1632800D02*
X828163Y1631436D01*
G01X836065Y1646345D02*
X837448Y1648740D01*
G01X828973Y1646336D02*
X830361Y1648740D01*
G01X832939Y1660450D02*
X832371Y1659646D01*
G01X832939Y1661828D02*
X831758Y1660157D01*
G01X825853Y1660450D02*
X825284Y1659646D01*
G01X825853Y1661828D02*
X825106Y1660772D01*
G01X826366Y1711005D02*
X826233Y1710783D01*
G01X826489Y1711202D02*
X826366Y1711005D01*
G01X826600Y1711370D02*
X826489Y1711202D01*
G01X826696Y1711506D02*
X826600Y1711370D01*
G01X826772Y1711597D02*
X826696Y1711506D01*
G01X826815Y1711628D02*
X826772Y1711597D01*
G01X840539Y1711005D02*
X840407Y1710783D01*
G01X840662Y1711202D02*
X840539Y1711005D01*
G01X840773Y1711370D02*
X840662Y1711202D01*
G01X840869Y1711506D02*
X840773Y1711370D01*
G01X840945Y1711597D02*
X840869Y1711506D01*
G01X840988Y1711628D02*
X840945Y1711597D01*
G01X826908Y1711582D02*
X826775Y1711359D01*
G01X827031Y1711778D02*
X826908Y1711582D01*
G01X841081D02*
X840948Y1711359D01*
G01X841204Y1711778D02*
X841081Y1711582D01*
G01X826142Y1671488D02*
X826048Y1671394D01*
G01X826246Y1671572D02*
X826142Y1671488D01*
G01X833229D02*
X833135Y1671394D01*
G01X833333Y1671572D02*
X833229Y1671488D01*
G01X840315D02*
X840221Y1671394D01*
G01X840420Y1671572D02*
X840315Y1671488D01*
G01X826142D02*
X826246Y1671572D01*
G01X826048Y1671394D02*
X826142Y1671488D01*
G01X825968Y1671294D02*
X826048Y1671394D01*
G01X833229Y1671488D02*
X833333Y1671572D01*
G01X833135Y1671394D02*
X833229Y1671488D01*
G01X833055Y1671294D02*
X833135Y1671394D01*
G01X840315Y1671488D02*
X840420Y1671572D01*
G01X840221Y1671394D02*
X840315Y1671488D01*
G01X840141Y1671294D02*
X840221Y1671394D01*
G01X830437Y1681670D02*
X830445Y1681890D01*
G01X830415Y1681475D02*
X830437Y1681670D01*
G01X830380Y1681344D02*
X830415Y1681475D01*
G01X830341Y1681299D02*
X830380Y1681344D01*
G01X844611Y1681670D02*
X844618Y1681890D01*
G01X844588Y1681475D02*
X844611Y1681670D01*
G01X844554Y1681344D02*
X844588Y1681475D01*
G01X844514Y1681299D02*
X844554Y1681344D01*
G01X825867Y1671048D02*
X825853Y1670900D01*
G01X825906Y1671181D02*
X825867Y1671048D01*
G01X825968Y1671294D02*
X825906Y1671181D01*
G01X832954Y1671048D02*
X832939Y1670900D01*
G01X832993Y1671181D02*
X832954Y1671048D01*
G01X833055Y1671294D02*
X832993Y1671181D01*
G01X840040Y1671048D02*
X840026Y1670900D01*
G01X840080Y1671181D02*
X840040Y1671048D01*
G01X840141Y1671294D02*
X840080Y1671181D01*
G01X830480Y1681526D02*
X830485Y1681890D01*
G01X830465Y1681197D02*
X830480Y1681526D01*
G01X830442Y1680935D02*
X830465Y1681197D01*
G01X830413Y1680767D02*
X830442Y1680935D01*
G01X830381Y1680709D02*
X830413Y1680767D01*
G01X844653Y1681526D02*
X844658Y1681890D01*
G01X844638Y1681197D02*
X844653Y1681526D01*
G01X844615Y1680935D02*
X844638Y1681197D01*
G01X844586Y1680767D02*
X844615Y1680935D01*
G01X844554Y1680709D02*
X844586Y1680767D01*
G01X829373Y1670724D02*
X829298Y1670709D01*
G01X829437Y1670767D02*
X829373Y1670724D01*
G01X829479Y1670829D02*
X829437Y1670767D01*
G01X836459Y1670724D02*
X836384Y1670709D01*
G01X836524Y1670767D02*
X836459Y1670724D01*
G01X836566Y1670829D02*
X836524Y1670767D01*
G01X843546Y1670724D02*
X843471Y1670709D01*
G01X843610Y1670767D02*
X843546Y1670724D01*
G01X843652Y1670829D02*
X843610Y1670767D01*
G01X826100Y1672795D02*
X826246Y1672835D01*
G01X825972Y1672678D02*
X826100Y1672795D01*
G01X825885Y1672500D02*
X825972Y1672678D01*
G01X825853Y1672278D02*
X825885Y1672500D01*
G01X833187Y1672795D02*
X833333Y1672835D01*
G01X833059Y1672678D02*
X833187Y1672795D01*
G01X832972Y1672500D02*
X833059Y1672678D01*
G01X832939Y1672278D02*
X832972Y1672500D01*
G01X829839Y1681343D02*
X829799Y1681299D01*
G01X829873Y1681474D02*
X829839Y1681343D01*
G01X829896Y1681669D02*
X829873Y1681474D01*
G01X829903Y1681890D02*
X829896Y1681669D01*
G01X827318Y1680759D02*
X827136Y1680709D01*
G01X827457Y1680890D02*
X827318Y1680759D01*
G01X827541Y1681079D02*
X827457Y1680890D01*
G01X827556Y1681299D02*
X827541Y1681079D01*
G01X841491Y1680759D02*
X841309Y1680709D01*
G01X841631Y1680890D02*
X841491Y1680759D01*
G01X841714Y1681079D02*
X841631Y1680890D01*
G01X841729Y1681299D02*
X841714Y1681079D01*
G01X826831Y1680758D02*
X826650Y1680709D01*
G01X826971Y1680889D02*
X826831Y1680758D01*
G01X827055Y1681078D02*
X826971Y1680889D01*
G01X827069Y1681299D02*
X827055Y1681078D01*
G01X841004Y1680758D02*
X840823Y1680709D01*
G01X841144Y1680889D02*
X841004Y1680758D01*
G01X841228Y1681078D02*
X841144Y1680889D01*
G01X841243Y1681299D02*
X841228Y1681078D01*
G01X830215Y1681685D02*
X830219Y1681890D01*
G01X830206Y1681486D02*
X830215Y1681685D01*
G01X830191Y1681299D02*
X830206Y1681486D01*
G01X844389Y1681685D02*
X844392Y1681890D01*
G01X844379Y1681486D02*
X844389Y1681685D01*
G01X844364Y1681299D02*
X844379Y1681486D01*
G01X826452Y1680720D02*
X826337Y1680709D01*
G01X826561Y1680754D02*
X826452Y1680720D01*
G01X826661Y1680809D02*
X826561Y1680754D01*
G01X826749Y1680882D02*
X826661Y1680809D01*
G01X826822Y1680972D02*
X826749Y1680882D01*
G01X826875Y1681074D02*
X826822Y1680972D01*
G01X826908Y1681185D02*
X826875Y1681074D01*
G01X826919Y1681299D02*
X826908Y1681185D01*
G01X840626Y1680720D02*
X840511Y1680709D01*
G01X840734Y1680754D02*
X840626Y1680720D01*
G01X840834Y1680809D02*
X840734Y1680754D01*
G01X840922Y1680882D02*
X840834Y1680809D01*
G01X840995Y1680972D02*
X840922Y1680882D01*
G01X841048Y1681074D02*
X840995Y1680972D01*
G01X841081Y1681185D02*
X841048Y1681074D01*
G01X841093Y1681299D02*
X841081Y1681185D01*
G01X840274Y1672795D02*
X840420Y1672835D01*
G01X840146Y1672678D02*
X840274Y1672795D01*
G01X840059Y1672500D02*
X840146Y1672678D01*
G01X840026Y1672278D02*
X840059Y1672500D01*
G01X829943Y1680758D02*
X830124Y1680709D01*
G01X829803Y1680889D02*
X829943Y1680758D01*
G01X829719Y1681078D02*
X829803Y1680889D01*
G01X829704Y1681299D02*
X829719Y1681078D01*
G01X826880Y1681343D02*
X826919Y1681299D01*
G01X826845Y1681474D02*
X826880Y1681343D01*
G01X826822Y1681669D02*
X826845Y1681474D01*
G01X826815Y1681890D02*
X826822Y1681669D01*
G01X841053Y1681343D02*
X841093Y1681299D01*
G01X841019Y1681474D02*
X841053Y1681343D01*
G01X840996Y1681669D02*
X841019Y1681474D01*
G01X840988Y1681890D02*
X840996Y1681669D01*
G01X826847Y1680767D02*
X826879Y1680709D01*
G01X826818Y1680935D02*
X826847Y1680767D01*
G01X826795Y1681196D02*
X826818Y1680935D01*
G01X826780Y1681526D02*
X826795Y1681196D01*
G01X826775Y1681890D02*
X826780Y1681526D01*
G01X841020Y1680767D02*
X841052Y1680709D01*
G01X840991Y1680935D02*
X841020Y1680767D01*
G01X840968Y1681196D02*
X840991Y1680935D01*
G01X840954Y1681526D02*
X840968Y1681196D01*
G01X840948Y1681890D02*
X840954Y1681526D01*
G01X830955Y1680767D02*
X830922Y1680709D01*
G01X830983Y1680935D02*
X830955Y1680767D01*
G01X831007Y1681196D02*
X830983Y1680935D01*
G01X831021Y1681526D02*
X831007Y1681196D01*
G01X831026Y1681890D02*
X831021Y1681526D01*
G01X845128Y1680767D02*
X845096Y1680709D01*
G01X845157Y1680935D02*
X845128Y1680767D01*
G01X845180Y1681196D02*
X845157Y1680935D01*
G01X845194Y1681526D02*
X845180Y1681196D01*
G01X845200Y1681890D02*
X845194Y1681526D01*
G01X829720Y1681486D02*
X829704Y1681299D01*
G01X829729Y1681685D02*
X829720Y1681486D01*
G01X829732Y1681890D02*
X829729Y1681685D01*
G01X843893Y1681486D02*
X843878Y1681299D01*
G01X843902Y1681685D02*
X843893Y1681486D01*
G01X843906Y1681890D02*
X843902Y1681685D01*
G01X844012Y1681343D02*
X843972Y1681299D01*
G01X844046Y1681474D02*
X844012Y1681343D01*
G01X844069Y1681669D02*
X844046Y1681474D01*
G01X844076Y1681890D02*
X844069Y1681669D01*
G01X830266Y1680720D02*
X830381Y1680709D01*
G01X830157Y1680754D02*
X830266Y1680720D01*
G01X830057Y1680809D02*
X830157Y1680754D01*
G01X829969Y1680882D02*
X830057Y1680809D01*
G01X829896Y1680972D02*
X829969Y1680882D01*
G01X829843Y1681074D02*
X829896Y1680972D01*
G01X829810Y1681185D02*
X829843Y1681074D01*
G01X829799Y1681299D02*
X829810Y1681185D01*
G01X844439Y1680720D02*
X844554Y1680709D01*
G01X844330Y1680754D02*
X844439Y1680720D01*
G01X844230Y1680809D02*
X844330Y1680754D01*
G01X844143Y1680882D02*
X844230Y1680809D01*
G01X844069Y1680972D02*
X844143Y1680882D01*
G01X844016Y1681074D02*
X844069Y1680972D01*
G01X843983Y1681185D02*
X844016Y1681074D01*
G01X843972Y1681299D02*
X843983Y1681185D01*
G01X829539Y1671181D02*
X829478Y1671294D01*
G01X829579Y1671048D02*
X829539Y1671181D01*
G01X829593Y1670900D02*
X829579Y1671048D01*
G01X836626Y1671181D02*
X836564Y1671294D01*
G01X836665Y1671048D02*
X836626Y1671181D01*
G01X836680Y1670900D02*
X836665Y1671048D01*
G01X843713Y1671181D02*
X843651Y1671294D01*
G01X843752Y1671048D02*
X843713Y1671181D01*
G01X843766Y1670900D02*
X843752Y1671048D01*
G01X827044Y1681686D02*
X827041Y1681890D01*
G01X827054Y1681485D02*
X827044Y1681686D01*
G01X827069Y1681299D02*
X827054Y1681485D01*
G01X841218Y1681686D02*
X841215Y1681890D01*
G01X841227Y1681485D02*
X841218Y1681686D01*
G01X841243Y1681299D02*
X841227Y1681485D01*
G01X827531Y1681685D02*
X827528Y1681890D01*
G01X827540Y1681486D02*
X827531Y1681685D01*
G01X827556Y1681299D02*
X827540Y1681486D01*
G01X841704Y1681685D02*
X841701Y1681890D01*
G01X841713Y1681486D02*
X841704Y1681685D01*
G01X841729Y1681299D02*
X841713Y1681486D01*
G01X844116Y1680758D02*
X844297Y1680709D01*
G01X843976Y1680889D02*
X844116Y1680758D01*
G01X843892Y1681078D02*
X843976Y1680889D01*
G01X843878Y1681299D02*
X843892Y1681078D01*
G01X829345Y1672795D02*
X829199Y1672835D01*
G01X829473Y1672678D02*
X829345Y1672795D01*
G01X829560Y1672500D02*
X829473Y1672678D01*
G01X829593Y1672278D02*
X829560Y1672500D01*
G01X836432Y1672795D02*
X836286Y1672835D01*
G01X836560Y1672678D02*
X836432Y1672795D01*
G01X836647Y1672500D02*
X836560Y1672678D01*
G01X836680Y1672278D02*
X836647Y1672500D01*
G01X843519Y1672795D02*
X843372Y1672835D01*
G01X843646Y1672678D02*
X843519Y1672795D01*
G01X843733Y1672500D02*
X843646Y1672678D01*
G01X843766Y1672278D02*
X843733Y1672500D01*
G01X826239Y1681526D02*
X826233Y1681890D01*
G01X826253Y1681197D02*
X826239Y1681526D01*
G01X826276Y1680935D02*
X826253Y1681197D01*
G01X826305Y1680767D02*
X826276Y1680935D01*
G01X826337Y1680709D02*
X826305Y1680767D01*
G01X840412Y1681526D02*
X840407Y1681890D01*
G01X840426Y1681197D02*
X840412Y1681526D01*
G01X840450Y1680935D02*
X840426Y1681197D01*
G01X840478Y1680767D02*
X840450Y1680935D01*
G01X840511Y1680709D02*
X840478Y1680767D01*
G01X829304Y1671488D02*
X829199Y1671572D01*
G01X829398Y1671394D02*
X829304Y1671488D01*
G01X829478Y1671294D02*
X829398Y1671394D01*
G01X836390Y1671488D02*
X836286Y1671572D01*
G01X836484Y1671394D02*
X836390Y1671488D01*
G01X836564Y1671294D02*
X836484Y1671394D01*
G01X843477Y1671488D02*
X843372Y1671572D01*
G01X843571Y1671394D02*
X843477Y1671488D01*
G01X843651Y1671294D02*
X843571Y1671394D01*
G01X826009Y1670767D02*
X826073Y1670724D01*
G01X825967Y1670829D02*
X826009Y1670767D01*
G01X833095D02*
X833159Y1670724D01*
G01X833053Y1670829D02*
X833095Y1670767D01*
G01X840182D02*
X840246Y1670724D01*
G01X840140Y1670829D02*
X840182Y1670767D01*
G01X827364Y1681670D02*
X827357Y1681890D01*
G01X827387Y1681475D02*
X827364Y1681670D01*
G01X827421Y1681344D02*
X827387Y1681475D01*
G01X827461Y1681299D02*
X827421Y1681344D01*
G01X841537Y1681670D02*
X841530Y1681890D01*
G01X841560Y1681475D02*
X841537Y1681670D01*
G01X841594Y1681344D02*
X841560Y1681475D01*
G01X841634Y1681299D02*
X841594Y1681344D01*
G01X830893Y1711006D02*
X831026Y1710783D01*
G01X830770Y1711202D02*
X830893Y1711006D01*
G01X830660Y1711370D02*
X830770Y1711202D01*
G01X830563Y1711506D02*
X830660Y1711370D01*
G01X830488Y1711597D02*
X830563Y1711506D01*
G01X830445Y1711628D02*
X830488Y1711597D01*
G01X845067Y1711006D02*
X845200Y1710783D01*
G01X844944Y1711202D02*
X845067Y1711006D01*
G01X844833Y1711370D02*
X844944Y1711202D01*
G01X844737Y1711506D02*
X844833Y1711370D01*
G01X844661Y1711597D02*
X844737Y1711506D01*
G01X844618Y1711628D02*
X844661Y1711597D01*
G01X830352Y1711582D02*
X830485Y1711359D01*
G01X830229Y1711778D02*
X830352Y1711582D01*
G01X844525D02*
X844658Y1711359D01*
G01X844402Y1711778D02*
X844525Y1711582D01*
G01X840040Y1672427D02*
X840026Y1672278D01*
G01X840078Y1672554D02*
X840040Y1672427D01*
G01X840131Y1672657D02*
X840078Y1672554D01*
G01X840196Y1672737D02*
X840131Y1672657D01*
G01X840269Y1672792D02*
X840196Y1672737D01*
G01X840344Y1672824D02*
X840269Y1672792D01*
G01X840420Y1672835D02*
X840344Y1672824D01*
G01X832954Y1672427D02*
X832939Y1672278D01*
G01X832991Y1672554D02*
X832954Y1672427D01*
G01X833045Y1672657D02*
X832991Y1672554D01*
G01X833110Y1672737D02*
X833045Y1672657D01*
G01X833182Y1672792D02*
X833110Y1672737D01*
G01X833257Y1672824D02*
X833182Y1672792D01*
G01X833333Y1672835D02*
X833257Y1672824D01*
G01X825867Y1672427D02*
X825853Y1672278D01*
G01X825904Y1672554D02*
X825867Y1672427D01*
G01X825958Y1672657D02*
X825904Y1672554D01*
G01X826023Y1672737D02*
X825958Y1672657D01*
G01X826095Y1672792D02*
X826023Y1672737D01*
G01X826171Y1672824D02*
X826095Y1672792D01*
G01X826246Y1672835D02*
X826171Y1672824D01*
G01X841623Y1681183D02*
X841634Y1681299D01*
G01X841589Y1681072D02*
X841623Y1681183D01*
G01X841536Y1680971D02*
X841589Y1681072D01*
G01X841464Y1680882D02*
X841536Y1680971D01*
G01X841374Y1680807D02*
X841464Y1680882D01*
G01X841274Y1680754D02*
X841374Y1680807D01*
G01X841165Y1680720D02*
X841274Y1680754D01*
G01X841052Y1680709D02*
X841165Y1680720D01*
G01X827450Y1681183D02*
X827461Y1681299D01*
G01X827416Y1681072D02*
X827450Y1681183D01*
G01X827363Y1680971D02*
X827416Y1681072D01*
G01X827291Y1680882D02*
X827363Y1680971D01*
G01X827201Y1680807D02*
X827291Y1680882D01*
G01X827101Y1680754D02*
X827201Y1680807D01*
G01X826992Y1680720D02*
X827101Y1680754D01*
G01X826879Y1680709D02*
X826992Y1680720D01*
G01X830352Y1681183D02*
X830341Y1681299D01*
G01X830385Y1681072D02*
X830352Y1681183D01*
G01X830439Y1680971D02*
X830385Y1681072D01*
G01X830511Y1680882D02*
X830439Y1680971D01*
G01X830600Y1680807D02*
X830511Y1680882D01*
G01X830701Y1680754D02*
X830600Y1680807D01*
G01X830809Y1680720D02*
X830701Y1680754D01*
G01X830922Y1680709D02*
X830809Y1680720D01*
G01X844526Y1681183D02*
X844514Y1681299D01*
G01X844559Y1681072D02*
X844526Y1681183D01*
G01X844612Y1680971D02*
X844559Y1681072D01*
G01X844684Y1680882D02*
X844612Y1680971D01*
G01X844774Y1680807D02*
X844684Y1680882D01*
G01X844874Y1680754D02*
X844774Y1680807D01*
G01X844983Y1680720D02*
X844874Y1680754D01*
G01X845096Y1680709D02*
X844983Y1680720D01*
G01X829579Y1672427D02*
X829593Y1672278D01*
G01X829541Y1672554D02*
X829579Y1672427D01*
G01X829487Y1672657D02*
X829541Y1672554D01*
G01X829422Y1672737D02*
X829487Y1672657D01*
G01X829351Y1672792D02*
X829422Y1672737D01*
G01X829275Y1672824D02*
X829351Y1672792D01*
G01X829199Y1672835D02*
X829275Y1672824D01*
G01X836665Y1672427D02*
X836680Y1672278D01*
G01X836628Y1672554D02*
X836665Y1672427D01*
G01X836574Y1672657D02*
X836628Y1672554D01*
G01X836509Y1672737D02*
X836574Y1672657D01*
G01X836437Y1672792D02*
X836509Y1672737D01*
G01X836361Y1672824D02*
X836437Y1672792D01*
G01X836286Y1672835D02*
X836361Y1672824D01*
G01X843752Y1672427D02*
X843766Y1672278D01*
G01X843715Y1672554D02*
X843752Y1672427D01*
G01X843661Y1672657D02*
X843715Y1672554D01*
G01X843596Y1672737D02*
X843661Y1672657D01*
G01X843524Y1672792D02*
X843596Y1672737D01*
G01X843448Y1672824D02*
X843524Y1672792D01*
G01X843372Y1672835D02*
X843448Y1672824D01*
G01X826072Y1670724D02*
X826009Y1670767D01*
G01X826148Y1670709D02*
X826072Y1670724D01*
G01X833159D02*
X833095Y1670767D01*
G01X833235Y1670709D02*
X833159Y1670724D01*
G01X840246D02*
X840182Y1670767D01*
G01X840321Y1670709D02*
X840246Y1670724D01*
G01X830205Y1681078D02*
X830191Y1681299D01*
G01X830289Y1680889D02*
X830205Y1681078D01*
G01X830429Y1680758D02*
X830289Y1680889D01*
G01X830610Y1680709D02*
X830429Y1680758D01*
G01X844378Y1681078D02*
X844364Y1681299D01*
G01X844463Y1680889D02*
X844378Y1681078D01*
G01X844602Y1680758D02*
X844463Y1680889D01*
G01X844783Y1680709D02*
X844602Y1680758D01*
G01X836187Y1672441D02*
G03X834809Y1673819I-1378J0D01*
G01Y1667913D02*
G03X836187Y1669291I0J1378D01*
G01X841896Y1673819D02*
G03X840518Y1672441I0J-1378D01*
G01Y1669291D02*
G03X841896Y1667913I1378J0D01*
G01X827723Y1673819D02*
G03X826345Y1672441I0J-1378D01*
G01Y1669291D02*
G03X827723Y1667913I1378J0D01*
G01X829558Y1707244D02*
X827702D01*
G01X843731D02*
X841875D01*
G01X841552Y1706457D02*
X844054D01*
G01X827379D02*
X829881D01*
G01X827671Y1705906D02*
X826254D01*
G01X834757D02*
X833340D01*
G01X841076Y1705880D02*
X841215D01*
G01X830219D02*
X830357D01*
G01X826902D02*
X827041D01*
G01X844531D02*
X844392D01*
G01X827671Y1701181D02*
X826254D01*
G01X834757D02*
X833340D01*
G01X836911Y1688780D02*
X832974D01*
G01X838033Y1688583D02*
X839660D01*
G01X823195D02*
X825487D01*
G01Y1688249D02*
X823195D01*
G01X839660D02*
X838033D01*
G01X832974Y1688234D02*
X836911D01*
G01X838033Y1687851D02*
X839660D01*
G01X823195D02*
X825487D01*
G01X836911Y1687791D02*
X832974D01*
G01X823195Y1681890D02*
X880282D01*
G01X843878Y1681299D02*
X843972D01*
G01X841634D02*
X841729D01*
G01X829704D02*
X829799D01*
G01X827461D02*
X827556D01*
G01X830341D02*
X830191D01*
G01X827069D02*
X826919D01*
G01X844514D02*
X844364D01*
G01X841243D02*
X841093D01*
G01X838033Y1681197D02*
X839660D01*
G01X823195D02*
X825487D01*
G01X836911D02*
X832974D01*
G01X823195Y1680709D02*
X880282D01*
G01X833340Y1676280D02*
X834757D01*
G01Y1676181D02*
X833340D01*
G01X824770Y1675984D02*
X819258D01*
G01X835053D02*
X833045D01*
G01X824770Y1674803D02*
X824147D01*
G01X834809Y1673819D02*
X827723D01*
G01X848983D02*
X841896D01*
G01X829199Y1672835D02*
X826246D01*
G01X836286D02*
X833333D01*
G01X843372D02*
X840420D01*
G01X829494Y1672008D02*
X825951D01*
G01X836581D02*
X833038D01*
G01X843668D02*
X840124D01*
G01X829199Y1671572D02*
X826246D01*
G01X836286D02*
X833333D01*
G01X843372D02*
X840420D01*
G01X829478Y1671294D02*
X825968D01*
G01X836564D02*
X833055D01*
G01X843651D02*
X840141D01*
G01X829298Y1670709D02*
X826148D01*
G01X836384D02*
X833235D01*
G01X843471D02*
X840321D01*
G01X834809Y1667913D02*
X827723D01*
G01X848983D02*
X841896D01*
G01X829002Y1665551D02*
X826443D01*
G01X836089D02*
X833530D01*
G01X843176D02*
X840617D01*
G01X828904Y1665354D02*
X826542D01*
G01X835991D02*
X833628D01*
G01X843077D02*
X840715D01*
G01X835053Y1675984D02*
X834757Y1676280D01*
G01Y1676181D02*
X834954Y1675984D01*
G01X843571Y1671394D02*
X843651Y1671294D01*
G01X836484Y1671394D02*
X836564Y1671294D01*
G01X829398Y1671394D02*
X829478Y1671294D01*
G01X844531Y1711628D02*
X843870Y1712992D01*
G01X843672Y1707244D02*
X844054Y1706457D01*
G01X830357Y1711628D02*
X829697Y1712992D01*
G01X843905D02*
X845200Y1710783D01*
G01X844658Y1711359D02*
X843701Y1712992D01*
G01X844531Y1705880D02*
X843731Y1707244D01*
G01X844392Y1705880D02*
X844054Y1706457D01*
G01X829731Y1712992D02*
X831026Y1710783D01*
G01X830485Y1711359D02*
X829528Y1712992D01*
G01X830357Y1705880D02*
X829558Y1707244D01*
G01X830219Y1705880D02*
X829881Y1706457D01*
G01X829499Y1707244D02*
X829881Y1706457D01*
G01X840124Y1670906D02*
X840140Y1670829D01*
G01X833038Y1670906D02*
X833053Y1670829D01*
G01X825951Y1670906D02*
X825967Y1670829D01*
G01X845200Y1681890D02*
Y1710783D01*
G01X844658Y1711359D02*
Y1681890D01*
G01X844618Y1711628D02*
Y1681890D01*
G01X844531Y1711628D02*
Y1705880D01*
G01X844392D02*
Y1681890D01*
G01X844076D02*
Y1712205D01*
G01X843906D02*
Y1681890D01*
G01X843372Y1672835D02*
Y1671572D01*
G01X841701Y1681890D02*
Y1712205D01*
G01X841530D02*
Y1681890D01*
G01X841215Y1705880D02*
Y1681890D01*
G01X841076Y1705880D02*
Y1711628D01*
G01X840988Y1681890D02*
Y1711628D01*
G01X840948Y1681890D02*
Y1711359D01*
G01X840518Y1672441D02*
Y1669291D01*
G01X840420Y1672835D02*
Y1671572D01*
G01X840407Y1710783D02*
Y1681890D01*
G01X839660Y1688583D02*
Y1680709D01*
G01X838033Y1688583D02*
Y1680709D01*
G01X836911Y1688780D02*
Y1680709D01*
G01X836286Y1672835D02*
Y1671572D01*
G01X836187Y1672441D02*
Y1669291D01*
G01X834757Y1705906D02*
Y1680709D01*
G01X833340D02*
Y1705906D01*
G01X833333Y1672835D02*
Y1671572D01*
G01X832974Y1688780D02*
Y1680709D01*
G01X831026Y1681890D02*
Y1710783D01*
G01X830485Y1711359D02*
Y1681890D01*
G01X830445Y1711628D02*
Y1681890D01*
G01X830357Y1711628D02*
Y1705880D01*
G01X830219Y1681890D02*
Y1705880D01*
G01X829903Y1681890D02*
Y1712205D01*
G01X829732D02*
Y1681890D01*
G01X829199Y1672835D02*
Y1671572D01*
G01X827671Y1705906D02*
Y1680709D01*
G01X827528Y1681890D02*
Y1712205D01*
G01X827357D02*
Y1681890D01*
G01X827041Y1705880D02*
Y1681890D01*
G01X826902Y1705880D02*
Y1711628D01*
G01X826815Y1681890D02*
Y1711628D01*
G01X826775Y1681890D02*
Y1711359D01*
G01X826345Y1672441D02*
Y1669291D01*
G01X826254Y1705906D02*
Y1680709D01*
G01X826246Y1672835D02*
Y1671572D01*
G01X826233Y1710783D02*
Y1681890D01*
G01X825487Y1688583D02*
Y1680709D01*
G01X823195Y1714413D02*
Y1680709D01*
G01X819258Y1675984D02*
Y1718504D01*
G01X843652Y1670829D02*
X843668Y1670906D01*
G01X836566Y1670829D02*
X836581Y1670906D01*
G01X829479Y1670829D02*
X829494Y1670906D01*
G01X841552Y1706457D02*
X841934Y1707244D01*
G01X841076Y1711628D02*
X841737Y1712992D01*
G01X841552Y1706457D02*
X841215Y1705880D01*
G01X841875Y1707244D02*
X841076Y1705880D01*
G01X841906Y1712992D02*
X840948Y1711359D01*
G01X840407Y1710783D02*
X841702Y1712992D01*
G01X827379Y1706457D02*
X827041Y1705880D01*
G01X827702Y1707244D02*
X826902Y1705880D01*
G01X827732Y1712992D02*
X826775Y1711359D01*
G01X826233Y1710783D02*
X827528Y1712992D01*
G01X827379Y1706457D02*
X827761Y1707244D01*
G01X826902Y1711628D02*
X827563Y1712992D01*
G01X833143Y1675984D02*
X833340Y1676181D01*
G01Y1676280D02*
X833045Y1675984D01*
G01X843546Y1670724D02*
X843611Y1670767D01*
G01X836460Y1670724D02*
X836524Y1670767D01*
G01X829373Y1670724D02*
X829437Y1670767D01*
G01X827142Y1711947D02*
X827031Y1711778D01*
G01X827238Y1712082D02*
X827142Y1711947D01*
G01X827313Y1712173D02*
X827238Y1712082D01*
G01X827357Y1712205D02*
X827313Y1712173D01*
G01X841315Y1711947D02*
X841204Y1711778D01*
G01X841411Y1712082D02*
X841315Y1711947D01*
G01X841487Y1712173D02*
X841411Y1712082D01*
G01X841530Y1712205D02*
X841487Y1712173D01*
G01X830118Y1711946D02*
X830229Y1711778D01*
G01X830022Y1712082D02*
X830118Y1711946D01*
G01X829946Y1712173D02*
X830022Y1712082D01*
G01X829903Y1712205D02*
X829946Y1712173D01*
G01X844291Y1711946D02*
X844402Y1711778D01*
G01X844195Y1712082D02*
X844291Y1711946D01*
G01X844120Y1712173D02*
X844195Y1712082D01*
G01X844076Y1712205D02*
X844120Y1712173D01*
G01X880282Y1718504D02*
X819258D01*
G01X880282Y1714413D02*
X823195D01*
G01X829731Y1712992D02*
X827528D01*
G01X843905D02*
X841702D01*
G01X841530Y1712205D02*
X844076D01*
G01X827357D02*
X829903D01*
G01X840988Y1711628D02*
X844618D01*
G01X826815D02*
X830445D01*
G01X843906Y1712205D02*
X843524Y1712992D01*
G01X829732Y1712205D02*
X829351Y1712992D01*
G01X820833Y1718504D02*
X823195Y1714413D01*
G01X842082Y1712992D02*
X841701Y1712205D01*
G01X827909Y1712992D02*
X827528Y1712205D01*
G01X854331Y-152756D02*
G03X858268Y-148819I0J3937D01*
G01X866142Y-129134D02*
G03X858268I-3937J0D01*
G01Y-148819D02*
Y-129134D01*
G01X870079Y-152756D02*
X1177165D01*
G01X866142Y-148819D02*
G03X870079Y-152756I3937J0D01*
G01X866142Y-11811D02*
Y-148819D01*
G01X854331Y-152756D02*
G03X858268Y-148819I0J3937D01*
G01X866142Y-129134D02*
G03X858268I-3937J0D01*
G01Y-148819D02*
Y-129134D01*
G01X866142Y-148819D02*
G03X870079Y-152756I3937J0D01*
G01X866142Y-148819D02*
Y-11811D01*
G01X1177165Y-152756D02*
X870079D01*
G01X858268Y-98425D02*
G03X866142I3937J0D01*
G01X858268D02*
Y-15748D01*
G01Y-98425D02*
Y-15748D01*
G01Y-98425D02*
G03X866142I3937J0D01*
G01Y-11811D02*
G03X862205Y-7874I-3937J0D01*
G01X886076Y8655D02*
G03X886863Y9443I0J787D01*
G01Y9639D02*
G03X886076Y10427I-787J1D01*
G01X885682Y12002D02*
G03Y10427I0J-788D01*
G01X886076Y12002D02*
G03X886863Y12789I0J787D01*
G01Y12986D02*
G03X886076Y13773I-787J0D01*
G01X866142Y-11811D02*
G03X862205Y-7874I-3937J0D01*
G01X883320Y8970D02*
X883202Y8852D01*
G01X876161Y8661D02*
X876752Y9252D01*
G01X872224Y8661D02*
X872815Y9252D01*
G01X868287Y8661D02*
X868878Y9252D01*
G01X864350Y8661D02*
X864941Y9252D01*
G01X860413Y8661D02*
X861004Y9252D01*
G01X856476Y8661D02*
X857067Y9252D01*
G01X852539Y8661D02*
X853130Y9252D01*
G01X848602Y8661D02*
X849193Y9252D01*
G01X884252Y11220D02*
X886024Y13751D01*
G01X882067Y8661D02*
X882461Y10236D01*
G01X877454Y12198D02*
X877611Y12986D01*
G01X873517Y12198D02*
X873674Y12986D01*
G01X869580Y12198D02*
X869737Y12986D01*
G01X865643Y12198D02*
X865800Y12986D01*
G01X861706Y12198D02*
X861863Y12986D01*
G01X857769Y12198D02*
X857926Y12986D01*
G01X853831Y12198D02*
X853989Y12986D01*
G01X849894Y12198D02*
X850052Y12986D01*
G01X877454Y12041D02*
X877611Y12848D01*
G01X873517Y12041D02*
X873674Y12848D01*
G01X869580Y12041D02*
X869737Y12848D01*
G01X865643Y12041D02*
X865800Y12848D01*
G01X861706Y12041D02*
X861863Y12848D01*
G01X857769Y12041D02*
X857926Y12848D01*
G01X853831Y12041D02*
X853989Y12848D01*
G01X849894Y12041D02*
X850052Y12848D01*
G01X886863Y12789D02*
Y12986D01*
G01Y9639D02*
Y9443D01*
G01X886024Y13751D02*
Y15669D01*
G01X884252Y8661D02*
Y22835D01*
G01X883320Y13780D02*
Y8655D01*
G01X883287Y10236D02*
Y15709D01*
G01X883268Y20472D02*
Y9055D01*
G01X882532Y15709D02*
Y8655D01*
G01X882461Y10236D02*
Y15709D01*
G01X881496Y20472D02*
Y9055D01*
G01X881024Y13780D02*
Y8661D01*
G01X879528Y20472D02*
Y8661D01*
G01X879134Y25197D02*
Y8661D01*
G01X877611Y10999D02*
Y20472D01*
G01Y4915D02*
Y9220D01*
G01X877579Y22047D02*
Y9252D01*
G01X877559Y8660D02*
Y20472D01*
G01X876824Y22047D02*
Y4915D01*
G01X876752Y9252D02*
Y22047D01*
G01X873674Y10999D02*
Y20472D01*
G01Y4915D02*
Y9220D01*
G01X873642Y22047D02*
Y9252D01*
G01X872887Y22047D02*
Y4915D01*
G01X872835Y20472D02*
Y8660D01*
G01X872815Y22047D02*
Y9252D01*
G01X869737Y10999D02*
Y20472D01*
G01Y4915D02*
Y9220D01*
G01X869705Y22047D02*
Y9252D01*
G01X868950Y22047D02*
Y4915D01*
G01X868878Y22047D02*
Y9252D01*
G01X865800Y10999D02*
Y20472D01*
G01Y4915D02*
Y9220D01*
G01X865768Y22047D02*
Y9252D01*
G01X865013Y22047D02*
Y4915D01*
G01X864941Y22047D02*
Y9252D01*
G01X861863Y10999D02*
Y20472D01*
G01Y4915D02*
Y9220D01*
G01X861831Y22047D02*
Y9252D01*
G01X861076Y22047D02*
Y4915D01*
G01X861004Y22047D02*
Y9252D01*
G01X857926Y10999D02*
Y20472D01*
G01Y4915D02*
Y9220D01*
G01X857894Y22047D02*
Y9252D01*
G01X857139Y22047D02*
Y4915D01*
G01X857067Y22047D02*
Y9252D01*
G01X853989Y10999D02*
Y20472D01*
G01Y4915D02*
Y9220D01*
G01X853957Y22047D02*
Y9252D01*
G01X853202Y22047D02*
Y4915D01*
G01X853130Y22047D02*
Y9252D01*
G01X850052Y10999D02*
Y20472D01*
G01Y4915D02*
Y9220D01*
G01X850020Y22047D02*
Y9252D01*
G01X849265Y22047D02*
Y4915D01*
G01X849193Y22047D02*
Y9252D01*
G01X876824Y12848D02*
X876981Y12041D01*
G01X872887Y12848D02*
X873044Y12041D01*
G01X868950Y12848D02*
X869107Y12041D01*
G01X865013Y12848D02*
X865170Y12041D01*
G01X861076Y12848D02*
X861233Y12041D01*
G01X857139Y12848D02*
X857296Y12041D01*
G01X876824Y12986D02*
X876981Y12198D01*
G01X872887Y12986D02*
X873044Y12198D01*
G01X868950Y12986D02*
X869107Y12198D01*
G01X865013Y12986D02*
X865170Y12198D01*
G01X861076Y12986D02*
X861233Y12198D01*
G01X853202Y12848D02*
X853359Y12041D01*
G01X849265Y12848D02*
X849422Y12041D01*
G01X857139Y12986D02*
X857296Y12198D01*
G01X853202Y12986D02*
X853359Y12198D01*
G01X849265Y12986D02*
X849422Y12198D01*
G01X883681Y8661D02*
X883287Y10237D01*
G01X883268Y9055D02*
X883661Y8661D01*
G01X882650Y8852D02*
X882532Y8970D01*
G01X881496Y9055D02*
X881890Y8661D01*
G01X877579Y9252D02*
X878169Y8661D01*
G01X873642Y9252D02*
X874232Y8661D01*
G01X869705Y9252D02*
X870295Y8661D01*
G01X865768Y9252D02*
X866358Y8661D01*
G01X861831Y9252D02*
X862421Y8661D01*
G01X857894Y9252D02*
X858484Y8661D01*
G01X853957Y9252D02*
X854547Y8661D01*
G01X850020Y9252D02*
X850610Y8661D01*
G01X886076Y13773D02*
X884252Y13778D01*
G01X883320Y13780D02*
X884252Y13778D01*
G01X876752Y16520D02*
X877579D01*
G01X872815D02*
X873642D01*
G01X868878D02*
X869705D01*
G01X864941D02*
X865768D01*
G01X861004D02*
X861831D01*
G01X857067D02*
X857894D01*
G01X853130D02*
X853957D01*
G01X849193D02*
X850020D01*
G01X850052Y16093D02*
X849265D01*
G01X853989D02*
X853202D01*
G01X857926D02*
X857139D01*
G01X861863D02*
X861076D01*
G01X865800D02*
X865013D01*
G01X869737D02*
X868950D01*
G01X877611D02*
X876824D01*
G01X873674D02*
X872887D01*
G01X853989Y16065D02*
X853957D01*
G01X850052D02*
X850020D01*
G01X857926D02*
X857894D01*
G01X861863D02*
X861831D01*
G01X865800D02*
X865768D01*
G01X869737D02*
X869705D01*
G01X873674D02*
X873642D01*
G01X877611D02*
X877579D01*
G01X850020Y16056D02*
X849265D01*
G01X853957D02*
X853202D01*
G01X857894D02*
X857139D01*
G01X861831D02*
X861076D01*
G01X865768D02*
X865013D01*
G01X869705D02*
X868950D01*
G01X877579D02*
X876824D01*
G01X873642D02*
X872887D01*
G01X876824Y15896D02*
X877611D01*
G01X872887D02*
X873674D01*
G01X868950D02*
X869737D01*
G01X865013D02*
X865800D01*
G01X861076D02*
X861863D01*
G01X857139D02*
X857926D01*
G01X853202D02*
X853989D01*
G01X849265D02*
X850052D01*
G01X883287Y15709D02*
X882461D01*
G01X886024Y15669D02*
X884252D01*
G01X876824Y15489D02*
X877579D01*
G01X872887D02*
X873642D01*
G01X868950D02*
X869705D01*
G01X865013D02*
X865768D01*
G01X861076D02*
X861831D01*
G01X857139D02*
X857894D01*
G01X853202D02*
X853957D01*
G01X849265D02*
X850020D01*
G01Y15411D02*
X849265D01*
G01X853957D02*
X853202D01*
G01X857894D02*
X857139D01*
G01X861831D02*
X861076D01*
G01X865768D02*
X865013D01*
G01X869705D02*
X868950D01*
G01X877579D02*
X876824D01*
G01X873642D02*
X872887D01*
G01X850020Y15329D02*
X849265D01*
G01X853957D02*
X853202D01*
G01X857894D02*
X857139D01*
G01X861831D02*
X861076D01*
G01X865768D02*
X865013D01*
G01X869705D02*
X868950D01*
G01X877579D02*
X876824D01*
G01X873642D02*
X872887D01*
G01X850020Y15311D02*
X849265D01*
G01X853957D02*
X853202D01*
G01X857894D02*
X857139D01*
G01X861831D02*
X861076D01*
G01X865768D02*
X865013D01*
G01X869705D02*
X868950D01*
G01X877579D02*
X876824D01*
G01X873642D02*
X872887D01*
G01X850020Y15292D02*
X849265D01*
G01X853957D02*
X853202D01*
G01X857894D02*
X857139D01*
G01X861831D02*
X861076D01*
G01X865768D02*
X865013D01*
G01X869705D02*
X868950D01*
G01X877579D02*
X876824D01*
G01X873642D02*
X872887D01*
G01X876752Y15217D02*
X876824D01*
G01X868878D02*
X868950D01*
G01X864941D02*
X865013D01*
G01X861004D02*
X861076D01*
G01X857067D02*
X857139D01*
G01X853130D02*
X853202D01*
G01X849193D02*
X849265D01*
G01X872887D02*
X872815D01*
G01X882532Y14610D02*
X883287D01*
G01Y14567D02*
X882461D01*
G01X883287Y14488D02*
X882461D01*
G01X883287Y14094D02*
X882461D01*
G01Y13780D02*
X881024D01*
G01X884252D02*
X883320D01*
G01X882532Y13773D02*
X886076D01*
G01X850052Y13183D02*
X849265D01*
G01X853989D02*
X853202D01*
G01X857926D02*
X857139D01*
G01X861863D02*
X861076D01*
G01X865800D02*
X865013D01*
G01X869737D02*
X868950D01*
G01X877611D02*
X876824D01*
G01X873674D02*
X872887D01*
G01X850052Y12848D02*
X849265D01*
G01X853989D02*
X853202D01*
G01X857926D02*
X857139D01*
G01X861863D02*
X861076D01*
G01X865800D02*
X865013D01*
G01X869737D02*
X868950D01*
G01X877611D02*
X876824D01*
G01X873674D02*
X872887D01*
G01X853831Y12198D02*
X853359D01*
G01X849894D02*
X849422D01*
G01X857769D02*
X857296D01*
G01X861706D02*
X861233D01*
G01X865643D02*
X865170D01*
G01X869580D02*
X869107D01*
G01X877454D02*
X876981D01*
G01X873517D02*
X873044D01*
G01X876824Y12161D02*
X877579D01*
G01X872887D02*
X873642D01*
G01X868950D02*
X869705D01*
G01X865013D02*
X865768D01*
G01X861076D02*
X861831D01*
G01X857139D02*
X857894D01*
G01X853202D02*
X853957D01*
G01X849265D02*
X850020D01*
G01X876981Y12041D02*
X877454D01*
G01X873044D02*
X873517D01*
G01X869107D02*
X869580D01*
G01X865170D02*
X865643D01*
G01X861233D02*
X861706D01*
G01X857296D02*
X857769D01*
G01X853359D02*
X853831D01*
G01X849422D02*
X849894D01*
G01X886076Y12002D02*
X885682D01*
G01X850020Y11939D02*
X849265D01*
G01X853957D02*
X853202D01*
G01X857894D02*
X857139D01*
G01X861831D02*
X861076D01*
G01X865768D02*
X865013D01*
G01X869705D02*
X868950D01*
G01X877579D02*
X876824D01*
G01X873642D02*
X872887D01*
G01X850052Y11512D02*
X849265D01*
G01X853989D02*
X853202D01*
G01X857926D02*
X857139D01*
G01X861863D02*
X861076D01*
G01X865800D02*
X865013D01*
G01X869737D02*
X868950D01*
G01X877611D02*
X876824D01*
G01X873674D02*
X872887D01*
G01X883287Y11313D02*
X882532D01*
G01X883287Y11181D02*
X882461D01*
G01X853989Y10999D02*
X853957D01*
G01X850052D02*
X850020D01*
G01X857926D02*
X857894D01*
G01X861863D02*
X861831D01*
G01X865800D02*
X865768D01*
G01X869737D02*
X869705D01*
G01X873674D02*
X873642D01*
G01X877611D02*
X877579D01*
G01X876824Y10950D02*
X877579D01*
G01X872887D02*
X873642D01*
G01X868950D02*
X869705D01*
G01X865013D02*
X865768D01*
G01X861076D02*
X861831D01*
G01X857139D02*
X857894D01*
G01X853202D02*
X853957D01*
G01X849265D02*
X850020D01*
G01X886076Y10427D02*
X885682D01*
G01X882461Y10354D02*
X883287D01*
G01X882532Y10338D02*
X883287D01*
G01Y10237D02*
X882461D01*
G01X850020Y10137D02*
X849265D01*
G01X853957D02*
X853202D01*
G01X857894D02*
X857139D01*
G01X861831D02*
X861076D01*
G01X865768D02*
X865013D01*
G01X869705D02*
X868950D01*
G01X877579D02*
X876824D01*
G01X873642D02*
X872887D01*
G01X872835Y9646D02*
X877559D01*
G01Y9055D02*
X883268D01*
G01X882532Y9049D02*
X883320D01*
G01X877559Y8939D02*
X872835D01*
G01X883320Y8891D02*
X882532D01*
G01X883202Y8852D02*
X882650D01*
G01X882532Y8655D02*
X886076D01*
G01X850052Y8443D02*
X849265D01*
G01X853989D02*
X853202D01*
G01X857926D02*
X857139D01*
G01X861863D02*
X861076D01*
G01X865800D02*
X865013D01*
G01X869737D02*
X868950D01*
G01X877611D02*
X876824D01*
G01X873674D02*
X872887D01*
G01X876824Y8193D02*
X877611D01*
G01X872887D02*
X873674D01*
G01X868950D02*
X869737D01*
G01X865013D02*
X865800D01*
G01X861076D02*
X861863D01*
G01X857139D02*
X857926D01*
G01X853202D02*
X853989D01*
G01X849265D02*
X850052D01*
G01Y7426D02*
X849265D01*
G01X853989D02*
X853202D01*
G01X857926D02*
X857139D01*
G01X861863D02*
X861076D01*
G01X865800D02*
X865013D01*
G01X869737D02*
X868950D01*
G01X877611D02*
X876824D01*
G01X873674D02*
X872887D01*
G01X876824Y7205D02*
X877611D01*
G01X872887D02*
X873674D01*
G01X868950D02*
X869737D01*
G01X865013D02*
X865800D01*
G01X861076D02*
X861863D01*
G01X857139D02*
X857926D01*
G01X853202D02*
X853989D01*
G01X849265D02*
X850052D01*
G01Y5112D02*
X849265D01*
G01X853989D02*
X853202D01*
G01X857926D02*
X857139D01*
G01X861863D02*
X861076D01*
G01X865800D02*
X865013D01*
G01X869737D02*
X868950D01*
G01X877611D02*
X876824D01*
G01X873674D02*
X872887D01*
G01X850052Y4915D02*
X849265D01*
G01X853989D02*
X853202D01*
G01X857926D02*
X857139D01*
G01X861863D02*
X861076D01*
G01X865800D02*
X865013D01*
G01X869737D02*
X868950D01*
G01X877611D02*
X876824D01*
G01X873674D02*
X872887D01*
G01X878169Y26772D02*
X877579Y26181D01*
G01X874232Y26772D02*
X873642Y26181D01*
G01X870295Y26772D02*
X869705Y26181D01*
G01X866358Y26772D02*
X865768Y26181D01*
G01X862421Y26772D02*
X861831Y26181D01*
G01X858484Y26772D02*
X857894Y26181D01*
G01X854547Y26772D02*
X853957Y26181D01*
G01X850610Y26772D02*
X850020Y26181D01*
G01X877611Y26214D02*
Y30899D01*
G01X877579Y26181D02*
Y24409D01*
G01X876824Y30899D02*
Y24409D01*
G01X876752Y26181D02*
Y24409D01*
G01X873674Y26214D02*
Y30899D01*
G01X873642Y26181D02*
Y24409D01*
G01X872887Y30899D02*
Y24409D01*
G01X872815Y26181D02*
Y24409D01*
G01X869737Y26214D02*
Y30899D01*
G01X869705Y26181D02*
Y24409D01*
G01X868950Y30899D02*
Y24409D01*
G01X868878Y26181D02*
Y24409D01*
G01X865800Y26214D02*
Y30899D01*
G01X865768Y26181D02*
Y24409D01*
G01X865013Y30899D02*
Y24409D01*
G01X864941Y26181D02*
Y24409D01*
G01X861863Y26214D02*
Y30899D01*
G01X861831Y26181D02*
Y24409D01*
G01X861076Y30899D02*
Y24409D01*
G01X861004Y26181D02*
Y24409D01*
G01X857926Y26214D02*
Y30899D01*
G01X857894Y26181D02*
Y24409D01*
G01X857139Y30899D02*
Y24409D01*
G01X857067Y26181D02*
Y24409D01*
G01X853989Y26214D02*
Y30899D01*
G01X853957Y26181D02*
Y24409D01*
G01X853202Y30899D02*
Y24409D01*
G01X853130Y26181D02*
Y24409D01*
G01X850052Y26214D02*
Y30899D01*
G01X850020Y26181D02*
Y24409D01*
G01X849265Y30899D02*
Y24409D01*
G01X849193Y26181D02*
Y24409D01*
G01X884252Y22835D02*
X880315Y26772D01*
G01X876752Y26181D02*
X876161Y26772D01*
G01X872815Y26181D02*
X872224Y26772D01*
G01X868878Y26181D02*
X868287Y26772D01*
G01X864941Y26181D02*
X864350Y26772D01*
G01X861004Y26181D02*
X860413Y26772D01*
G01X857067Y26181D02*
X856476Y26772D01*
G01X853130Y26181D02*
X852539Y26772D01*
G01X849193Y26181D02*
X848602Y26772D01*
G01X876824Y25192D02*
X876752Y25197D01*
G01X872887Y25192D02*
X872815Y25197D01*
G01X868950Y25192D02*
X868878Y25197D01*
G01X865013Y25192D02*
X864941Y25197D01*
G01X861076Y25192D02*
X861004Y25197D01*
G01X857139Y25192D02*
X857067Y25197D01*
G01X853202Y25192D02*
X853130Y25197D01*
G01X849265Y25192D02*
X849193Y25197D01*
G01X850052Y30899D02*
X849265D01*
G01X853989D02*
X853202D01*
G01X857926D02*
X857139D01*
G01X861863D02*
X861076D01*
G01X865800D02*
X865013D01*
G01X869737D02*
X868950D01*
G01X877611D02*
X876824D01*
G01X873674D02*
X872887D01*
G01X876824Y30506D02*
X877611D01*
G01X872887D02*
X873674D01*
G01X868950D02*
X869737D01*
G01X865013D02*
X865800D01*
G01X861076D02*
X861863D01*
G01X857139D02*
X857926D01*
G01X853202D02*
X853989D01*
G01X849265D02*
X850052D01*
G01Y28781D02*
X849265D01*
G01X853989D02*
X853202D01*
G01X857926D02*
X857139D01*
G01X861863D02*
X861076D01*
G01X865800D02*
X865013D01*
G01X869737D02*
X868950D01*
G01X877611D02*
X876824D01*
G01X873674D02*
X872887D01*
G01X876824Y28364D02*
X877611D01*
G01X872887D02*
X873674D01*
G01X868950D02*
X869737D01*
G01X865013D02*
X865800D01*
G01X861076D02*
X861863D01*
G01X857139D02*
X857926D01*
G01X853202D02*
X853989D01*
G01X849265D02*
X850052D01*
G01Y27706D02*
X849265D01*
G01X853989D02*
X853202D01*
G01X857926D02*
X857139D01*
G01X861863D02*
X861076D01*
G01X865800D02*
X865013D01*
G01X869737D02*
X868950D01*
G01X877611D02*
X876824D01*
G01X873674D02*
X872887D01*
G01X876824Y27419D02*
X877611D01*
G01X872887D02*
X873674D01*
G01X868950D02*
X869737D01*
G01X865013D02*
X865800D01*
G01X861076D02*
X861863D01*
G01X857139D02*
X857926D01*
G01X853202D02*
X853989D01*
G01X849265D02*
X850052D01*
G01Y26859D02*
X849265D01*
G01X853989D02*
X853202D01*
G01X857926D02*
X857139D01*
G01X861863D02*
X861076D01*
G01X865800D02*
X865013D01*
G01X869737D02*
X868950D01*
G01X877611D02*
X876824D01*
G01X873674D02*
X872887D01*
G01X850052Y26687D02*
X849265D01*
G01X853989D02*
X853202D01*
G01X857926D02*
X857139D01*
G01X861863D02*
X861076D01*
G01X865800D02*
X865013D01*
G01X869737D02*
X868950D01*
G01X877611D02*
X876824D01*
G01X873674D02*
X872887D01*
G01X850052Y26608D02*
X849265D01*
G01X853989D02*
X853202D01*
G01X857926D02*
X857139D01*
G01X861863D02*
X861076D01*
G01X865800D02*
X865013D01*
G01X869737D02*
X868950D01*
G01X877611D02*
X876824D01*
G01X873674D02*
X872887D01*
G01X850052Y26588D02*
X849265D01*
G01X853989D02*
X853202D01*
G01X857926D02*
X857139D01*
G01X861863D02*
X861076D01*
G01X865800D02*
X865013D01*
G01X869737D02*
X868950D01*
G01X877611D02*
X876824D01*
G01X873674D02*
X872887D01*
G01X850052Y26490D02*
X849265D01*
G01X853989D02*
X853202D01*
G01X857926D02*
X857139D01*
G01X861863D02*
X861076D01*
G01X865800D02*
X865013D01*
G01X869737D02*
X868950D01*
G01X877611D02*
X876824D01*
G01X873674D02*
X872887D01*
G01X850020Y26181D02*
X849193D01*
G01X853957D02*
X853130D01*
G01X857894D02*
X857067D01*
G01X861831D02*
X861004D01*
G01X865768D02*
X864941D01*
G01X869705D02*
X868878D01*
G01X873642D02*
X872815D01*
G01X877579D02*
X876752D01*
G01X850020Y25495D02*
X849265D01*
G01X853957D02*
X853202D01*
G01X857894D02*
X857139D01*
G01X861831D02*
X861076D01*
G01X865768D02*
X865013D01*
G01X869705D02*
X868950D01*
G01X877579D02*
X876824D01*
G01X873642D02*
X872887D01*
G01X850020Y25197D02*
X849193D01*
G01X853957D02*
X853130D01*
G01X857894D02*
X857067D01*
G01X861831D02*
X861004D01*
G01X865768D02*
X864941D01*
G01X869705D02*
X868878D01*
G01X873642D02*
X872815D01*
G01X877579D02*
X876752D01*
G01X881890D02*
X879134D01*
G01X850020Y25191D02*
X849265D01*
G01X853957D02*
X853202D01*
G01X857894D02*
X857139D01*
G01X861831D02*
X861076D01*
G01X865768D02*
X865013D01*
G01X869705D02*
X868950D01*
G01X877579D02*
X876824D01*
G01X873642D02*
X872887D01*
G01X850020Y24994D02*
X849265D01*
G01X853957D02*
X853202D01*
G01X857894D02*
X857139D01*
G01X861831D02*
X861076D01*
G01X865768D02*
X865013D01*
G01X869705D02*
X868950D01*
G01X877579D02*
X876824D01*
G01X873642D02*
X872887D01*
G01X850020Y24724D02*
X849193D01*
G01X853957D02*
X853130D01*
G01X857894D02*
X857067D01*
G01X861831D02*
X861004D01*
G01X865768D02*
X864941D01*
G01X869705D02*
X868878D01*
G01X873642D02*
X872815D01*
G01X877579D02*
X876752D01*
G01X850020Y24600D02*
X849265D01*
G01X853957D02*
X853202D01*
G01X857894D02*
X857139D01*
G01X861831D02*
X861076D01*
G01X865768D02*
X865013D01*
G01X869705D02*
X868950D01*
G01X877579D02*
X876824D01*
G01X873642D02*
X872887D01*
G01X850020Y24409D02*
X849193D01*
G01X853957D02*
X853130D01*
G01X857894D02*
X857067D01*
G01X861831D02*
X861004D01*
G01X865768D02*
X864941D01*
G01X869705D02*
X868878D01*
G01X873642D02*
X872815D01*
G01X877579D02*
X876752D01*
G01X850020Y22047D02*
X849193D01*
G01X853957D02*
X853130D01*
G01X857894D02*
X857067D01*
G01X861831D02*
X861004D01*
G01X865768D02*
X864941D01*
G01X869705D02*
X868878D01*
G01X877579D02*
X876752D01*
G01X873642D02*
X872815D01*
G01X850020Y21541D02*
X849265D01*
G01X853957D02*
X853202D01*
G01X857894D02*
X857139D01*
G01X861831D02*
X861076D01*
G01X865768D02*
X865013D01*
G01X869705D02*
X868950D01*
G01X877579D02*
X876824D01*
G01X873642D02*
X872887D01*
G01X876824Y21520D02*
X877579D01*
G01X872887D02*
X873642D01*
G01X868950D02*
X869705D01*
G01X865013D02*
X865768D01*
G01X861076D02*
X861831D01*
G01X857139D02*
X857894D01*
G01X853202D02*
X853957D01*
G01X849265D02*
X850020D01*
G01X876824Y21175D02*
X877579D01*
G01X872887D02*
X873642D01*
G01X868950D02*
X869705D01*
G01X865013D02*
X865768D01*
G01X861076D02*
X861831D01*
G01X857139D02*
X857894D01*
G01X853202D02*
X853957D01*
G01X849265D02*
X850020D01*
G01Y20702D02*
X849265D01*
G01X853957D02*
X853202D01*
G01X857894D02*
X857139D01*
G01X861831D02*
X861076D01*
G01X865768D02*
X865013D01*
G01X869705D02*
X868950D01*
G01X877579D02*
X876824D01*
G01X873642D02*
X872887D01*
G01X850020Y20584D02*
X849265D01*
G01X853957D02*
X853202D01*
G01X857894D02*
X857139D01*
G01X861831D02*
X861076D01*
G01X865768D02*
X865013D01*
G01X869705D02*
X868950D01*
G01X877579D02*
X876824D01*
G01X873642D02*
X872887D01*
G01X850052Y20387D02*
X849265D01*
G01X853989D02*
X853202D01*
G01X857926D02*
X857139D01*
G01X861863D02*
X861076D01*
G01X865800D02*
X865013D01*
G01X869737D02*
X868950D01*
G01X877611D02*
X876824D01*
G01X873674D02*
X872887D01*
G01X850052Y20309D02*
X849265D01*
G01X853989D02*
X853202D01*
G01X857926D02*
X857139D01*
G01X861863D02*
X861076D01*
G01X865800D02*
X865013D01*
G01X869737D02*
X868950D01*
G01X877611D02*
X876824D01*
G01X873674D02*
X872887D01*
G01X876824Y20191D02*
X877611D01*
G01X872887D02*
X873674D01*
G01X868950D02*
X869737D01*
G01X865013D02*
X865800D01*
G01X861076D02*
X861863D01*
G01X857139D02*
X857926D01*
G01X853202D02*
X853989D01*
G01X849265D02*
X850052D01*
G01X847669Y1589446D02*
X847752Y1589382D01*
G01X847618Y1589513D02*
X847669Y1589446D01*
G01X847617Y1589575D02*
X847618Y1589513D01*
G01X847667Y1589622D02*
X847617Y1589575D01*
G01X847749Y1589653D02*
X847667Y1589622D01*
G01X861843Y1589446D02*
X861925Y1589382D01*
G01X861791Y1589513D02*
X861843Y1589446D01*
G01X861790Y1589575D02*
X861791Y1589513D01*
G01X861840Y1589622D02*
X861790Y1589575D01*
G01X861922Y1589653D02*
X861840Y1589622D01*
G01X876016Y1589446D02*
X876098Y1589382D01*
G01X875965Y1589513D02*
X876016Y1589446D01*
G01X875963Y1589575D02*
X875965Y1589513D01*
G01X876013Y1589622D02*
X875963Y1589575D01*
G01X876095Y1589653D02*
X876013Y1589622D01*
G01X882583Y1591322D02*
X882536Y1591001D01*
G01X882731Y1591645D02*
X882583Y1591322D01*
G01X882971Y1591929D02*
X882731Y1591645D01*
G01X889800Y1591617D02*
X890057Y1591929D01*
G01X889652Y1591248D02*
X889800Y1591617D01*
G01X847288Y1591630D02*
X847538Y1591929D01*
G01X847139Y1591275D02*
X847288Y1591630D01*
G01X854375D02*
X854624Y1591929D01*
G01X854226Y1591275D02*
X854375Y1591630D01*
G01X861461D02*
X861711Y1591929D01*
G01X861312Y1591275D02*
X861461Y1591630D01*
G01X868548D02*
X868798Y1591929D01*
G01X868399Y1591275D02*
X868548Y1591630D01*
G01X875635D02*
X875884Y1591929D01*
G01X875485Y1591275D02*
X875635Y1591630D01*
G01X847112Y1591141D02*
X847103Y1591001D01*
G01X847139Y1591281D02*
X847112Y1591141D01*
G01X854199D02*
X854190Y1591001D01*
G01X854226Y1591281D02*
X854199Y1591141D01*
G01X847312Y1591536D02*
X847538Y1591929D01*
G01X847159Y1591060D02*
X847312Y1591536D01*
G01X847103Y1590537D02*
X847159Y1591060D01*
G01X854398Y1591536D02*
X854624Y1591929D01*
G01X854245Y1591060D02*
X854398Y1591536D01*
G01X854190Y1590537D02*
X854245Y1591060D01*
G01X861485Y1591536D02*
X861711Y1591929D01*
G01X861332Y1591060D02*
X861485Y1591536D01*
G01X861276Y1590537D02*
X861332Y1591060D01*
G01X868572Y1591536D02*
X868798Y1591929D01*
G01X868419Y1591060D02*
X868572Y1591536D01*
G01X868363Y1590537D02*
X868419Y1591060D01*
G01X875658Y1591536D02*
X875884Y1591929D01*
G01X875505Y1591060D02*
X875658Y1591536D01*
G01X875450Y1590537D02*
X875505Y1591060D01*
G01X882745Y1591536D02*
X882971Y1591929D01*
G01X882592Y1591060D02*
X882745Y1591536D01*
G01X882536Y1590537D02*
X882592Y1591060D01*
G01X889630Y1591128D02*
X889623Y1591001D01*
G01X889652Y1591255D02*
X889630Y1591128D01*
G01X861285Y1591141D02*
X861276Y1591001D01*
G01X861312Y1591281D02*
X861285Y1591141D01*
G01X868372D02*
X868363Y1591001D01*
G01X868399Y1591281D02*
X868372Y1591141D01*
G01X875459D02*
X875450Y1591001D01*
G01X875485Y1591281D02*
X875459Y1591141D01*
G01X889831Y1591536D02*
X890057Y1591929D01*
G01X889678Y1591060D02*
X889831Y1591536D01*
G01X889623Y1590537D02*
X889678Y1591060D01*
G01X850028Y1591527D02*
X849798Y1591929D01*
G01X850178Y1591055D02*
X850028Y1591527D01*
G01X850233Y1590537D02*
X850178Y1591055D01*
G01X857115Y1591527D02*
X856885Y1591929D01*
G01X857265Y1591055D02*
X857115Y1591527D01*
G01X857320Y1590537D02*
X857265Y1591055D01*
G01X864202Y1591527D02*
X863971Y1591929D01*
G01X864352Y1591055D02*
X864202Y1591527D01*
G01X864406Y1590537D02*
X864352Y1591055D01*
G01X871288Y1591527D02*
X871058Y1591929D01*
G01X871438Y1591055D02*
X871288Y1591527D01*
G01X871493Y1590537D02*
X871438Y1591055D01*
G01X878375Y1591527D02*
X878144Y1591929D01*
G01X878525Y1591055D02*
X878375Y1591527D01*
G01X878580Y1590537D02*
X878525Y1591055D01*
G01X885461Y1591527D02*
X885231Y1591929D01*
G01X885611Y1591055D02*
X885461Y1591527D01*
G01X885666Y1590537D02*
X885611Y1591055D01*
G01X892548Y1591527D02*
X892318Y1591929D01*
G01X892698Y1591055D02*
X892548Y1591527D01*
G01X892753Y1590537D02*
X892698Y1591055D01*
G01X892745Y1591128D02*
X892723Y1591255D01*
G01X892753Y1591001D02*
X892745Y1591128D01*
G01X850227Y1591113D02*
X850210Y1591226D01*
G01X850233Y1591001D02*
X850227Y1591113D01*
G01X857314D02*
X857296Y1591226D01*
G01X857320Y1591001D02*
X857314Y1591113D01*
G01X864400D02*
X864383Y1591226D01*
G01X864406Y1591001D02*
X864400Y1591113D01*
G01X871487D02*
X871470Y1591226D01*
G01X871493Y1591001D02*
X871487Y1591113D01*
G01X878574D02*
X878556Y1591226D01*
G01X878580Y1591001D02*
X878574Y1591113D01*
G01X848631Y1588954D02*
X848521Y1589023D01*
G01X848722Y1588879D02*
X848631Y1588954D01*
G01X848788Y1588793D02*
X848722Y1588879D01*
G01X848813Y1588701D02*
X848788Y1588793D01*
G01X885471Y1591646D02*
X885231Y1591929D01*
G01X885619Y1591323D02*
X885471Y1591646D01*
G01X885666Y1591001D02*
X885619Y1591323D01*
G01X862804Y1588954D02*
X862694Y1589023D01*
G01X862896Y1588879D02*
X862804Y1588954D01*
G01X862961Y1588793D02*
X862896Y1588879D01*
G01X862986Y1588701D02*
X862961Y1588793D01*
G01X876977Y1588954D02*
X876867Y1589023D01*
G01X877069Y1588879D02*
X876977Y1588954D01*
G01X877135Y1588793D02*
X877069Y1588879D01*
G01X877159Y1588701D02*
X877135Y1588793D01*
G01X850127Y1591478D02*
X850210Y1591218D01*
G01X849988Y1591719D02*
X850127Y1591478D01*
G01X849798Y1591929D02*
X849988Y1591719D01*
G01X857214Y1591478D02*
X857296Y1591218D01*
G01X857075Y1591719D02*
X857214Y1591478D01*
G01X856885Y1591929D02*
X857075Y1591719D01*
G01X892577Y1591614D02*
X892723Y1591248D01*
G01X892318Y1591929D02*
X892577Y1591614D01*
G01X864300Y1591478D02*
X864383Y1591218D01*
G01X864161Y1591719D02*
X864300Y1591478D01*
G01X863971Y1591929D02*
X864161Y1591719D01*
G01X871387Y1591478D02*
X871470Y1591218D01*
G01X871248Y1591719D02*
X871387Y1591478D01*
G01X871058Y1591929D02*
X871248Y1591719D01*
G01X878474Y1591478D02*
X878556Y1591218D01*
G01X878335Y1591719D02*
X878474Y1591478D01*
G01X878144Y1591929D02*
X878335Y1591719D01*
G01X847669Y1589624D02*
X847752Y1589654D01*
G01X847618Y1589578D02*
X847669Y1589624D01*
G01X847617Y1589516D02*
X847618Y1589578D01*
G01X847667Y1589448D02*
X847617Y1589516D01*
G01X847749Y1589384D02*
X847667Y1589448D01*
G01X847853Y1589323D02*
X847749Y1589384D01*
G01X848631Y1588954D02*
X848722Y1588879D01*
G01X848521Y1589023D02*
X848631Y1588954D01*
G01X848396Y1589088D02*
X848521Y1589023D01*
G01X848256Y1589151D02*
X848396Y1589088D01*
G01X848103Y1589213D02*
X848256Y1589151D01*
G01X862804Y1588954D02*
X862896Y1588879D01*
G01X862694Y1589023D02*
X862804Y1588954D01*
G01X862569Y1589088D02*
X862694Y1589023D01*
G01X862430Y1589151D02*
X862569Y1589088D01*
G01X862276Y1589213D02*
X862430Y1589151D01*
G01X876977Y1588954D02*
X877069Y1588879D01*
G01X876867Y1589023D02*
X876977Y1588954D01*
G01X876742Y1589088D02*
X876867Y1589023D01*
G01X876603Y1589151D02*
X876742Y1589088D01*
G01X876450Y1589213D02*
X876603Y1589151D01*
G01X861843Y1589624D02*
X861925Y1589654D01*
G01X861791Y1589578D02*
X861843Y1589624D01*
G01X861790Y1589516D02*
X861791Y1589578D01*
G01X861840Y1589448D02*
X861790Y1589516D01*
G01X861922Y1589384D02*
X861840Y1589448D01*
G01X862026Y1589323D02*
X861922Y1589384D01*
G01X876016Y1589624D02*
X876098Y1589654D01*
G01X875965Y1589578D02*
X876016Y1589624D01*
G01X875963Y1589516D02*
X875965Y1589578D01*
G01X876013Y1589448D02*
X875963Y1589516D01*
G01X876095Y1589384D02*
X876013Y1589448D01*
G01X876200Y1589323D02*
X876095Y1589384D01*
G01X891254Y1598031D02*
G03I-709J0D01*
G01X877087Y1594095D02*
G03I-709J0D01*
G01X878144Y1591929D02*
G03X875884I-1130J-1083D01*
G01X885231D02*
G03X882971I-1130J-1083D01*
G01X892318D02*
G03X890057I-1131J-1082D01*
G01X886070Y1610157D02*
G03I-1969J0D01*
G01X893156D02*
G03I-1968J0D01*
G01X878983D02*
G03I-1969J0D01*
G01X856885Y1591929D02*
G03X854624I-1131J-1082D01*
G01X863971D02*
G03X861711I-1130J-1083D01*
G01X871058D02*
G03X868798I-1130J-1083D01*
G01X871896Y1610157D02*
G03I-1968J0D01*
G01X864810D02*
G03I-1969J0D01*
G01X857723D02*
G03I-1968J0D01*
G01X849798Y1591929D02*
G03X847538I-1130J-1083D01*
G01X850637Y1610157D02*
G03I-1969J0D01*
G01X878556Y1587205D02*
X878580D01*
G01X871470D02*
X871493D01*
G01X864383D02*
X864406D01*
G01X857296D02*
X857320D01*
G01X850210D02*
X850233D01*
G01X854226Y1595729D02*
X850210D01*
G01X861312D02*
X857296D01*
G01X868399D02*
X864383D01*
G01X875485D02*
X871470D01*
G01X880289D02*
X878556D01*
G01X889652Y1595728D02*
X887920D01*
G01X896739D02*
X892723D01*
G01X892318Y1591929D02*
X897144D01*
G01X885231D02*
X890057D01*
G01X878144D02*
X882971D01*
G01X871058D02*
X875884D01*
G01X863971D02*
X868798D01*
G01X856885D02*
X861711D01*
G01X849798D02*
X854624D01*
G01X915715Y1589685D02*
X887920D01*
G01X862276Y1589213D02*
X848813D01*
G01X876450D02*
X862986D01*
G01X880289D02*
X877159D01*
G01X891326Y1588780D02*
X890145D01*
G01X915715Y1588701D02*
X887920D01*
G01X877159Y1588386D02*
X875978D01*
G01X887920Y1587205D02*
X877317D01*
G01X915715Y1585630D02*
X887920D01*
G01X850210Y1584449D02*
X847139D01*
G01X857296D02*
X854226D01*
G01X864383D02*
X861312D01*
G01X871470D02*
X868399D01*
G01X878556D02*
X875485D01*
G01X892723D02*
X889652D01*
G01X849029Y1583268D02*
X848320D01*
G01X856115D02*
X855407D01*
G01X863202D02*
X862493D01*
G01X870289D02*
X869580D01*
G01X877375D02*
X876667D01*
G01X891542D02*
X890833D01*
G01X915715Y1582283D02*
X887920D01*
G01X847103Y1587205D02*
X847139D01*
G01X854190D02*
X854226D01*
G01X861276D02*
X861312D01*
G01X868363D02*
X868399D01*
G01X875450D02*
X875485D01*
G01X848103Y1589685D02*
X847970Y1589682D01*
G01X862276Y1589685D02*
X862143Y1589682D01*
G01X876450Y1589685D02*
X876316Y1589682D01*
G01X847851Y1589672D02*
X847971Y1589682D01*
G01X862024Y1589672D02*
X862144Y1589682D01*
G01X876198Y1589672D02*
X876317Y1589682D01*
G01X847749Y1589653D02*
X847853Y1589672D01*
G01X861922Y1589653D02*
X862026Y1589672D01*
G01X876095Y1589653D02*
X876200Y1589672D01*
G01X876317Y1589267D02*
X876198Y1589324D01*
G01X862144Y1589267D02*
X862024Y1589324D01*
G01X847971Y1589267D02*
X847851Y1589324D01*
G01X876450Y1589213D02*
X876316Y1589267D01*
G01X862276Y1589213D02*
X862143Y1589267D01*
G01X848103Y1589213D02*
X847970Y1589267D01*
G01X889652Y1584449D02*
X890833Y1583268D01*
G01X875485Y1584449D02*
X876667Y1583268D01*
G01X868399Y1584449D02*
X869580Y1583268D01*
G01X861312Y1584449D02*
X862493Y1583268D01*
G01X854226Y1584449D02*
X855407Y1583268D01*
G01X847139Y1584449D02*
X848320Y1583268D01*
G01X877135Y1588793D02*
X877159Y1588701D01*
G01X862961Y1588793D02*
X862986Y1588701D01*
G01X848788Y1588793D02*
X848813Y1588701D01*
G01X892753Y1591001D02*
Y1584843D01*
G01X892723Y1595728D02*
Y1584449D01*
G01X891326Y1589685D02*
Y1588780D01*
G01X890145Y1589685D02*
Y1588780D01*
G01X889652Y1595728D02*
Y1584449D01*
G01X889623Y1591001D02*
Y1584843D01*
G01X887920Y1582283D02*
Y1675984D01*
G01X885666Y1591001D02*
Y1584843D01*
G01X882536Y1591001D02*
Y1584843D01*
G01X880289Y1582283D02*
Y1660969D01*
G01X878580Y1591001D02*
Y1584843D01*
G01X878556Y1595729D02*
Y1584449D01*
G01X877159Y1589685D02*
Y1588386D01*
G01X875978Y1589685D02*
Y1588386D01*
G01X875485Y1595729D02*
Y1584449D01*
G01X875450Y1591001D02*
Y1584843D01*
G01X871493Y1591001D02*
Y1584843D01*
G01X871470Y1595729D02*
Y1584449D01*
G01X868399Y1595729D02*
Y1584449D01*
G01X868363Y1591001D02*
Y1584843D01*
G01X864406Y1591001D02*
Y1584843D01*
G01X864383Y1595729D02*
Y1584449D01*
G01X862986Y1589685D02*
Y1588701D01*
G01X861312Y1595729D02*
Y1584449D01*
G01X861276Y1591001D02*
Y1584843D01*
G01X857320Y1591001D02*
Y1584843D01*
G01X857296Y1595729D02*
Y1584449D01*
G01X854226Y1595729D02*
Y1584449D01*
G01X854190Y1591001D02*
Y1584843D01*
G01X850233Y1591001D02*
Y1584843D01*
G01X850210Y1595729D02*
Y1584449D01*
G01X848813Y1589685D02*
Y1588701D01*
G01X847139Y1595729D02*
Y1584449D01*
G01X847103Y1591001D02*
Y1584843D01*
G01X892723Y1584449D02*
X891542Y1583268D01*
G01X878556Y1584449D02*
X877375Y1583268D01*
G01X871470Y1584449D02*
X870289Y1583268D01*
G01X864383Y1584449D02*
X863202Y1583268D01*
G01X857296Y1584449D02*
X856115Y1583268D01*
G01X850210Y1584449D02*
X849029Y1583268D01*
G01X880270Y1660874D02*
X880230Y1660780D01*
G01X880286Y1660985D02*
X880270Y1660874D01*
G01X888815Y1660711D02*
X888879Y1660772D01*
G01X888740Y1660690D02*
X888815Y1660711D01*
G01X888664D02*
X888740Y1660690D01*
G01X888600Y1660772D02*
X888664Y1660711D01*
G01X888558Y1660861D02*
X888600Y1660772D01*
G01X888543Y1660969D02*
X888558Y1660861D01*
G01X880270Y1660874D02*
X880286Y1660985D01*
G01X880230Y1660780D02*
X880270Y1660874D01*
G01X880167Y1660715D02*
X880230Y1660780D01*
G01X880090Y1660690D02*
X880167Y1660715D01*
G01X880012Y1660710D02*
X880090Y1660690D01*
G01X879946Y1660772D02*
X880012Y1660710D01*
G01X891254Y1650394D02*
G03I-709J0D01*
G01X892723Y1642357D02*
G03Y1644137I-1299J890D01*
G01Y1635034D02*
G03Y1636814I-1299J890D01*
G01X889652Y1644137D02*
G03Y1642357I1299J-890D01*
G01Y1636814D02*
G03Y1635034I1299J-890D01*
G01X877087Y1650788D02*
G03I-709J0D01*
G01X875485Y1644137D02*
G03Y1642357I1300J-890D01*
G01Y1636814D02*
G03Y1635034I1300J-890D01*
G01X878556D02*
G03Y1636814I-1299J890D01*
G01Y1642357D02*
G03Y1644137I-1299J890D01*
G01X892566Y1625348D02*
G03X893550Y1626332I0J984D01*
G01X888826D02*
G03X889810Y1625348I984J0D01*
G01X878399D02*
G03X879383Y1626332I0J984D01*
G01X874659D02*
G03X875643Y1625348I984J0D01*
G01X889623Y1629843D02*
G03X892753I1565J0D01*
G01X882536D02*
G03X885666I1565J0D01*
G01X875450D02*
G03X878580I1565J0D01*
G01X864383Y1642357D02*
G03Y1644137I-1299J890D01*
G01X871470Y1642357D02*
G03Y1644137I-1299J890D01*
G01X868399D02*
G03Y1642357I1299J-890D01*
G01X864383Y1635034D02*
G03Y1636814I-1299J890D01*
G01X871470Y1635034D02*
G03Y1636814I-1299J890D01*
G01X868399D02*
G03Y1635034I1299J-890D01*
G01X861312Y1644137D02*
G03Y1642357I1299J-890D01*
G01X857296D02*
G03Y1644137I-1299J890D01*
G01X854226D02*
G03Y1642357I1299J-890D01*
G01X861312Y1636814D02*
G03Y1635034I1299J-890D01*
G01X857296D02*
G03Y1636814I-1299J890D01*
G01X854226D02*
G03Y1635034I1299J-890D01*
G01X847139Y1644137D02*
G03Y1642357I1299J-890D01*
G01X850210D02*
G03Y1644137I-1299J890D01*
G01X847139Y1636814D02*
G03Y1635034I1299J-890D01*
G01X850210D02*
G03Y1636814I-1299J890D01*
G01X871312Y1625348D02*
G03X872296Y1626332I0J984D01*
G01X867572D02*
G03X868556Y1625348I984J0D01*
G01X864226D02*
G03X865210Y1626332I0J984D01*
G01X860485D02*
G03X861470Y1625348I984J0D01*
G01X857139D02*
G03X858123Y1626332I0J984D01*
G01X853399D02*
G03X854383Y1625348I984J0D01*
G01X868363Y1629843D02*
G03X871493I1565J0D01*
G01X861276D02*
G03X864406I1565J0D01*
G01X854190D02*
G03X857320I1565J0D01*
G01X850052Y1625348D02*
G03X851037Y1626332I1J984D01*
G01X846312D02*
G03X847296Y1625348I984J0D01*
G01X847103Y1629843D02*
G03X850233I1565J0D01*
G01X876148Y1662992D02*
X878510D01*
G01X861975D02*
X864337D01*
G01X847802D02*
X850164D01*
G01X857250D02*
X854888D01*
G01X871424D02*
X869061D01*
G01X892677D02*
X890315D01*
G01X850164Y1661417D02*
X847802D01*
G01X857250D02*
X854888D01*
G01X864337D02*
X861975D01*
G01X871424D02*
X869061D01*
G01X878510D02*
X876148D01*
G01X892677D02*
X890315D01*
G01X850262Y1661220D02*
X847703D01*
G01X857349D02*
X854790D01*
G01X864435D02*
X861876D01*
G01X871522D02*
X868963D01*
G01X878609D02*
X876050D01*
G01X892776D02*
X890217D01*
G01X853018Y1660157D02*
X852034D01*
G01X860105D02*
X859120D01*
G01X867191D02*
X866207D01*
G01X874278D02*
X873294D01*
G01X851421Y1659646D02*
X846544D01*
G01X858508D02*
X853631D01*
G01X865594D02*
X860717D01*
G01X872681D02*
X867804D01*
G01X879768D02*
X874891D01*
G01X893935D02*
X889057D01*
G01X915715Y1659213D02*
X887920D01*
G01X915709Y1659055D02*
X888543D01*
G01X915715Y1658661D02*
X887920D01*
G01X915715Y1658425D02*
X887920D01*
G01X871470Y1649757D02*
X875485D01*
G01X854226D02*
X850210D01*
G01X861312D02*
X857296D01*
G01X868399D02*
X864383D01*
G01X880289D02*
X878556D01*
G01X889652D02*
X887920D01*
G01X896739D02*
X892723D01*
G01X852802Y1648740D02*
X851621D01*
G01X859889D02*
X858707D01*
G01X866975D02*
X865794D01*
G01X874062D02*
X872881D01*
G01X881148D02*
X879967D01*
G01X888235D02*
X887054D01*
G01X895322D02*
X894141D01*
G01X853983Y1646694D02*
X850440D01*
G01X861070D02*
X857526D01*
G01X868156D02*
X864613D01*
G01X875243D02*
X871700D01*
G01X882330D02*
X878786D01*
G01X889416D02*
X885873D01*
G01X896503D02*
X892959D01*
G01X849422Y1631436D02*
X847926D01*
G01X856509D02*
X855013D01*
G01X863596D02*
X862100D01*
G01X870682D02*
X869186D01*
G01X877769D02*
X876273D01*
G01X891936D02*
X890440D01*
G01X874659Y1627871D02*
X879383D01*
G01X867572D02*
X872296D01*
G01X860485D02*
X865210D01*
G01X853399D02*
X858123D01*
G01X846312D02*
X851037D01*
G01X888826Y1627870D02*
X893550D01*
G01X850052Y1625348D02*
X847296D01*
G01X857139D02*
X854383D01*
G01X864226D02*
X861470D01*
G01X871312D02*
X868556D01*
G01X878399D02*
X875643D01*
G01X892566D02*
X889810D01*
G01X880012Y1660710D02*
X879946Y1660772D01*
G01X893366Y1661828D02*
X894547Y1660157D01*
G01X893366Y1660450D02*
X893935Y1659646D01*
G01X879199Y1661828D02*
X879946Y1660772D01*
G01X879199Y1660450D02*
X879768Y1659646D01*
G01X872113Y1661828D02*
X873294Y1660157D01*
G01X872113Y1660450D02*
X872681Y1659646D01*
G01X865026Y1661828D02*
X866207Y1660157D01*
G01X865026Y1660450D02*
X865594Y1659646D01*
G01X857939Y1661828D02*
X859120Y1660157D01*
G01X857939Y1660450D02*
X858508Y1659646D01*
G01X850853Y1661828D02*
X852034Y1660157D01*
G01X850853Y1660450D02*
X851421Y1659646D01*
G01X888235Y1648740D02*
X889618Y1646345D01*
G01X881148Y1648740D02*
X882531Y1646345D01*
G01X890440Y1631436D02*
X889652Y1632800D01*
G01X874062Y1648740D02*
X875444Y1646345D01*
G01X866975Y1648740D02*
X868358Y1646345D01*
G01X876273Y1631436D02*
X875485Y1632800D01*
G01X859889Y1648740D02*
X861271Y1646345D01*
G01X869186Y1631436D02*
X868399Y1632800D01*
G01X852802Y1648740D02*
X854185Y1646345D01*
G01X862100Y1631436D02*
X861312Y1632800D01*
G01X855013Y1631436D02*
X854226Y1632800D01*
G01X847926Y1631436D02*
X847139Y1632800D01*
G01X892756Y1635083D02*
X892753Y1629843D01*
G01X892760Y1642413D02*
X892757Y1636763D01*
G01X892763Y1646354D02*
X892761Y1644078D01*
G01X893935Y1659646D02*
Y1659055D01*
G01X893550Y1649757D02*
Y1626332D01*
G01X893366Y1672278D02*
Y1660450D01*
G01X893268Y1672008D02*
Y1658661D01*
G01X893071D02*
Y1670709D01*
G01X892776Y1665551D02*
Y1661220D01*
G01X892723Y1635034D02*
Y1632800D01*
G01Y1642357D02*
Y1636814D01*
G01Y1649757D02*
Y1644137D01*
G01X892677Y1665354D02*
Y1661417D01*
G01X890315Y1665354D02*
Y1661417D01*
G01X890217Y1665551D02*
Y1661220D01*
G01X889921Y1670709D02*
Y1658661D01*
G01X889620Y1635083D02*
X889623Y1629843D01*
G01X889615Y1642413D02*
X889619Y1636763D01*
G01X889613Y1646354D02*
X889614Y1644078D01*
G01X885676Y1646354D02*
X885666Y1629843D01*
G01X878583Y1635074D02*
X878580Y1629843D01*
G01X878587Y1642404D02*
X878583Y1636773D01*
G01X878589Y1646354D02*
X878588Y1644089D01*
G01X871496Y1635074D02*
X871493Y1629843D01*
G01X871500Y1642404D02*
X871497Y1636773D01*
G01X871503Y1646354D02*
X871501Y1644089D01*
G01X864409Y1635074D02*
X864406Y1629843D01*
G01X864414Y1642404D02*
X864410Y1636773D01*
G01X864416Y1646354D02*
X864415Y1644089D01*
G01X857323Y1635074D02*
X857320Y1629843D01*
G01X857327Y1642404D02*
X857324Y1636773D01*
G01X857330Y1646354D02*
X857328Y1644089D01*
G01X850236Y1635074D02*
X850233Y1629843D01*
G01X850241Y1642404D02*
X850237Y1636773D01*
G01X850243Y1646354D02*
X850241Y1644089D01*
G01X889724Y1672008D02*
Y1658661D01*
G01X889652Y1635034D02*
Y1632800D01*
G01Y1642357D02*
Y1636814D01*
G01Y1649757D02*
Y1644137D01*
G01X889626Y1672278D02*
Y1660450D01*
G01X889057Y1659646D02*
Y1659055D01*
G01X888879Y1660772D02*
Y1659055D01*
G01X888826Y1649757D02*
Y1626332D01*
G01X888543Y1718504D02*
Y1659055D01*
G01X880282Y1718504D02*
Y1659055D01*
G01X879946Y1660772D02*
Y1659055D01*
G01X879768Y1659646D02*
Y1659055D01*
G01X879383Y1649757D02*
Y1626332D01*
G01X879199Y1672278D02*
Y1660450D01*
G01X879101Y1672008D02*
Y1658661D01*
G01X878904D02*
Y1670709D01*
G01X878609Y1665551D02*
Y1661220D01*
G01X878556Y1635034D02*
Y1632800D01*
G01Y1642357D02*
Y1636814D01*
G01Y1649757D02*
Y1644137D01*
G01X878510Y1665354D02*
Y1661417D01*
G01X876148Y1665354D02*
Y1661417D01*
G01X876050Y1665551D02*
Y1661220D01*
G01X875754Y1670709D02*
Y1658661D01*
G01X875557Y1672008D02*
Y1658661D01*
G01X875485Y1635034D02*
Y1632800D01*
G01Y1642357D02*
Y1636814D01*
G01Y1649757D02*
Y1644137D01*
G01X875459Y1672278D02*
Y1660450D01*
G01X874891Y1659646D02*
Y1659055D01*
G01X874659Y1649757D02*
Y1626332D01*
G01X874278Y1660157D02*
Y1659055D01*
G01X873294Y1660157D02*
Y1659055D01*
G01X872681Y1659646D02*
Y1659055D01*
G01X872296Y1649757D02*
Y1626332D01*
G01X872113Y1672278D02*
Y1660450D01*
G01X872014Y1672008D02*
Y1658661D01*
G01X871817D02*
Y1670709D01*
G01X871522Y1665551D02*
Y1661220D01*
G01X871470Y1635034D02*
Y1632800D01*
G01Y1642357D02*
Y1636814D01*
G01Y1649757D02*
Y1644137D01*
G01X871424Y1665354D02*
Y1661417D01*
G01X869061Y1665354D02*
Y1661417D01*
G01X868963Y1665551D02*
Y1661220D01*
G01X868668Y1670709D02*
Y1658661D01*
G01X868471Y1672008D02*
Y1658661D01*
G01X868399Y1635034D02*
Y1632800D01*
G01Y1642357D02*
Y1636814D01*
G01Y1649757D02*
Y1644137D01*
G01X868372Y1672278D02*
Y1660450D01*
G01X867804Y1659646D02*
Y1659055D01*
G01X867572Y1649757D02*
Y1626332D01*
G01X867191Y1660157D02*
Y1659055D01*
G01X866207Y1660157D02*
Y1659055D01*
G01X865594Y1659646D02*
Y1659055D01*
G01X865210Y1649757D02*
Y1626332D01*
G01X865026Y1672278D02*
Y1660450D01*
G01X864928Y1672008D02*
Y1658661D01*
G01X864731D02*
Y1670709D01*
G01X864435Y1665551D02*
Y1661220D01*
G01X864383Y1635034D02*
Y1632800D01*
G01Y1642357D02*
Y1636814D01*
G01Y1649757D02*
Y1644137D01*
G01X864337Y1665354D02*
Y1661417D01*
G01X861975Y1665354D02*
Y1661417D01*
G01X861876Y1665551D02*
Y1661220D01*
G01X861581Y1670709D02*
Y1658661D01*
G01X861384Y1672008D02*
Y1658661D01*
G01X861312Y1635034D02*
Y1632800D01*
G01Y1642357D02*
Y1636814D01*
G01Y1649757D02*
Y1644137D01*
G01X861286Y1672278D02*
Y1660450D01*
G01X860717Y1659646D02*
Y1659055D01*
G01X860485Y1649757D02*
Y1626332D01*
G01X860105Y1660157D02*
Y1659055D01*
G01X859120Y1660157D02*
Y1659055D01*
G01X858508Y1659646D02*
Y1659055D01*
G01X858123Y1649757D02*
Y1626332D01*
G01X857939Y1672278D02*
Y1660450D01*
G01X857841Y1672008D02*
Y1658661D01*
G01X857644D02*
Y1670709D01*
G01X857349Y1665551D02*
Y1661220D01*
G01X857296Y1635034D02*
Y1632800D01*
G01Y1642357D02*
Y1636814D01*
G01Y1649757D02*
Y1644137D01*
G01X857250Y1665354D02*
Y1661417D01*
G01X854888Y1665354D02*
Y1661417D01*
G01X854790Y1665551D02*
Y1661220D01*
G01X854494Y1670709D02*
Y1658661D01*
G01X854298Y1672008D02*
Y1658661D01*
G01X854226Y1635034D02*
Y1632800D01*
G01Y1642357D02*
Y1636814D01*
G01Y1649757D02*
Y1644137D01*
G01X854199Y1672278D02*
Y1660450D01*
G01X853631Y1659646D02*
Y1659055D01*
G01X853399Y1649757D02*
Y1626332D01*
G01X853018Y1660157D02*
Y1659055D01*
G01X852034Y1660157D02*
Y1659055D01*
G01X851421Y1659646D02*
Y1659055D01*
G01X851037Y1649757D02*
Y1626332D01*
G01X850853Y1672278D02*
Y1660450D01*
G01X850754Y1672008D02*
Y1658661D01*
G01X850557D02*
Y1670709D01*
G01X850262Y1665551D02*
Y1661220D01*
G01X850210Y1635034D02*
Y1632800D01*
G01Y1642357D02*
Y1636814D01*
G01Y1649757D02*
Y1644137D01*
G01X850164Y1665354D02*
Y1661417D01*
G01X847802Y1665354D02*
Y1661417D01*
G01X847703Y1665551D02*
Y1661220D01*
G01X847408Y1670709D02*
Y1658661D01*
G01X847211Y1672008D02*
Y1658661D01*
G01X847139Y1635034D02*
Y1632800D01*
G01Y1642357D02*
Y1636814D01*
G01Y1649757D02*
Y1644137D01*
G01X847113Y1672278D02*
Y1660450D01*
G01X846544Y1659646D02*
Y1659055D01*
G01X846312Y1649757D02*
Y1626332D01*
G01X882526Y1646354D02*
X882536Y1629843D01*
G01X875446Y1635094D02*
X875450Y1629843D01*
G01X875442Y1642424D02*
X875445Y1636753D01*
G01X875440Y1646354D02*
X875441Y1644069D01*
G01X868360Y1635094D02*
X868363Y1629843D01*
G01X868356Y1642424D02*
X868359Y1636753D01*
G01X868353Y1646354D02*
X868354Y1644069D01*
G01X861273Y1635094D02*
X861276Y1629843D01*
G01X861269Y1642424D02*
X861272Y1636753D01*
G01X861267Y1646354D02*
X861268Y1644069D01*
G01X854187Y1635094D02*
X854190Y1629843D01*
G01X854182Y1642424D02*
X854185Y1636753D01*
G01X854180Y1646354D02*
X854181Y1644069D01*
G01X847100Y1635094D02*
X847103Y1629843D01*
G01X847096Y1642424D02*
X847099Y1636753D01*
G01X847093Y1646354D02*
X847094Y1644069D01*
G01X880286Y1660985D02*
X880289Y1659213D01*
G01X892723Y1632800D02*
X891936Y1631436D01*
G01X892757Y1646345D02*
X894141Y1648740D01*
G01X878556Y1632800D02*
X877769Y1631436D01*
G01X885671Y1646345D02*
X887054Y1648740D01*
G01X871470Y1632800D02*
X870682Y1631436D01*
G01X878584Y1646345D02*
X879967Y1648740D01*
G01X864383Y1632800D02*
X863596Y1631436D01*
G01X871498Y1646345D02*
X872881Y1648740D01*
G01X857296Y1632800D02*
X856509Y1631436D01*
G01X864411Y1646345D02*
X865794Y1648740D01*
G01X889626Y1660450D02*
X889057Y1659646D01*
G01X889626Y1661828D02*
X888879Y1660772D01*
G01X875459Y1660450D02*
X874891Y1659646D01*
G01X875459Y1661828D02*
X874278Y1660157D01*
G01X868372Y1660450D02*
X867804Y1659646D01*
G01X868372Y1661828D02*
X867191Y1660157D01*
G01X861286Y1660450D02*
X860717Y1659646D01*
G01X861286Y1661828D02*
X860105Y1660157D01*
G01X854199Y1660450D02*
X853631Y1659646D01*
G01X854199Y1661828D02*
X853018Y1660157D01*
G01X847113Y1660450D02*
X846544Y1659646D01*
G01X850210Y1632800D02*
X849422Y1631436D01*
G01X857324Y1646345D02*
X858707Y1648740D01*
G01X850238Y1646345D02*
X851621Y1648740D01*
G01X888879Y1660772D02*
X888815Y1660711D01*
G01X854713Y1711005D02*
X854580Y1710783D01*
G01X854835Y1711202D02*
X854713Y1711005D01*
G01X854946Y1711370D02*
X854835Y1711202D01*
G01X855043Y1711506D02*
X854946Y1711370D01*
G01X855118Y1711597D02*
X855043Y1711506D01*
G01X855161Y1711628D02*
X855118Y1711597D01*
G01X868886Y1711005D02*
X868753Y1710783D01*
G01X869009Y1711202D02*
X868886Y1711005D01*
G01X869120Y1711370D02*
X869009Y1711202D01*
G01X869216Y1711506D02*
X869120Y1711370D01*
G01X869291Y1711597D02*
X869216Y1711506D01*
G01X869335Y1711628D02*
X869291Y1711597D01*
G01X855255Y1711582D02*
X855122Y1711359D01*
G01X855378Y1711778D02*
X855255Y1711582D01*
G01X869428D02*
X869295Y1711359D01*
G01X869551Y1711778D02*
X869428Y1711582D01*
G01X847308Y1671394D02*
X847228Y1671294D01*
G01X847402Y1671488D02*
X847308Y1671394D01*
G01X847506Y1671572D02*
X847402Y1671488D01*
G01X854489D02*
X854394Y1671394D01*
G01X854593Y1671572D02*
X854489Y1671488D01*
G01X861575D02*
X861481Y1671394D01*
G01X861680Y1671572D02*
X861575Y1671488D01*
G01X868662D02*
X868568Y1671394D01*
G01X868766Y1671572D02*
X868662Y1671488D01*
G01X875748D02*
X875654Y1671394D01*
G01X875853Y1671572D02*
X875748Y1671488D01*
G01X889915D02*
X889821Y1671394D01*
G01X890020Y1671572D02*
X889915Y1671488D01*
G01X890139Y1711005D02*
X890007Y1710783D01*
G01X890262Y1711201D02*
X890139Y1711005D01*
G01X890373Y1711370D02*
X890262Y1711201D01*
G01X890469Y1711505D02*
X890373Y1711370D01*
G01X890545Y1711596D02*
X890469Y1711505D01*
G01X890588Y1711628D02*
X890545Y1711596D01*
G01X890681Y1711582D02*
X890548Y1711359D01*
G01X890804Y1711778D02*
X890681Y1711582D01*
G01X854489Y1671488D02*
X854593Y1671572D01*
G01X854394Y1671394D02*
X854489Y1671488D01*
G01X854315Y1671294D02*
X854394Y1671394D01*
G01X861575Y1671488D02*
X861680Y1671572D01*
G01X861481Y1671394D02*
X861575Y1671488D01*
G01X861401Y1671294D02*
X861481Y1671394D01*
G01X868662Y1671488D02*
X868766Y1671572D01*
G01X868568Y1671394D02*
X868662Y1671488D01*
G01X868488Y1671294D02*
X868568Y1671394D01*
G01X875748Y1671488D02*
X875853Y1671572D01*
G01X875654Y1671394D02*
X875748Y1671488D01*
G01X875574Y1671294D02*
X875654Y1671394D01*
G01X858784Y1681670D02*
X858791Y1681890D01*
G01X858761Y1681475D02*
X858784Y1681670D01*
G01X858727Y1681344D02*
X858761Y1681475D01*
G01X858687Y1681299D02*
X858727Y1681344D01*
G01X872957Y1681670D02*
X872965Y1681890D01*
G01X872935Y1681475D02*
X872957Y1681670D01*
G01X872900Y1681344D02*
X872935Y1681475D01*
G01X872860Y1681299D02*
X872900Y1681344D01*
G01X894211Y1681670D02*
X894218Y1681890D01*
G01X894188Y1681474D02*
X894211Y1681670D01*
G01X894154Y1681343D02*
X894188Y1681474D01*
G01X894114Y1681299D02*
X894154Y1681343D01*
G01X847127Y1671048D02*
X847113Y1670900D01*
G01X847166Y1671181D02*
X847127Y1671048D01*
G01X847228Y1671294D02*
X847166Y1671181D01*
G01X858826Y1681526D02*
X858831Y1681890D01*
G01X858811Y1681197D02*
X858826Y1681526D01*
G01X858788Y1680935D02*
X858811Y1681197D01*
G01X858759Y1680767D02*
X858788Y1680935D01*
G01X858727Y1680709D02*
X858759Y1680767D01*
G01X850633Y1670724D02*
X850557Y1670709D01*
G01X850697Y1670767D02*
X850633Y1670724D01*
G01X850739Y1670829D02*
X850697Y1670767D01*
G01X857719Y1670724D02*
X857644Y1670709D01*
G01X857783Y1670767D02*
X857719Y1670724D01*
G01X857826Y1670829D02*
X857783Y1670767D01*
G01X864806Y1670724D02*
X864731Y1670709D01*
G01X864870Y1670767D02*
X864806Y1670724D01*
G01X864912Y1670829D02*
X864870Y1670767D01*
G01X871893Y1670724D02*
X871817Y1670709D01*
G01X871957Y1670767D02*
X871893Y1670724D01*
G01X871999Y1670829D02*
X871957Y1670767D01*
G01X878979Y1670724D02*
X878904Y1670709D01*
G01X879043Y1670767D02*
X878979Y1670724D01*
G01X879085Y1670829D02*
X879043Y1670767D01*
G01X889915Y1671488D02*
X890020Y1671572D01*
G01X889821Y1671394D02*
X889915Y1671488D01*
G01X889741Y1671294D02*
X889821Y1671394D01*
G01X854213Y1671048D02*
X854199Y1670900D01*
G01X854253Y1671181D02*
X854213Y1671048D01*
G01X854315Y1671294D02*
X854253Y1671181D01*
G01X861300Y1671048D02*
X861286Y1670900D01*
G01X861339Y1671181D02*
X861300Y1671048D01*
G01X861401Y1671294D02*
X861339Y1671181D01*
G01X868387Y1671048D02*
X868372Y1670900D01*
G01X868426Y1671181D02*
X868387Y1671048D01*
G01X868488Y1671294D02*
X868426Y1671181D01*
G01X875473Y1671048D02*
X875459Y1670900D01*
G01X875513Y1671181D02*
X875473Y1671048D01*
G01X875574Y1671294D02*
X875513Y1671181D01*
G01X889640Y1671048D02*
X889626Y1670900D01*
G01X889680Y1671180D02*
X889640Y1671048D01*
G01X889741Y1671294D02*
X889680Y1671180D01*
G01X872999Y1681526D02*
X873004Y1681890D01*
G01X872985Y1681197D02*
X872999Y1681526D01*
G01X872961Y1680935D02*
X872985Y1681197D01*
G01X872933Y1680767D02*
X872961Y1680935D01*
G01X872900Y1680709D02*
X872933Y1680767D01*
G01X894253Y1681526D02*
X894258Y1681890D01*
G01X894238Y1681197D02*
X894253Y1681526D01*
G01X894215Y1680935D02*
X894238Y1681197D01*
G01X894186Y1680767D02*
X894215Y1680935D01*
G01X894154Y1680709D02*
X894186Y1680767D01*
G01X855664Y1680759D02*
X855483Y1680709D01*
G01X855804Y1680890D02*
X855664Y1680759D01*
G01X855887Y1681079D02*
X855804Y1680890D01*
G01X855902Y1681299D02*
X855887Y1681079D01*
G01X855177Y1680758D02*
X854996Y1680709D01*
G01X855317Y1680889D02*
X855177Y1680758D01*
G01X855401Y1681078D02*
X855317Y1680889D01*
G01X855416Y1681299D02*
X855401Y1681078D01*
G01X858562Y1681685D02*
X858565Y1681890D01*
G01X858552Y1681486D02*
X858562Y1681685D01*
G01X858537Y1681299D02*
X858552Y1681486D01*
G01X872735Y1681685D02*
X872738Y1681890D01*
G01X872726Y1681486D02*
X872735Y1681685D01*
G01X872710Y1681299D02*
X872726Y1681486D01*
G01X854799Y1680720D02*
X854684Y1680709D01*
G01X854907Y1680754D02*
X854799Y1680720D01*
G01X855007Y1680809D02*
X854907Y1680754D01*
G01X855095Y1680882D02*
X855007Y1680809D01*
G01X855169Y1680972D02*
X855095Y1680882D01*
G01X855222Y1681074D02*
X855169Y1680972D01*
G01X855255Y1681185D02*
X855222Y1681074D01*
G01X855266Y1681299D02*
X855255Y1681185D01*
G01X868972Y1680720D02*
X868857Y1680709D01*
G01X869081Y1680754D02*
X868972Y1680720D01*
G01X869181Y1680809D02*
X869081Y1680754D01*
G01X869269Y1680882D02*
X869181Y1680809D01*
G01X869342Y1680972D02*
X869269Y1680882D01*
G01X869395Y1681074D02*
X869342Y1680972D01*
G01X869428Y1681185D02*
X869395Y1681074D01*
G01X869439Y1681299D02*
X869428Y1681185D01*
G01X847360Y1672795D02*
X847506Y1672835D01*
G01X847232Y1672678D02*
X847360Y1672795D01*
G01X847145Y1672500D02*
X847232Y1672678D01*
G01X847113Y1672278D02*
X847145Y1672500D01*
G01X854447Y1672795D02*
X854593Y1672835D01*
G01X854319Y1672678D02*
X854447Y1672795D01*
G01X854232Y1672500D02*
X854319Y1672678D01*
G01X854199Y1672278D02*
X854232Y1672500D01*
G01X861533Y1672795D02*
X861680Y1672835D01*
G01X861406Y1672678D02*
X861533Y1672795D01*
G01X861319Y1672500D02*
X861406Y1672678D01*
G01X861286Y1672278D02*
X861319Y1672500D01*
G01X868620Y1672795D02*
X868766Y1672835D01*
G01X868492Y1672678D02*
X868620Y1672795D01*
G01X868405Y1672500D02*
X868492Y1672678D01*
G01X868372Y1672278D02*
X868405Y1672500D01*
G01X875707Y1672795D02*
X875853Y1672835D01*
G01X875579Y1672678D02*
X875707Y1672795D01*
G01X875492Y1672500D02*
X875579Y1672678D01*
G01X875459Y1672278D02*
X875492Y1672500D01*
G01X893146Y1670724D02*
X893071Y1670709D01*
G01X893210Y1670766D02*
X893146Y1670724D01*
G01X893252Y1670829D02*
X893210Y1670766D01*
G01X893268Y1670906D02*
X893252Y1670829D01*
G01X855226Y1681343D02*
X855266Y1681299D01*
G01X855192Y1681474D02*
X855226Y1681343D01*
G01X855169Y1681669D02*
X855192Y1681474D01*
G01X855161Y1681890D02*
X855169Y1681669D01*
G01X855194Y1680767D02*
X855226Y1680709D01*
G01X855165Y1680935D02*
X855194Y1680767D01*
G01X855141Y1681196D02*
X855165Y1680935D01*
G01X855127Y1681526D02*
X855141Y1681196D01*
G01X855122Y1681890D02*
X855127Y1681526D01*
G01X869367Y1680767D02*
X869399Y1680709D01*
G01X869338Y1680935D02*
X869367Y1680767D01*
G01X869315Y1681196D02*
X869338Y1680935D01*
G01X869300Y1681526D02*
X869315Y1681196D01*
G01X869295Y1681890D02*
X869300Y1681526D01*
G01X859301Y1680767D02*
X859269Y1680709D01*
G01X859330Y1680935D02*
X859301Y1680767D01*
G01X859353Y1681196D02*
X859330Y1680935D01*
G01X859368Y1681526D02*
X859353Y1681196D01*
G01X859373Y1681890D02*
X859368Y1681526D01*
G01X873474Y1680767D02*
X873442Y1680709D01*
G01X873503Y1680935D02*
X873474Y1680767D01*
G01X873526Y1681196D02*
X873503Y1680935D01*
G01X873541Y1681526D02*
X873526Y1681196D01*
G01X873546Y1681890D02*
X873541Y1681526D01*
G01X858066Y1681486D02*
X858051Y1681299D01*
G01X858076Y1681685D02*
X858066Y1681486D01*
G01X858079Y1681890D02*
X858076Y1681685D01*
G01X872239Y1681486D02*
X872224Y1681299D01*
G01X872249Y1681685D02*
X872239Y1681486D01*
G01X872252Y1681890D02*
X872249Y1681685D01*
G01X858185Y1681343D02*
X858145Y1681299D01*
G01X858219Y1681474D02*
X858185Y1681343D01*
G01X858242Y1681669D02*
X858219Y1681474D01*
G01X858250Y1681890D02*
X858242Y1681669D01*
G01X872358Y1681343D02*
X872319Y1681299D01*
G01X872393Y1681474D02*
X872358Y1681343D01*
G01X872415Y1681669D02*
X872393Y1681474D01*
G01X872423Y1681890D02*
X872415Y1681669D01*
G01X893611Y1681343D02*
X893572Y1681299D01*
G01X893646Y1681474D02*
X893611Y1681343D01*
G01X893669Y1681669D02*
X893646Y1681474D01*
G01X893676Y1681890D02*
X893669Y1681669D01*
G01X869837Y1680759D02*
X869656Y1680709D01*
G01X869977Y1680890D02*
X869837Y1680759D01*
G01X870061Y1681079D02*
X869977Y1680890D01*
G01X870075Y1681299D02*
X870061Y1681079D01*
G01X869350Y1680758D02*
X869170Y1680709D01*
G01X869491Y1680889D02*
X869350Y1680758D01*
G01X869574Y1681078D02*
X869491Y1680889D01*
G01X869589Y1681299D02*
X869574Y1681078D01*
G01X890604Y1680758D02*
X890423Y1680709D01*
G01X890744Y1680889D02*
X890604Y1680758D01*
G01X890828Y1681078D02*
X890744Y1680889D01*
G01X890843Y1681299D02*
X890828Y1681078D01*
G01X893989Y1681685D02*
X893992Y1681890D01*
G01X893979Y1681486D02*
X893989Y1681685D01*
G01X893964Y1681299D02*
X893979Y1681486D01*
G01X893502Y1681685D02*
X893506Y1681890D01*
G01X893493Y1681485D02*
X893502Y1681685D01*
G01X893478Y1681299D02*
X893493Y1681485D01*
G01X890226Y1680720D02*
X890111Y1680709D01*
G01X890334Y1680754D02*
X890226Y1680720D01*
G01X890434Y1680808D02*
X890334Y1680754D01*
G01X890522Y1680881D02*
X890434Y1680808D01*
G01X890595Y1680972D02*
X890522Y1680881D01*
G01X890648Y1681074D02*
X890595Y1680972D01*
G01X890681Y1681184D02*
X890648Y1681074D01*
G01X890692Y1681299D02*
X890681Y1681184D01*
G01X858612Y1680720D02*
X858727Y1680709D01*
G01X858504Y1680754D02*
X858612Y1680720D01*
G01X858404Y1680809D02*
X858504Y1680754D01*
G01X858316Y1680882D02*
X858404Y1680809D01*
G01X858243Y1680972D02*
X858316Y1680882D01*
G01X858189Y1681074D02*
X858243Y1680972D01*
G01X858157Y1681185D02*
X858189Y1681074D01*
G01X858145Y1681299D02*
X858157Y1681185D01*
G01X872785Y1680720D02*
X872900Y1680709D01*
G01X872677Y1680754D02*
X872785Y1680720D01*
G01X872577Y1680809D02*
X872677Y1680754D01*
G01X872489Y1680882D02*
X872577Y1680809D01*
G01X872416Y1680972D02*
X872489Y1680882D01*
G01X872363Y1681074D02*
X872416Y1680972D01*
G01X872330Y1681185D02*
X872363Y1681074D01*
G01X872319Y1681299D02*
X872330Y1681185D01*
G01X893196Y1672736D02*
X893124Y1672792D01*
G01X893261Y1672657D02*
X893196Y1672736D01*
G01X893315Y1672554D02*
X893261Y1672657D01*
G01X893352Y1672427D02*
X893315Y1672554D01*
G01X893366Y1672278D02*
X893352Y1672427D01*
G01X850799Y1671181D02*
X850737Y1671294D01*
G01X850839Y1671048D02*
X850799Y1671181D01*
G01X850853Y1670900D02*
X850839Y1671048D01*
G01X857886Y1671181D02*
X857824Y1671294D01*
G01X857925Y1671048D02*
X857886Y1671181D01*
G01X857939Y1670900D02*
X857925Y1671048D01*
G01X864972Y1671181D02*
X864911Y1671294D01*
G01X865012Y1671048D02*
X864972Y1671181D01*
G01X865026Y1670900D02*
X865012Y1671048D01*
G01X872059Y1671181D02*
X871997Y1671294D01*
G01X872098Y1671048D02*
X872059Y1671181D01*
G01X872113Y1670900D02*
X872098Y1671048D01*
G01X879146Y1671181D02*
X879084Y1671294D01*
G01X879185Y1671048D02*
X879146Y1671181D01*
G01X879199Y1670900D02*
X879185Y1671048D01*
G01X893313Y1671180D02*
X893251Y1671294D01*
G01X893352Y1671048D02*
X893313Y1671180D01*
G01X893366Y1670900D02*
X893352Y1671048D01*
G01X855391Y1681686D02*
X855388Y1681890D01*
G01X855400Y1681485D02*
X855391Y1681686D01*
G01X855416Y1681299D02*
X855400Y1681485D01*
G01X869564Y1681686D02*
X869561Y1681890D01*
G01X869574Y1681485D02*
X869564Y1681686D01*
G01X869589Y1681299D02*
X869574Y1681485D01*
G01X855877Y1681685D02*
X855874Y1681890D01*
G01X855887Y1681486D02*
X855877Y1681685D01*
G01X855902Y1681299D02*
X855887Y1681486D01*
G01X870050Y1681685D02*
X870047Y1681890D01*
G01X870060Y1681486D02*
X870050Y1681685D01*
G01X870075Y1681299D02*
X870060Y1681486D01*
G01X891304Y1681685D02*
X891301Y1681890D01*
G01X891313Y1681486D02*
X891304Y1681685D01*
G01X891329Y1681299D02*
X891313Y1681486D01*
G01X858289Y1680758D02*
X858470Y1680709D01*
G01X858149Y1680889D02*
X858289Y1680758D01*
G01X858065Y1681078D02*
X858149Y1680889D01*
G01X858051Y1681299D02*
X858065Y1681078D01*
G01X872463Y1680758D02*
X872643Y1680709D01*
G01X872322Y1680889D02*
X872463Y1680758D01*
G01X872239Y1681078D02*
X872322Y1680889D01*
G01X872224Y1681299D02*
X872239Y1681078D01*
G01X893716Y1680758D02*
X893897Y1680709D01*
G01X893576Y1680889D02*
X893716Y1680758D01*
G01X893492Y1681078D02*
X893576Y1680889D01*
G01X893478Y1681299D02*
X893492Y1681078D01*
G01X894202Y1680759D02*
X894383Y1680709D01*
G01X894062Y1680889D02*
X894202Y1680759D01*
G01X893978Y1681079D02*
X894062Y1680889D01*
G01X893964Y1681299D02*
X893978Y1681079D01*
G01X869399Y1681343D02*
X869439Y1681299D01*
G01X869365Y1681474D02*
X869399Y1681343D01*
G01X869342Y1681669D02*
X869365Y1681474D01*
G01X869335Y1681890D02*
X869342Y1681669D01*
G01X890653Y1681343D02*
X890692Y1681299D01*
G01X890619Y1681474D02*
X890653Y1681343D01*
G01X890596Y1681669D02*
X890619Y1681474D01*
G01X890588Y1681890D02*
X890596Y1681669D01*
G01X890827Y1681486D02*
X890843Y1681299D01*
G01X890818Y1681685D02*
X890827Y1681486D01*
G01X890815Y1681890D02*
X890818Y1681685D01*
G01X890620Y1680767D02*
X890652Y1680709D01*
G01X890591Y1680935D02*
X890620Y1680767D01*
G01X890568Y1681196D02*
X890591Y1680935D01*
G01X890554Y1681525D02*
X890568Y1681196D01*
G01X890548Y1681890D02*
X890554Y1681525D01*
G01X894039Y1680720D02*
X894154Y1680709D01*
G01X893930Y1680754D02*
X894039Y1680720D01*
G01X893830Y1680808D02*
X893930Y1680754D01*
G01X893743Y1680881D02*
X893830Y1680808D01*
G01X893669Y1680972D02*
X893743Y1680881D01*
G01X893616Y1681074D02*
X893669Y1680972D01*
G01X893583Y1681184D02*
X893616Y1681074D01*
G01X893572Y1681299D02*
X893583Y1681184D01*
G01X889846Y1670723D02*
X889921Y1670709D01*
G01X889782Y1670766D02*
X889846Y1670723D01*
G01X889740Y1670829D02*
X889782Y1670766D01*
G01X889724Y1670906D02*
X889740Y1670829D01*
G01X850605Y1672795D02*
X850459Y1672835D01*
G01X850733Y1672678D02*
X850605Y1672795D01*
G01X850820Y1672500D02*
X850733Y1672678D01*
G01X850853Y1672278D02*
X850820Y1672500D01*
G01X857692Y1672795D02*
X857546Y1672835D01*
G01X857820Y1672678D02*
X857692Y1672795D01*
G01X857907Y1672500D02*
X857820Y1672678D01*
G01X857939Y1672278D02*
X857907Y1672500D01*
G01X864778Y1672795D02*
X864632Y1672835D01*
G01X864906Y1672678D02*
X864778Y1672795D01*
G01X864993Y1672500D02*
X864906Y1672678D01*
G01X865026Y1672278D02*
X864993Y1672500D01*
G01X871865Y1672795D02*
X871719Y1672835D01*
G01X871993Y1672678D02*
X871865Y1672795D01*
G01X872080Y1672500D02*
X871993Y1672678D01*
G01X872113Y1672278D02*
X872080Y1672500D01*
G01X878952Y1672795D02*
X878806Y1672835D01*
G01X879080Y1672678D02*
X878952Y1672795D01*
G01X879167Y1672500D02*
X879080Y1672678D01*
G01X879199Y1672278D02*
X879167Y1672500D01*
G01X854585Y1681526D02*
X854580Y1681890D01*
G01X854600Y1681197D02*
X854585Y1681526D01*
G01X854623Y1680935D02*
X854600Y1681197D01*
G01X854652Y1680767D02*
X854623Y1680935D01*
G01X854684Y1680709D02*
X854652Y1680767D01*
G01X868758Y1681526D02*
X868753Y1681890D01*
G01X868773Y1681197D02*
X868758Y1681526D01*
G01X868796Y1680935D02*
X868773Y1681197D01*
G01X868825Y1680767D02*
X868796Y1680935D01*
G01X868857Y1680709D02*
X868825Y1680767D01*
G01X890012Y1681526D02*
X890007Y1681890D01*
G01X890026Y1681197D02*
X890012Y1681526D01*
G01X890049Y1680935D02*
X890026Y1681197D01*
G01X890078Y1680767D02*
X890049Y1680935D01*
G01X890111Y1680709D02*
X890078Y1680767D01*
G01X847269Y1670767D02*
X847333Y1670724D01*
G01X847226Y1670829D02*
X847269Y1670767D01*
G01X854355D02*
X854419Y1670724D01*
G01X854313Y1670829D02*
X854355Y1670767D01*
G01X861442D02*
X861506Y1670724D01*
G01X861400Y1670829D02*
X861442Y1670767D01*
G01X868528D02*
X868593Y1670724D01*
G01X868486Y1670829D02*
X868528Y1670767D01*
G01X875615D02*
X875679Y1670724D01*
G01X875573Y1670829D02*
X875615Y1670767D01*
G01X894125Y1711582D02*
X894002Y1711778D01*
G01X894258Y1711359D02*
X894125Y1711582D01*
G01X855711Y1681670D02*
X855703Y1681890D01*
G01X855733Y1681475D02*
X855711Y1681670D01*
G01X855768Y1681344D02*
X855733Y1681475D01*
G01X855807Y1681299D02*
X855768Y1681344D01*
G01X869884Y1681670D02*
X869876Y1681890D01*
G01X869907Y1681475D02*
X869884Y1681670D01*
G01X869941Y1681344D02*
X869907Y1681475D01*
G01X869981Y1681299D02*
X869941Y1681344D01*
G01X891137Y1681670D02*
X891130Y1681890D01*
G01X891160Y1681474D02*
X891137Y1681670D01*
G01X891194Y1681343D02*
X891160Y1681474D01*
G01X891234Y1681299D02*
X891194Y1681343D01*
G01X850563Y1671488D02*
X850459Y1671572D01*
G01X850657Y1671394D02*
X850563Y1671488D01*
G01X850737Y1671294D02*
X850657Y1671394D01*
G01X857650Y1671488D02*
X857546Y1671572D01*
G01X857744Y1671394D02*
X857650Y1671488D01*
G01X857824Y1671294D02*
X857744Y1671394D01*
G01X864737Y1671488D02*
X864632Y1671572D01*
G01X864831Y1671394D02*
X864737Y1671488D01*
G01X864911Y1671294D02*
X864831Y1671394D01*
G01X871823Y1671488D02*
X871719Y1671572D01*
G01X871917Y1671394D02*
X871823Y1671488D01*
G01X871997Y1671294D02*
X871917Y1671394D01*
G01X878910Y1671488D02*
X878806Y1671572D01*
G01X879004Y1671394D02*
X878910Y1671488D01*
G01X879084Y1671294D02*
X879004Y1671394D01*
G01X893077Y1671488D02*
X892972Y1671572D01*
G01X893171Y1671394D02*
X893077Y1671488D01*
G01X893251Y1671294D02*
X893171Y1671394D01*
G01X859240Y1711006D02*
X859373Y1710783D01*
G01X859117Y1711202D02*
X859240Y1711006D01*
G01X859006Y1711370D02*
X859117Y1711202D01*
G01X858910Y1711506D02*
X859006Y1711370D01*
G01X858835Y1711597D02*
X858910Y1711506D01*
G01X858791Y1711628D02*
X858835Y1711597D01*
G01X873413Y1711006D02*
X873546Y1710783D01*
G01X873290Y1711202D02*
X873413Y1711006D01*
G01X873180Y1711370D02*
X873290Y1711202D01*
G01X873083Y1711506D02*
X873180Y1711370D01*
G01X873008Y1711597D02*
X873083Y1711506D01*
G01X872965Y1711628D02*
X873008Y1711597D01*
G01X894544Y1711202D02*
X894667Y1711006D01*
G01X894433Y1711370D02*
X894544Y1711202D01*
G01X894337Y1711506D02*
X894433Y1711370D01*
G01X894261Y1711596D02*
X894337Y1711506D01*
G01X858698Y1711582D02*
X858831Y1711359D01*
G01X858576Y1711778D02*
X858698Y1711582D01*
G01X872872D02*
X873004Y1711359D01*
G01X872749Y1711778D02*
X872872Y1711582D01*
G01X891314Y1681078D02*
X891329Y1681299D01*
G01X891230Y1680889D02*
X891314Y1681078D01*
G01X891090Y1680758D02*
X891230Y1680889D01*
G01X890909Y1680709D02*
X891090Y1680758D01*
G01X889640Y1672427D02*
X889626Y1672278D01*
G01X889678Y1672554D02*
X889640Y1672427D01*
G01X889731Y1672657D02*
X889678Y1672554D01*
G01X889796Y1672736D02*
X889731Y1672657D01*
G01X889868Y1672792D02*
X889796Y1672736D01*
G01X889944Y1672824D02*
X889868Y1672792D01*
G01X890020Y1672835D02*
X889944Y1672824D01*
G01X875473Y1672427D02*
X875459Y1672278D01*
G01X875511Y1672554D02*
X875473Y1672427D01*
G01X875565Y1672657D02*
X875511Y1672554D01*
G01X875630Y1672737D02*
X875565Y1672657D01*
G01X875702Y1672792D02*
X875630Y1672737D01*
G01X875777Y1672824D02*
X875702Y1672792D01*
G01X875853Y1672835D02*
X875777Y1672824D01*
G01X868387Y1672427D02*
X868372Y1672278D01*
G01X868424Y1672554D02*
X868387Y1672427D01*
G01X868478Y1672657D02*
X868424Y1672554D01*
G01X868543Y1672737D02*
X868478Y1672657D01*
G01X868615Y1672792D02*
X868543Y1672737D01*
G01X868691Y1672824D02*
X868615Y1672792D01*
G01X868766Y1672835D02*
X868691Y1672824D01*
G01X861300Y1672427D02*
X861286Y1672278D01*
G01X861337Y1672554D02*
X861300Y1672427D01*
G01X861391Y1672657D02*
X861337Y1672554D01*
G01X861456Y1672737D02*
X861391Y1672657D01*
G01X861528Y1672792D02*
X861456Y1672737D01*
G01X861604Y1672824D02*
X861528Y1672792D01*
G01X861680Y1672835D02*
X861604Y1672824D01*
G01X854213Y1672427D02*
X854199Y1672278D01*
G01X854251Y1672554D02*
X854213Y1672427D01*
G01X854305Y1672657D02*
X854251Y1672554D01*
G01X854370Y1672737D02*
X854305Y1672657D01*
G01X854442Y1672792D02*
X854370Y1672737D01*
G01X854517Y1672824D02*
X854442Y1672792D01*
G01X854593Y1672835D02*
X854517Y1672824D01*
G01X847127Y1672427D02*
X847113Y1672278D01*
G01X847164Y1672554D02*
X847127Y1672427D01*
G01X847218Y1672657D02*
X847164Y1672554D01*
G01X847283Y1672737D02*
X847218Y1672657D01*
G01X847355Y1672792D02*
X847283Y1672737D01*
G01X847431Y1672824D02*
X847355Y1672792D01*
G01X847506Y1672835D02*
X847431Y1672824D01*
G01X891222Y1681182D02*
X891234Y1681299D01*
G01X891189Y1681072D02*
X891222Y1681182D01*
G01X891136Y1680970D02*
X891189Y1681072D01*
G01X891064Y1680881D02*
X891136Y1680970D01*
G01X890974Y1680807D02*
X891064Y1680881D01*
G01X890874Y1680753D02*
X890974Y1680807D01*
G01X890765Y1680720D02*
X890874Y1680753D01*
G01X890652Y1680709D02*
X890765Y1680720D01*
G01X869969Y1681183D02*
X869981Y1681299D01*
G01X869936Y1681072D02*
X869969Y1681183D01*
G01X869882Y1680971D02*
X869936Y1681072D01*
G01X869810Y1680882D02*
X869882Y1680971D01*
G01X869721Y1680807D02*
X869810Y1680882D01*
G01X869620Y1680754D02*
X869721Y1680807D01*
G01X869512Y1680720D02*
X869620Y1680754D01*
G01X869399Y1680709D02*
X869512Y1680720D01*
G01X855796Y1681183D02*
X855807Y1681299D01*
G01X855763Y1681072D02*
X855796Y1681183D01*
G01X855709Y1680971D02*
X855763Y1681072D01*
G01X855637Y1680882D02*
X855709Y1680971D01*
G01X855548Y1680807D02*
X855637Y1680882D01*
G01X855447Y1680754D02*
X855548Y1680807D01*
G01X855339Y1680720D02*
X855447Y1680754D01*
G01X855226Y1680709D02*
X855339Y1680720D01*
G01X858699Y1681183D02*
X858687Y1681299D01*
G01X858732Y1681072D02*
X858699Y1681183D01*
G01X858785Y1680971D02*
X858732Y1681072D01*
G01X858857Y1680882D02*
X858785Y1680971D01*
G01X858947Y1680807D02*
X858857Y1680882D01*
G01X859047Y1680754D02*
X858947Y1680807D01*
G01X859156Y1680720D02*
X859047Y1680754D01*
G01X859269Y1680709D02*
X859156Y1680720D01*
G01X872872Y1681183D02*
X872860Y1681299D01*
G01X872905Y1681072D02*
X872872Y1681183D01*
G01X872959Y1680971D02*
X872905Y1681072D01*
G01X873031Y1680882D02*
X872959Y1680971D01*
G01X873120Y1680807D02*
X873031Y1680882D01*
G01X873220Y1680754D02*
X873120Y1680807D01*
G01X873329Y1680720D02*
X873220Y1680754D01*
G01X873442Y1680709D02*
X873329Y1680720D01*
G01X894125Y1681182D02*
X894114Y1681299D01*
G01X894159Y1681072D02*
X894125Y1681182D01*
G01X894212Y1680970D02*
X894159Y1681072D01*
G01X894284Y1680881D02*
X894212Y1680970D01*
G01X894374Y1680807D02*
X894284Y1680881D01*
G01X894474Y1680753D02*
X894374Y1680807D01*
G01X894583Y1680720D02*
X894474Y1680753D01*
G01X850839Y1672427D02*
X850853Y1672278D01*
G01X850801Y1672554D02*
X850839Y1672427D01*
G01X850747Y1672657D02*
X850801Y1672554D01*
G01X850682Y1672737D02*
X850747Y1672657D01*
G01X850611Y1672792D02*
X850682Y1672737D01*
G01X850535Y1672824D02*
X850611Y1672792D01*
G01X850459Y1672835D02*
X850535Y1672824D01*
G01X857925Y1672427D02*
X857939Y1672278D01*
G01X857888Y1672554D02*
X857925Y1672427D01*
G01X857834Y1672657D02*
X857888Y1672554D01*
G01X857769Y1672737D02*
X857834Y1672657D01*
G01X857697Y1672792D02*
X857769Y1672737D01*
G01X857621Y1672824D02*
X857697Y1672792D01*
G01X857546Y1672835D02*
X857621Y1672824D01*
G01X865012Y1672427D02*
X865026Y1672278D01*
G01X864974Y1672554D02*
X865012Y1672427D01*
G01X864920Y1672657D02*
X864974Y1672554D01*
G01X864856Y1672737D02*
X864920Y1672657D01*
G01X864784Y1672792D02*
X864856Y1672737D01*
G01X864708Y1672824D02*
X864784Y1672792D01*
G01X864632Y1672835D02*
X864708Y1672824D01*
G01X872098Y1672427D02*
X872113Y1672278D01*
G01X872061Y1672554D02*
X872098Y1672427D01*
G01X872007Y1672657D02*
X872061Y1672554D01*
G01X871942Y1672737D02*
X872007Y1672657D01*
G01X871870Y1672792D02*
X871942Y1672737D01*
G01X871794Y1672824D02*
X871870Y1672792D01*
G01X871719Y1672835D02*
X871794Y1672824D01*
G01X879185Y1672427D02*
X879199Y1672278D01*
G01X879148Y1672554D02*
X879185Y1672427D01*
G01X879094Y1672657D02*
X879148Y1672554D01*
G01X879029Y1672737D02*
X879094Y1672657D01*
G01X878957Y1672792D02*
X879029Y1672737D01*
G01X878881Y1672824D02*
X878957Y1672792D01*
G01X878806Y1672835D02*
X878881Y1672824D01*
G01X847332Y1670724D02*
X847269Y1670767D01*
G01X847408Y1670709D02*
X847332Y1670724D01*
G01X854419D02*
X854355Y1670767D01*
G01X854494Y1670709D02*
X854419Y1670724D01*
G01X861506D02*
X861442Y1670767D01*
G01X861581Y1670709D02*
X861506Y1670724D01*
G01X868592D02*
X868528Y1670767D01*
G01X868668Y1670709D02*
X868592Y1670724D01*
G01X875679D02*
X875615Y1670767D01*
G01X875754Y1670709D02*
X875679Y1670724D01*
G01X858552Y1681078D02*
X858537Y1681299D01*
G01X858636Y1680889D02*
X858552Y1681078D01*
G01X858776Y1680758D02*
X858636Y1680889D01*
G01X858956Y1680709D02*
X858776Y1680758D01*
G01X872725Y1681078D02*
X872710Y1681299D01*
G01X872809Y1680889D02*
X872725Y1681078D01*
G01X872949Y1680758D02*
X872809Y1680889D01*
G01X873130Y1680709D02*
X872949Y1680758D01*
G01X891496Y1673819D02*
G03X890118Y1672441I0J-1378D01*
G01Y1669291D02*
G03X891496Y1667913I1378J0D01*
G01X878707Y1672441D02*
G03X877329Y1673819I-1378J0D01*
G01Y1667913D02*
G03X878707Y1669291I0J1378D01*
G01X870243Y1673819D02*
G03X868865Y1672441I0J-1378D01*
G01Y1669291D02*
G03X870243Y1667913I1378J0D01*
G01X856069Y1673819D02*
G03X854691Y1672441I0J-1378D01*
G01X864534D02*
G03X863156Y1673819I-1378J0D01*
G01Y1667913D02*
G03X864534Y1669291I0J1378D01*
G01X854691D02*
G03X856069Y1667913I1378J0D01*
G01X850361Y1672441D02*
G03X848983Y1673819I-1378J0D01*
G01Y1667913D02*
G03X850361Y1669291I0J1378D01*
G01X857904Y1707244D02*
X856048D01*
G01X872078D02*
X870222D01*
G01X893331D02*
X891475D01*
G01X869899Y1706457D02*
X872400D01*
G01X855726D02*
X858227D01*
G01X891152D02*
X893654D01*
G01X891444Y1705906D02*
X890027D01*
G01X869422Y1705880D02*
X869561D01*
G01X855249D02*
X855388D01*
G01X858704D02*
X858565D01*
G01X872877D02*
X872738D01*
G01X890676D02*
X890815D01*
G01X894130D02*
X893992D01*
G01X891444Y1701181D02*
X890027D01*
G01X893048Y1672824D02*
X892972Y1672835D01*
G01X851084Y1688780D02*
X847147D01*
G01X865257D02*
X861320D01*
G01X879430D02*
X875493D01*
G01X866379Y1688583D02*
X868007D01*
G01X852206D02*
X853833D01*
G01X888543D02*
X889260D01*
G01X853833Y1688249D02*
X852206D01*
G01X868007D02*
X866379D01*
G01X889260D02*
X888543D01*
G01X875493Y1688234D02*
X879430D01*
G01X861320D02*
X865257D01*
G01X847147D02*
X851084D01*
G01X866379Y1687851D02*
X868007D01*
G01X852206D02*
X853833D01*
G01X888543D02*
X889260D01*
G01X851084Y1687791D02*
X847147D01*
G01X865257D02*
X861320D01*
G01X879430D02*
X875493D01*
G01X888543Y1681890D02*
X916890D01*
G01X872224Y1681299D02*
X872319D01*
G01X869981D02*
X870075D01*
G01X858051D02*
X858145D01*
G01X855807D02*
X855902D01*
G01X858687D02*
X858537D01*
G01X855416D02*
X855266D01*
G01X872860D02*
X872710D01*
G01X869589D02*
X869439D01*
G01X893478D02*
X893572D01*
G01X891234D02*
X891329D01*
G01X890843D02*
X890692D01*
G01X894114D02*
X893964D01*
G01X866379Y1681197D02*
X868007D01*
G01X852206D02*
X853833D01*
G01X851084D02*
X847147D01*
G01X865257D02*
X861320D01*
G01X879430D02*
X875493D01*
G01X888543Y1681196D02*
X889260D01*
G01X888543Y1680709D02*
X916890D01*
G01X875860Y1676280D02*
X877277D01*
G01X861687D02*
X863104D01*
G01X847513D02*
X848931D01*
G01Y1676181D02*
X847513D01*
G01X863104D02*
X861687D01*
G01X877277D02*
X875860D01*
G01X849226Y1675984D02*
X847218D01*
G01X863399D02*
X861391D01*
G01X877572D02*
X875565D01*
G01X888543D02*
X887920D01*
G01X888543Y1674803D02*
X887920D01*
G01X863156Y1673819D02*
X856069D01*
G01X877329D02*
X870243D01*
G01X898583D02*
X891496D01*
G01X850459Y1672835D02*
X847506D01*
G01X857546D02*
X854593D01*
G01X864632D02*
X861680D01*
G01X871719D02*
X868766D01*
G01X878806D02*
X875853D01*
G01X892972D02*
X890020D01*
G01X850754Y1672008D02*
X847211D01*
G01X857841D02*
X854298D01*
G01X864928D02*
X861384D01*
G01X872014D02*
X868471D01*
G01X879101D02*
X875557D01*
G01X893268D02*
X889724D01*
G01X850459Y1671572D02*
X847506D01*
G01X857546D02*
X854593D01*
G01X864632D02*
X861680D01*
G01X871719D02*
X868766D01*
G01X878806D02*
X875853D01*
G01X892972D02*
X890020D01*
G01X850737Y1671294D02*
X847228D01*
G01X857824D02*
X854315D01*
G01X864911D02*
X861401D01*
G01X871997D02*
X868488D01*
G01X879084D02*
X875574D01*
G01X893251D02*
X889741D01*
G01X850557Y1670709D02*
X847408D01*
G01X857644D02*
X854494D01*
G01X864731D02*
X861581D01*
G01X871817D02*
X868668D01*
G01X878904D02*
X875754D01*
G01X893071D02*
X889921D01*
G01X863156Y1667913D02*
X856069D01*
G01X877329D02*
X870243D01*
G01X898583D02*
X891496D01*
G01X850262Y1665551D02*
X847703D01*
G01X857349D02*
X854790D01*
G01X864435D02*
X861876D01*
G01X871522D02*
X868963D01*
G01X878609D02*
X876050D01*
G01X892776D02*
X890217D01*
G01X850164Y1665354D02*
X847802D01*
G01X857250D02*
X854888D01*
G01X864337D02*
X861975D01*
G01X871424D02*
X869061D01*
G01X878510D02*
X876148D01*
G01X892677D02*
X890315D01*
G01X893048Y1672824D02*
X893124Y1672792D01*
G01X877572Y1675984D02*
X877277Y1676280D01*
G01Y1676181D02*
X877474Y1675984D01*
G01X863399D02*
X863104Y1676280D01*
G01Y1676181D02*
X863301Y1675984D01*
G01X893171Y1671394D02*
X893251Y1671294D01*
G01X879004Y1671394D02*
X879084Y1671294D01*
G01X871917Y1671394D02*
X871997Y1671294D01*
G01X864831Y1671394D02*
X864911Y1671294D01*
G01X857744Y1671394D02*
X857824Y1671294D01*
G01X850657Y1671394D02*
X850737Y1671294D01*
G01X849226Y1675984D02*
X848931Y1676280D01*
G01Y1676181D02*
X849128Y1675984D01*
G01X893504Y1712992D02*
X894800Y1710783D01*
G01X894258Y1711359D02*
X893301Y1712992D01*
G01X894130Y1705880D02*
X893331Y1707244D01*
G01X893654Y1706457D02*
X893992Y1705880D01*
G01X872251Y1712992D02*
X873546Y1710783D01*
G01X873004Y1711359D02*
X872047Y1712992D01*
G01X872877Y1705880D02*
X872078Y1707244D01*
G01X872738Y1705880D02*
X872400Y1706457D01*
G01X858078Y1712992D02*
X859373Y1710783D01*
G01X858831Y1711359D02*
X857874Y1712992D01*
G01X858704Y1705880D02*
X857904Y1707244D01*
G01X858565Y1705880D02*
X858227Y1706457D01*
G01X893470Y1712992D02*
X894130Y1711628D01*
G01X893272Y1707244D02*
X893654Y1706457D01*
G01X872877Y1711628D02*
X872217Y1712992D01*
G01X872019Y1707244D02*
X872400Y1706457D01*
G01X858704Y1711628D02*
X858043Y1712992D01*
G01X857846Y1707244D02*
X858227Y1706457D01*
G01X875557Y1670906D02*
X875573Y1670829D01*
G01X868471Y1670906D02*
X868486Y1670829D01*
G01X861384Y1670906D02*
X861400Y1670829D01*
G01X854298Y1670906D02*
X854313Y1670829D01*
G01X847211Y1670906D02*
X847226Y1670829D01*
G01X894258Y1711359D02*
Y1681890D01*
G01X894218Y1711628D02*
Y1681890D01*
G01X894130Y1711628D02*
Y1705880D01*
G01X893992D02*
Y1681890D01*
G01X893676D02*
Y1712205D01*
G01X893506D02*
Y1681890D01*
G01X892972Y1672835D02*
Y1671572D01*
G01X891444Y1680709D02*
Y1705906D01*
G01X891301Y1712205D02*
Y1681890D01*
G01X891130Y1712205D02*
Y1681890D01*
G01X890815Y1705880D02*
Y1681890D01*
G01X890676Y1705880D02*
Y1711628D01*
G01X890588Y1681890D02*
Y1711628D01*
G01X890548Y1681890D02*
Y1711359D01*
G01X890118Y1672441D02*
Y1669291D01*
G01X890027Y1705906D02*
Y1680709D01*
G01X890020Y1672835D02*
Y1671572D01*
G01X890007Y1710783D02*
Y1681890D01*
G01X889260Y1688583D02*
Y1680709D01*
G01X879430Y1688780D02*
Y1680709D01*
G01X878806Y1672835D02*
Y1671572D01*
G01X878707Y1672441D02*
Y1669291D01*
G01X875853Y1672835D02*
Y1671572D01*
G01X875493Y1688780D02*
Y1680709D01*
G01X873546Y1681890D02*
Y1710783D01*
G01X873004Y1711359D02*
Y1681890D01*
G01X872965Y1711628D02*
Y1681890D01*
G01X872877Y1711628D02*
Y1705880D01*
G01X872738D02*
Y1681890D01*
G01X872423D02*
Y1712205D01*
G01X872252D02*
Y1681890D01*
G01X871719Y1672835D02*
Y1671572D01*
G01X870047Y1681890D02*
Y1712205D01*
G01X869876D02*
Y1681890D01*
G01X869561Y1705880D02*
Y1681890D01*
G01X869422Y1705880D02*
Y1711628D01*
G01X869335Y1681890D02*
Y1711628D01*
G01X869295Y1681890D02*
Y1711359D01*
G01X868865Y1672441D02*
Y1669291D01*
G01X868766Y1672835D02*
Y1671572D01*
G01X868753Y1710783D02*
Y1681890D01*
G01X868007Y1688583D02*
Y1680709D01*
G01X866379Y1688583D02*
Y1680709D01*
G01X865257Y1688780D02*
Y1680709D01*
G01X864632Y1672835D02*
Y1671572D01*
G01X864534Y1672441D02*
Y1669291D01*
G01X861680Y1672835D02*
Y1671572D01*
G01X861320Y1688780D02*
Y1680709D01*
G01X859373Y1681890D02*
Y1710783D01*
G01X858831Y1711359D02*
Y1681890D01*
G01X858791Y1711628D02*
Y1681890D01*
G01X858704Y1711628D02*
Y1705880D01*
G01X858565D02*
Y1681890D01*
G01X858250D02*
Y1712205D01*
G01X858079D02*
Y1681890D01*
G01X857546Y1672835D02*
Y1671572D01*
G01X855874Y1681890D02*
Y1712205D01*
G01X855703D02*
Y1681890D01*
G01X855388Y1705880D02*
Y1681890D01*
G01X855249Y1705880D02*
Y1711628D01*
G01X855161Y1681890D02*
Y1711628D01*
G01X855122Y1681890D02*
Y1711359D01*
G01X854691Y1672441D02*
Y1669291D01*
G01X854593Y1672835D02*
Y1671572D01*
G01X854580Y1710783D02*
Y1681890D01*
G01X853833Y1688583D02*
Y1680709D01*
G01X852206Y1688583D02*
Y1680709D01*
G01X851084Y1688780D02*
Y1680709D01*
G01X850459Y1672835D02*
Y1671572D01*
G01X850361Y1672441D02*
Y1669291D01*
G01X847506Y1672835D02*
Y1671572D01*
G01X847147Y1688780D02*
Y1680709D01*
G01X879085Y1670829D02*
X879101Y1670906D01*
G01X871999Y1670829D02*
X872014Y1670906D01*
G01X864912Y1670829D02*
X864928Y1670906D01*
G01X857826Y1670829D02*
X857841Y1670906D01*
G01X850739Y1670829D02*
X850754Y1670906D01*
G01X891152Y1706457D02*
X891534Y1707244D01*
G01X890676Y1711628D02*
X891336Y1712992D01*
G01X869899Y1706457D02*
X870280Y1707244D01*
G01X869422Y1711628D02*
X870083Y1712992D01*
G01X855726Y1706457D02*
X856107Y1707244D01*
G01X855249Y1711628D02*
X855910Y1712992D01*
G01X891152Y1706457D02*
X890815Y1705880D01*
G01X891475Y1707244D02*
X890676Y1705880D01*
G01X891506Y1712992D02*
X890548Y1711359D01*
G01X890007Y1710783D02*
X891302Y1712992D01*
G01X869899Y1706457D02*
X869561Y1705880D01*
G01X870222Y1707244D02*
X869422Y1705880D01*
G01X870252Y1712992D02*
X869295Y1711359D01*
G01X868753Y1710783D02*
X870048Y1712992D01*
G01X855726Y1706457D02*
X855388Y1705880D01*
G01X856048Y1707244D02*
X855249Y1705880D01*
G01X856079Y1712992D02*
X855122Y1711359D01*
G01X854580Y1710783D02*
X855875Y1712992D01*
G01X875663Y1675984D02*
X875860Y1676181D01*
G01Y1676280D02*
X875565Y1675984D01*
G01X878980Y1670724D02*
X879044Y1670767D01*
G01X871893Y1670724D02*
X871957Y1670767D01*
G01X864806Y1670724D02*
X864870Y1670767D01*
G01X861490Y1675984D02*
X861687Y1676181D01*
G01Y1676280D02*
X861391Y1675984D01*
G01X847317D02*
X847513Y1676181D01*
G01Y1676280D02*
X847218Y1675984D01*
G01X857720Y1670724D02*
X857784Y1670767D01*
G01X850633Y1670724D02*
X850697Y1670767D01*
G01X855489Y1711947D02*
X855378Y1711778D01*
G01X855585Y1712082D02*
X855489Y1711947D01*
G01X855660Y1712173D02*
X855585Y1712082D01*
G01X855703Y1712205D02*
X855660Y1712173D01*
G01X869662Y1711947D02*
X869551Y1711778D01*
G01X869758Y1712082D02*
X869662Y1711947D01*
G01X869833Y1712173D02*
X869758Y1712082D01*
G01X869876Y1712205D02*
X869833Y1712173D01*
G01X890915Y1711946D02*
X890804Y1711778D01*
G01X891011Y1712082D02*
X890915Y1711946D01*
G01X891087Y1712173D02*
X891011Y1712082D01*
G01X891130Y1712205D02*
X891087Y1712173D01*
G01X893720D02*
X893676Y1712205D01*
G01X893795Y1712082D02*
X893720Y1712173D01*
G01X893891Y1711946D02*
X893795Y1712082D01*
G01X894002Y1711778D02*
X893891Y1711946D01*
G01X894218Y1711628D02*
X894261Y1711596D01*
G01X858465Y1711946D02*
X858576Y1711778D01*
G01X858369Y1712082D02*
X858465Y1711946D01*
G01X858293Y1712173D02*
X858369Y1712082D01*
G01X858250Y1712205D02*
X858293Y1712173D01*
G01X872638Y1711946D02*
X872749Y1711778D01*
G01X872542Y1712082D02*
X872638Y1711946D01*
G01X872466Y1712173D02*
X872542Y1712082D01*
G01X872423Y1712205D02*
X872466Y1712173D01*
G01X920827Y1718504D02*
X888543D01*
G01Y1714412D02*
X916890D01*
G01X858078Y1712992D02*
X855875D01*
G01X872251D02*
X870048D01*
G01X893504D02*
X891302D01*
G01X869876Y1712205D02*
X872423D01*
G01X855703D02*
X858250D01*
G01X891130D02*
X893676D01*
G01X869335Y1711628D02*
X872965D01*
G01X855161D02*
X858791D01*
G01X890588D02*
X894218D01*
G01X893124Y1712992D02*
X893506Y1712205D01*
G01X872252D02*
X871870Y1712992D01*
G01X858079Y1712205D02*
X857697Y1712992D01*
G01X880289Y1718504D02*
Y1714413D01*
G01X891301Y1712205D02*
X891682Y1712992D01*
G01X870429D02*
X870047Y1712205D01*
G01X856256Y1712992D02*
X855874Y1712205D01*
G01X934154Y-124016D02*
G03X936122Y-125984I1968J0D01*
G01D02*
X951870D01*
G01X927032Y-57821D02*
G03X962732I17850J-12258D01*
G01X935531Y-111220D02*
G03X934941Y-111811I1J-591D01*
G01Y-118504D02*
G03X935531Y-119094I590J0D01*
G01X936713Y-116339D02*
G03X938681I984J1D01*
G01Y-113976D02*
G03X936713I-984J0D01*
G01X936122Y-104331D02*
G03X934154Y-106299I0J-1968D01*
G01X927032Y-57820D02*
G03X962731I17850J-12259D01*
G01X941634Y-119094D02*
Y-111220D01*
G01X940059D02*
Y-119094D01*
G01X938681Y-116339D02*
Y-113976D01*
G01X936713D02*
Y-116339D01*
G01X934941Y-118504D02*
Y-111811D01*
G01X934154Y-106299D02*
Y-124016D01*
G01X951870Y-104331D02*
X936122D01*
G01X941634Y-111220D02*
X935531D01*
G01X941634Y-119094D02*
X935531D01*
G01X954564Y-42571D02*
G03X935199I-9682J-3885D01*
G01X927032Y-57821D02*
G03X935199Y-42571I-64909J44573D01*
G01X896654Y-29528D02*
Y-21654D01*
G01Y-29528D02*
G03X913189I8268J0D01*
G01Y-21654D02*
Y-29528D01*
G01X896654D02*
G03X913189I8268J1D01*
G01X954565Y-42571D02*
G03X935199I-9683J-3885D01*
G01X927032Y-57820D02*
G03X935199Y-42571I-64908J44575D01*
G01X913189Y-21654D02*
Y-29528D01*
G01X896654Y-21654D02*
Y-29528D01*
G01X913189Y-21654D02*
G03X896654I-8268J0D01*
G01X913189D02*
G03X896654I-8268J1D01*
G01Y564961D02*
G03X913189I8268J0D01*
G01D02*
G03X896654I-8268J0D01*
G01X913189D02*
G03I-8268J0D01*
G01X944512Y1089121D02*
G03X978323I16905J-13531D01*
G01X944512Y1089122D02*
G03X978323I16905J-13531D01*
G01X944512Y1431641D02*
G03X978323I16905J-13531D01*
G01X944512D02*
G03X978323I16905J-13531D01*
G01X896887Y1591617D02*
X897144Y1591929D01*
G01X896739Y1591248D02*
X896887Y1591617D01*
G01X903974D02*
X904231Y1591929D01*
G01X903826Y1591248D02*
X903974Y1591617D01*
G01X911060D02*
X911317Y1591929D01*
G01X910912Y1591248D02*
X911060Y1591617D01*
G01X896717Y1591128D02*
X896709Y1591001D01*
G01X896739Y1591255D02*
X896717Y1591128D01*
G01X903804D02*
X903796Y1591001D01*
G01X903826Y1591255D02*
X903804Y1591128D01*
G01X910890D02*
X910883Y1591001D01*
G01X910912Y1591255D02*
X910890Y1591128D01*
G01X896918Y1591536D02*
X897144Y1591929D01*
G01X896765Y1591060D02*
X896918Y1591536D01*
G01X896709Y1590537D02*
X896765Y1591060D01*
G01X904005Y1591536D02*
X904231Y1591929D01*
G01X903852Y1591060D02*
X904005Y1591536D01*
G01X903796Y1590537D02*
X903852Y1591060D01*
G01X911091Y1591536D02*
X911317Y1591929D01*
G01X910938Y1591060D02*
X911091Y1591536D01*
G01X910883Y1590537D02*
X910938Y1591060D01*
G01X899832Y1591128D02*
X899810Y1591255D01*
G01X899839Y1591001D02*
X899832Y1591128D01*
G01X906919D02*
X906896Y1591255D01*
G01X906926Y1591001D02*
X906919Y1591128D01*
G01X914005D02*
X913983Y1591255D01*
G01X914013Y1591001D02*
X914005Y1591128D01*
G01X899635Y1591527D02*
X899404Y1591929D01*
G01X899785Y1591055D02*
X899635Y1591527D01*
G01X899839Y1590537D02*
X899785Y1591055D01*
G01X906870Y1591059D02*
X906926Y1590537D01*
G01X906717Y1591535D02*
X906870Y1591059D01*
G01X906491Y1591929D02*
X906717Y1591535D01*
G01X913957Y1591059D02*
X914013Y1590537D01*
G01X913804Y1591535D02*
X913957Y1591059D01*
G01X913578Y1591929D02*
X913804Y1591535D01*
G01X899663Y1591614D02*
X899810Y1591248D01*
G01X899404Y1591929D02*
X899663Y1591614D01*
G01X906750D02*
X906896Y1591248D01*
G01X906491Y1591929D02*
X906750Y1591614D01*
G01X913837D02*
X913983Y1591248D01*
G01X913578Y1591929D02*
X913837Y1591614D01*
G01X912513Y1594094D02*
G03I-708J0D01*
G01X899404Y1591929D02*
G03X897144I-1130J-1083D01*
G01X906491D02*
G03X904231I-1130J-1083D01*
G01X913578D02*
G03X911317I-1131J-1082D01*
G01X914416Y1610157D02*
G03I-1968J0D01*
G01X907330D02*
G03I-1969J0D01*
G01X900243D02*
G03I-1969J0D01*
G01X913983Y1595728D02*
X915715D01*
G01X903826D02*
X899810D01*
G01X910912D02*
X906896D01*
G01X913578Y1591929D02*
X915430D01*
G01X906491D02*
X911317D01*
G01X899404D02*
X904231D01*
G01X905499Y1588780D02*
X904318D01*
G01X898413Y1588386D02*
X897231D01*
G01X912586D02*
X911405D01*
G01X899810Y1584449D02*
X896739D01*
G01X906896D02*
X903826D01*
G01X913983D02*
X910912D01*
G01X898629Y1583268D02*
X897920D01*
G01X905715D02*
X905007D01*
G01X912802D02*
X912093D01*
G01X910912Y1584449D02*
X912093Y1583268D01*
G01X903826Y1584449D02*
X905007Y1583268D01*
G01X896739Y1584449D02*
X897920Y1583268D01*
G01X915715Y1582283D02*
Y1660968D01*
G01X915430Y1626703D02*
Y1584843D01*
G01X914013Y1591001D02*
Y1584843D01*
G01X913983Y1595728D02*
Y1584449D01*
G01X912586Y1589685D02*
Y1588386D01*
G01X911405Y1589685D02*
Y1588386D01*
G01X910912Y1595728D02*
Y1584449D01*
G01X910883Y1591001D02*
Y1584843D01*
G01X906926Y1591001D02*
Y1584843D01*
G01X906896Y1595728D02*
Y1584449D01*
G01X905499Y1589685D02*
Y1588780D01*
G01X904318Y1589685D02*
Y1588780D01*
G01X903826Y1595728D02*
Y1584449D01*
G01X903796Y1591001D02*
Y1584843D01*
G01X899839Y1591001D02*
Y1584843D01*
G01X899810Y1595728D02*
Y1584449D01*
G01X898413Y1589685D02*
Y1588386D01*
G01X897231Y1589685D02*
Y1588386D01*
G01X896739Y1595728D02*
Y1584449D01*
G01X896709Y1591001D02*
Y1584843D01*
G01X913983Y1584449D02*
X912802Y1583268D01*
G01X906896Y1584449D02*
X905715Y1583268D01*
G01X899810Y1584449D02*
X898629Y1583268D01*
G01X915697Y1660873D02*
X915657Y1660780D01*
G01X915713Y1660984D02*
X915697Y1660873D01*
G01D02*
X915713Y1660984D01*
G01X915657Y1660780D02*
X915697Y1660873D01*
G01X915593Y1660715D02*
X915657Y1660780D01*
G01X915516Y1660690D02*
X915593Y1660715D01*
G01X915439Y1660710D02*
X915516Y1660690D01*
G01X915373Y1660771D02*
X915439Y1660710D01*
G01X912513Y1650787D02*
G03I-708J0D01*
G01X910912Y1644137D02*
G03Y1642357I1299J-890D01*
G01Y1636814D02*
G03Y1635034I1299J-890D01*
G01X913983D02*
G03Y1636814I-1299J890D01*
G01Y1642357D02*
G03Y1644137I-1299J890D01*
G01X906896Y1642357D02*
G03Y1644137I-1299J890D01*
G01Y1635034D02*
G03Y1636814I-1299J890D01*
G01X903826Y1644137D02*
G03Y1642357I1299J-890D01*
G01Y1636814D02*
G03Y1635034I1299J-890D01*
G01X896739Y1644137D02*
G03Y1642357I1299J-890D01*
G01Y1636814D02*
G03Y1635034I1299J-890D01*
G01X899810D02*
G03Y1636814I-1299J890D01*
G01Y1642357D02*
G03Y1644137I-1299J890D01*
G01X913826Y1625348D02*
G03X914810Y1626332I0J984D01*
G01X910085D02*
G03X911070Y1625348I984J0D01*
G01X902999Y1626332D02*
G03X903983Y1625348I984J0D01*
G01X906739D02*
G03X907723Y1626332I0J984D01*
G01X899652Y1625348D02*
G03X900637Y1626332I1J984D01*
G01X895912D02*
G03X896896Y1625348I984J0D01*
G01X912487Y1628278D02*
G03X912526I19J1564D01*
G01X910883Y1629843D02*
G03X912487Y1628278I1565J-1D01*
G01X903796Y1629843D02*
G03X906926I1565J0D01*
G01X896709D02*
G03X899839I1565J0D01*
G01X915430Y1626703D02*
G03X913855Y1628278I-1575J0D01*
G01X911575Y1662992D02*
X913937D01*
G01X904488D02*
X906850D01*
G01X897402D02*
X899764D01*
G01Y1661417D02*
X897402D01*
G01X906850D02*
X904488D01*
G01X913937D02*
X911575D01*
G01X899862Y1661220D02*
X897303D01*
G01X906949D02*
X904390D01*
G01X914035D02*
X911476D01*
G01X895531Y1660157D02*
X894547D01*
G01X902618D02*
X901634D01*
G01X909705D02*
X908720D01*
G01X901021Y1659646D02*
X896144D01*
G01X908108D02*
X903230D01*
G01X915194D02*
X910317D01*
G01X903826Y1649757D02*
X899810D01*
G01X910912D02*
X906896D01*
G01X915715D02*
X913983D01*
G01X902408Y1648740D02*
X901227D01*
G01X909495D02*
X908314D01*
G01X903589Y1646694D02*
X900046D01*
G01X910676D02*
X907133D01*
G01X899022Y1631436D02*
X897526D01*
G01X906109D02*
X904613D01*
G01X913196D02*
X911700D01*
G01X912526Y1628278D02*
X913855D01*
G01X910085Y1627870D02*
X914810D01*
G01X902999D02*
X907723D01*
G01X895912D02*
X900637D01*
G01X899652Y1625348D02*
X896896D01*
G01X906739D02*
X903983D01*
G01X913826D02*
X911070D01*
G01X914626Y1661828D02*
X915373Y1660771D01*
G01X914626Y1660450D02*
X915194Y1659646D01*
G01X909495Y1648740D02*
X910878Y1646345D01*
G01X902408Y1648740D02*
X903791Y1646345D01*
G01X911700Y1631436D02*
X910912Y1632800D01*
G01X907539Y1661828D02*
X908720Y1660157D01*
G01X907539Y1660450D02*
X908108Y1659646D01*
G01X900453Y1661828D02*
X901634Y1660157D01*
G01X900453Y1660450D02*
X901021Y1659646D01*
G01X895322Y1648740D02*
X896704Y1646345D01*
G01X904613Y1631436D02*
X903826Y1632800D01*
G01X897526Y1631436D02*
X896739Y1632800D01*
G01X906929Y1635083D02*
X906926Y1629843D01*
G01X906933Y1642413D02*
X906930Y1636763D01*
G01X906936Y1646354D02*
X906934Y1644078D01*
G01X899843Y1635083D02*
X899839Y1629843D01*
G01X899847Y1642413D02*
X899843Y1636763D01*
G01X899849Y1646354D02*
X899848Y1644078D01*
G01X915709Y1675984D02*
Y1659055D01*
G01X915373Y1660771D02*
Y1659055D01*
G01X915194Y1659646D02*
Y1659055D01*
G01X914810Y1649757D02*
Y1626332D01*
G01X914626Y1672278D02*
Y1660450D01*
G01X914528Y1672008D02*
Y1658661D01*
G01X914331D02*
Y1670709D01*
G01X914035Y1665551D02*
Y1661220D01*
G01X913983Y1635034D02*
Y1632800D01*
G01Y1642357D02*
Y1636814D01*
G01Y1649757D02*
Y1644137D01*
G01X913937Y1665354D02*
Y1661417D01*
G01X911575Y1665354D02*
Y1661417D01*
G01X911476Y1665551D02*
Y1661220D01*
G01X911181Y1670709D02*
Y1658661D01*
G01X910984Y1672008D02*
Y1658661D01*
G01X910912Y1635034D02*
Y1632800D01*
G01Y1642357D02*
Y1636814D01*
G01Y1649757D02*
Y1644137D01*
G01X910886Y1672278D02*
Y1660450D01*
G01X910317Y1659646D02*
Y1659055D01*
G01X910085Y1649757D02*
Y1626332D01*
G01X909705Y1660157D02*
Y1659055D01*
G01X908720Y1660157D02*
Y1659055D01*
G01X908108Y1659646D02*
Y1659055D01*
G01X907723Y1649757D02*
Y1626332D01*
G01X907539Y1672278D02*
Y1660450D01*
G01X907441Y1672008D02*
Y1658661D01*
G01X907244D02*
Y1670709D01*
G01X906949Y1665551D02*
Y1661220D01*
G01X906896Y1635034D02*
Y1632800D01*
G01Y1642357D02*
Y1636814D01*
G01Y1649757D02*
Y1644137D01*
G01X906850Y1665354D02*
Y1661417D01*
G01X904488D02*
Y1665354D01*
G01X904390Y1665551D02*
Y1661220D01*
G01X904094Y1670709D02*
Y1658661D01*
G01X903898Y1672008D02*
Y1658661D01*
G01X903826Y1635034D02*
Y1632800D01*
G01Y1642357D02*
Y1636814D01*
G01Y1649757D02*
Y1644137D01*
G01X903799Y1672278D02*
Y1660450D01*
G01X903230Y1659646D02*
Y1659055D01*
G01X902999Y1649757D02*
Y1626332D01*
G01X902618Y1660157D02*
Y1659055D01*
G01X901634Y1660157D02*
Y1659055D01*
G01X901021Y1659646D02*
Y1659055D01*
G01X900637Y1649757D02*
Y1626332D01*
G01X900453Y1672278D02*
Y1660450D01*
G01X900354Y1672008D02*
Y1658661D01*
G01X900157D02*
Y1670709D01*
G01X899862Y1665551D02*
Y1661220D01*
G01X899810Y1635034D02*
Y1632800D01*
G01Y1642357D02*
Y1636814D01*
G01Y1649757D02*
Y1644137D01*
G01X899764Y1665354D02*
Y1661417D01*
G01X897402Y1665354D02*
Y1661417D01*
G01X897303Y1665551D02*
Y1661220D01*
G01X897008Y1670709D02*
Y1658661D01*
G01X896811Y1672008D02*
Y1658661D01*
G01X896739Y1635034D02*
Y1632800D01*
G01Y1642357D02*
Y1636814D01*
G01Y1649757D02*
Y1644137D01*
G01X896713Y1672278D02*
Y1660450D01*
G01X896144Y1659646D02*
Y1659055D01*
G01X895912Y1649757D02*
Y1626332D01*
G01X895531Y1660157D02*
Y1659055D01*
G01X894547Y1660157D02*
Y1659055D01*
G01X910880Y1635083D02*
X910883Y1629843D01*
G01X910875Y1642413D02*
X910878Y1636763D01*
G01X910873Y1646354D02*
X910874Y1644078D01*
G01X903793Y1635083D02*
X903796Y1629843D01*
G01X903789Y1642413D02*
X903792Y1636763D01*
G01X903786Y1646354D02*
X903787Y1644078D01*
G01X896706Y1635083D02*
X896709Y1629843D01*
G01X896702Y1642413D02*
X896705Y1636763D01*
G01X896700Y1646354D02*
X896701Y1644078D01*
G01X915713Y1660984D02*
X915715Y1659213D01*
G01X913983Y1632800D02*
X913196Y1631436D01*
G01X906896Y1632800D02*
X906109Y1631436D01*
G01X899810Y1632800D02*
X899022Y1631436D01*
G01X906931Y1646345D02*
X908314Y1648740D01*
G01X899844Y1646345D02*
X901227Y1648740D01*
G01X910886Y1660450D02*
X910317Y1659646D01*
G01X910886Y1661828D02*
X909705Y1660157D01*
G01X903799Y1660450D02*
X903230Y1659646D01*
G01X903799Y1661828D02*
X902618Y1660157D01*
G01X896713Y1660450D02*
X896144Y1659646D01*
G01X896713Y1661828D02*
X895531Y1660157D01*
G01X905489Y1681086D02*
X905502Y1681299D01*
G01X905411Y1680901D02*
X905489Y1681086D01*
G01X905281Y1680769D02*
X905411Y1680901D01*
G01X905111Y1680710D02*
X905281Y1680769D01*
G01X897002Y1671488D02*
X896908Y1671394D01*
G01X897106Y1671572D02*
X897002Y1671488D01*
G01X904088D02*
X903994Y1671394D01*
G01X904193Y1671572D02*
X904088Y1671488D01*
G01X911175D02*
X911081Y1671394D01*
G01X911280Y1671572D02*
X911175Y1671488D01*
G01X904313Y1711005D02*
X904180Y1710783D01*
G01X904435Y1711201D02*
X904313Y1711005D01*
G01X904546Y1711370D02*
X904435Y1711201D01*
G01X904643Y1711505D02*
X904546Y1711370D01*
G01X904718Y1711596D02*
X904643Y1711505D01*
G01X904761Y1711628D02*
X904718Y1711596D01*
G01X904855Y1711582D02*
X904722Y1711359D01*
G01X904978Y1711778D02*
X904855Y1711582D01*
G01X907426Y1670829D02*
X907441Y1670906D01*
G01X907383Y1670766D02*
X907426Y1670829D01*
G01X907319Y1670724D02*
X907383Y1670766D01*
G01X908384Y1681670D02*
X908391Y1681890D01*
G01X908361Y1681474D02*
X908384Y1681670D01*
G01X908327Y1681343D02*
X908361Y1681474D01*
G01X908287Y1681299D02*
X908327Y1681343D01*
G01X897002Y1671488D02*
X897106Y1671572D01*
G01X896908Y1671394D02*
X897002Y1671488D01*
G01X896828Y1671294D02*
X896908Y1671394D01*
G01X904088Y1671488D02*
X904193Y1671572D01*
G01X903994Y1671394D02*
X904088Y1671488D01*
G01X903915Y1671294D02*
X903994Y1671394D01*
G01X911175Y1671488D02*
X911280Y1671572D01*
G01X911081Y1671394D02*
X911175Y1671488D01*
G01X911001Y1671294D02*
X911081Y1671394D01*
G01X896727Y1671048D02*
X896713Y1670900D01*
G01X896766Y1671180D02*
X896727Y1671048D01*
G01X896828Y1671294D02*
X896766Y1671180D01*
G01X903813Y1671048D02*
X903799Y1670900D01*
G01X903853Y1671180D02*
X903813Y1671048D01*
G01X903915Y1671294D02*
X903853Y1671180D01*
G01X910900Y1671048D02*
X910886Y1670900D01*
G01X910939Y1671180D02*
X910900Y1671048D01*
G01X911001Y1671294D02*
X910939Y1671180D01*
G01X908426Y1681526D02*
X908431Y1681890D01*
G01X908411Y1681197D02*
X908426Y1681526D01*
G01X908388Y1680935D02*
X908411Y1681197D01*
G01X908359Y1680767D02*
X908388Y1680935D01*
G01X908327Y1680709D02*
X908359Y1680767D01*
G01X900233Y1670724D02*
X900157Y1670709D01*
G01X900296Y1670766D02*
X900233Y1670724D01*
G01X900339Y1670829D02*
X900296Y1670766D01*
G01X900354Y1670906D02*
X900339Y1670829D01*
G01X907319Y1670724D02*
X907244Y1670709D01*
G01X907383Y1670766D02*
X907319Y1670724D01*
G01X907426Y1670829D02*
X907383Y1670766D01*
G01X907441Y1670906D02*
X907426Y1670829D01*
G01X914406Y1670724D02*
X914331Y1670709D01*
G01X914470Y1670766D02*
X914406Y1670724D01*
G01X914512Y1670829D02*
X914470Y1670766D01*
G01X914528Y1670906D02*
X914512Y1670829D01*
G01X894728Y1680767D02*
X894695Y1680709D01*
G01X894757Y1680935D02*
X894728Y1680767D01*
G01X894780Y1681196D02*
X894757Y1680935D01*
G01X894794Y1681525D02*
X894780Y1681196D01*
G01X894800Y1681890D02*
X894794Y1681525D01*
G01X907785Y1681343D02*
X907745Y1681299D01*
G01X907819Y1681474D02*
X907785Y1681343D01*
G01X907842Y1681669D02*
X907819Y1681474D01*
G01X907850Y1681890D02*
X907842Y1681669D01*
G01X904777Y1680758D02*
X904596Y1680709D01*
G01X904917Y1680889D02*
X904777Y1680758D01*
G01X905001Y1681078D02*
X904917Y1680889D01*
G01X905016Y1681299D02*
X905001Y1681078D01*
G01X908162Y1681685D02*
X908165Y1681890D01*
G01X908152Y1681486D02*
X908162Y1681685D01*
G01X908137Y1681299D02*
X908152Y1681486D01*
G01X907676Y1681685D02*
X907679Y1681890D01*
G01X907666Y1681485D02*
X907676Y1681685D01*
G01X907651Y1681299D02*
X907666Y1681485D01*
G01X904399Y1680720D02*
X904284Y1680709D01*
G01X904507Y1680754D02*
X904399Y1680720D01*
G01X904607Y1680808D02*
X904507Y1680754D01*
G01X904695Y1680881D02*
X904607Y1680808D01*
G01X904769Y1680972D02*
X904695Y1680881D01*
G01X904822Y1681074D02*
X904769Y1680972D01*
G01X904854Y1681184D02*
X904822Y1681074D01*
G01X904865Y1681299D02*
X904854Y1681184D01*
G01X908375Y1680759D02*
X908556Y1680709D01*
G01X908235Y1680889D02*
X908375Y1680759D01*
G01X908151Y1681079D02*
X908235Y1680889D01*
G01X908137Y1681299D02*
X908151Y1681079D01*
G01X907871Y1680769D02*
X908041Y1680710D01*
G01X907741Y1680901D02*
X907871Y1680769D01*
G01X907663Y1681086D02*
X907741Y1680901D01*
G01X907651Y1681299D02*
X907663Y1681086D01*
G01X904826Y1681343D02*
X904865Y1681299D01*
G01X904792Y1681474D02*
X904826Y1681343D01*
G01X904769Y1681669D02*
X904792Y1681474D01*
G01X904761Y1681890D02*
X904769Y1681669D01*
G01X905000Y1681486D02*
X905016Y1681299D01*
G01X904991Y1681685D02*
X905000Y1681486D01*
G01X904988Y1681890D02*
X904991Y1681685D01*
G01X904793Y1680767D02*
X904826Y1680709D01*
G01X904765Y1680935D02*
X904793Y1680767D01*
G01X904741Y1681196D02*
X904765Y1680935D01*
G01X904727Y1681525D02*
X904741Y1681196D01*
G01X904722Y1681890D02*
X904727Y1681525D01*
G01X908901Y1680767D02*
X908869Y1680709D01*
G01X908930Y1680935D02*
X908901Y1680767D01*
G01X908953Y1681196D02*
X908930Y1680935D01*
G01X908968Y1681525D02*
X908953Y1681196D01*
G01X908973Y1681890D02*
X908968Y1681525D01*
G01X908212Y1680720D02*
X908327Y1680709D01*
G01X908104Y1680754D02*
X908212Y1680720D01*
G01X908004Y1680808D02*
X908104Y1680754D01*
G01X907916Y1680881D02*
X908004Y1680808D01*
G01X907843Y1680972D02*
X907916Y1680881D01*
G01X907789Y1681074D02*
X907843Y1680972D01*
G01X907756Y1681184D02*
X907789Y1681074D01*
G01X907745Y1681299D02*
X907756Y1681184D01*
G01X900282Y1672736D02*
X900210Y1672792D01*
G01X900347Y1672657D02*
X900282Y1672736D01*
G01X900401Y1672554D02*
X900347Y1672657D01*
G01X900438Y1672427D02*
X900401Y1672554D01*
G01X900453Y1672278D02*
X900438Y1672427D01*
G01X907369Y1672736D02*
X907297Y1672792D01*
G01X907434Y1672657D02*
X907369Y1672736D01*
G01X907488Y1672554D02*
X907434Y1672657D01*
G01X907525Y1672427D02*
X907488Y1672554D01*
G01X907539Y1672278D02*
X907525Y1672427D01*
G01X914456Y1672736D02*
X914383Y1672792D01*
G01X914520Y1672657D02*
X914456Y1672736D01*
G01X914574Y1672554D02*
X914520Y1672657D01*
G01X914611Y1672427D02*
X914574Y1672554D01*
G01X914626Y1672278D02*
X914611Y1672427D01*
G01X900399Y1671180D02*
X900337Y1671294D01*
G01X900439Y1671048D02*
X900399Y1671180D01*
G01X900453Y1670900D02*
X900439Y1671048D01*
G01X907486Y1671180D02*
X907424Y1671294D01*
G01X907525Y1671048D02*
X907486Y1671180D01*
G01X907539Y1670900D02*
X907525Y1671048D01*
G01X914572Y1671180D02*
X914511Y1671294D01*
G01X914612Y1671048D02*
X914572Y1671180D01*
G01X914626Y1670900D02*
X914612Y1671048D01*
G01X905477Y1681685D02*
X905474Y1681890D01*
G01X905486Y1681486D02*
X905477Y1681685D01*
G01X905502Y1681299D02*
X905486Y1681486D01*
G01X896933Y1670723D02*
X897008Y1670709D01*
G01X896869Y1670766D02*
X896933Y1670723D01*
G01X896826Y1670829D02*
X896869Y1670766D01*
G01X896811Y1670906D02*
X896826Y1670829D01*
G01X911106Y1670723D02*
X911181Y1670709D01*
G01X911042Y1670766D02*
X911106Y1670723D01*
G01X911000Y1670829D02*
X911042Y1670766D01*
G01X910984Y1670906D02*
X911000Y1670829D01*
G01X903913D02*
X903955Y1670766D01*
G01X903898Y1670906D02*
X903913Y1670829D01*
G01X908298Y1711582D02*
X908175Y1711778D01*
G01X908431Y1711359D02*
X908298Y1711582D01*
G01X904185Y1681526D02*
X904180Y1681890D01*
G01X904200Y1681197D02*
X904185Y1681526D01*
G01X904222Y1680935D02*
X904200Y1681197D01*
G01X904252Y1680767D02*
X904222Y1680935D01*
G01X904284Y1680709D02*
X904252Y1680767D01*
G01X900163Y1671488D02*
X900059Y1671572D01*
G01X900257Y1671394D02*
X900163Y1671488D01*
G01X900337Y1671294D02*
X900257Y1671394D01*
G01X907250Y1671488D02*
X907146Y1671572D01*
G01X907344Y1671394D02*
X907250Y1671488D01*
G01X907424Y1671294D02*
X907344Y1671394D01*
G01X914337Y1671488D02*
X914232Y1671572D01*
G01X914431Y1671394D02*
X914337Y1671488D01*
G01X914511Y1671294D02*
X914431Y1671394D01*
G01X905311Y1681670D02*
X905303Y1681890D01*
G01X905333Y1681474D02*
X905311Y1681670D01*
G01X905368Y1681343D02*
X905333Y1681474D01*
G01X905407Y1681299D02*
X905368Y1681343D01*
G01X903913Y1670829D02*
X903898Y1670906D01*
G01X903955Y1670766D02*
X903913Y1670829D01*
G01X904019Y1670724D02*
X903955Y1670766D01*
G01X894667Y1711006D02*
X894800Y1710783D01*
G01X908840Y1711006D02*
X908973Y1710783D01*
G01X908717Y1711202D02*
X908840Y1711006D01*
G01X908606Y1711370D02*
X908717Y1711202D01*
G01X908510Y1711506D02*
X908606Y1711370D01*
G01X908435Y1711596D02*
X908510Y1711506D01*
G01X908391Y1711628D02*
X908435Y1711596D01*
G01X910900Y1672427D02*
X910886Y1672278D01*
G01X910937Y1672554D02*
X910900Y1672427D01*
G01X910991Y1672657D02*
X910937Y1672554D01*
G01X911056Y1672736D02*
X910991Y1672657D01*
G01X911128Y1672792D02*
X911056Y1672736D01*
G01X911204Y1672824D02*
X911128Y1672792D01*
G01X911280Y1672835D02*
X911204Y1672824D01*
G01X903813Y1672427D02*
X903799Y1672278D01*
G01X903851Y1672554D02*
X903813Y1672427D01*
G01X903905Y1672657D02*
X903851Y1672554D01*
G01X903970Y1672736D02*
X903905Y1672657D01*
G01X904041Y1672792D02*
X903970Y1672736D01*
G01X904117Y1672824D02*
X904041Y1672792D01*
G01X904193Y1672835D02*
X904117Y1672824D01*
G01X896727Y1672427D02*
X896713Y1672278D01*
G01X896764Y1672554D02*
X896727Y1672427D01*
G01X896818Y1672657D02*
X896764Y1672554D01*
G01X896883Y1672736D02*
X896818Y1672657D01*
G01X896955Y1672792D02*
X896883Y1672736D01*
G01X897031Y1672824D02*
X896955Y1672792D01*
G01X897106Y1672835D02*
X897031Y1672824D01*
G01X905396Y1681182D02*
X905407Y1681299D01*
G01X905363Y1681072D02*
X905396Y1681182D01*
G01X905309Y1680970D02*
X905363Y1681072D01*
G01X905237Y1680881D02*
X905309Y1680970D01*
G01X905148Y1680807D02*
X905237Y1680881D01*
G01X905047Y1680753D02*
X905148Y1680807D01*
G01X904939Y1680720D02*
X905047Y1680753D01*
G01X904826Y1680709D02*
X904939Y1680720D01*
G01X894695Y1680709D02*
X894583Y1680720D01*
G01X908298Y1681182D02*
X908287Y1681299D01*
G01X908332Y1681072D02*
X908298Y1681182D01*
G01X908385Y1680970D02*
X908332Y1681072D01*
G01X908457Y1680881D02*
X908385Y1680970D01*
G01X908547Y1680807D02*
X908457Y1680881D01*
G01X908647Y1680753D02*
X908547Y1680807D01*
G01X908756Y1680720D02*
X908647Y1680753D01*
G01X908869Y1680709D02*
X908756Y1680720D01*
G01X905669Y1673819D02*
G03X904291Y1672441I0J-1378D01*
G01X914134D02*
G03X912756Y1673819I-1378J0D01*
G01Y1667913D02*
G03X914134Y1669291I0J1378D01*
G01X904291D02*
G03X905669Y1667913I1378J0D01*
G01X899961Y1672441D02*
G03X898583Y1673819I-1378J0D01*
G01Y1667913D02*
G03X899961Y1669291I0J1378D01*
G01X907504Y1707244D02*
X905648D01*
G01X905326Y1706457D02*
X907827D01*
G01X898531Y1705906D02*
X897113D01*
G01X904849Y1705880D02*
X904988D01*
G01X908304D02*
X908165D01*
G01X898531Y1701181D02*
X897113D01*
G01X904019Y1670724D02*
X904094Y1670709D01*
G01X914308Y1672824D02*
X914232Y1672835D01*
G01X907221Y1672824D02*
X907146Y1672835D01*
G01X900135Y1672824D02*
X900059Y1672835D01*
G01X900684Y1688780D02*
X896747D01*
G01X914857D02*
X910920D01*
G01X901806Y1688583D02*
X903433D01*
G01Y1688249D02*
X901806D01*
G01X910920Y1688234D02*
X914857D01*
G01X896747D02*
X900684D01*
G01X901806Y1687851D02*
X903433D01*
G01X900684Y1687791D02*
X896747D01*
G01X914857D02*
X910920D01*
G01X907651Y1681299D02*
X907745D01*
G01X905407D02*
X905502D01*
G01X905016D02*
X904865D01*
G01X908287D02*
X908137D01*
G01X901806Y1681196D02*
X903433D01*
G01X900684D02*
X896747D01*
G01X914857D02*
X910920D01*
G01X908041Y1680710D02*
X905111D01*
G01X911287Y1676280D02*
X912704D01*
G01X897113D02*
X898531D01*
G01Y1676181D02*
X897113D01*
G01X912704D02*
X911287D01*
G01X915709Y1675984D02*
X920827D01*
G01X898826D02*
X896818D01*
G01X912999D02*
X910991D01*
G01X912756Y1673819D02*
X905669D01*
G01X900059Y1672835D02*
X897106D01*
G01X907146D02*
X904193D01*
G01X914232D02*
X911280D01*
G01X900354Y1672008D02*
X896811D01*
G01X907441D02*
X903898D01*
G01X914528D02*
X910984D01*
G01X900059Y1671572D02*
X897106D01*
G01X907146D02*
X904193D01*
G01X914232D02*
X911280D01*
G01X900337Y1671294D02*
X896828D01*
G01X907424D02*
X903915D01*
G01X914511D02*
X911001D01*
G01X900157Y1670709D02*
X897008D01*
G01X907244D02*
X904094D01*
G01X914331D02*
X911181D01*
G01X912756Y1667913D02*
X905669D01*
G01X899862Y1665551D02*
X897303D01*
G01X906949D02*
X904390D01*
G01X914035D02*
X911476D01*
G01X899764Y1665354D02*
X897402D01*
G01X906850D02*
X904488D01*
G01X913937D02*
X911575D01*
G01X914308Y1672824D02*
X914383Y1672792D01*
G01X907221Y1672824D02*
X907297Y1672792D01*
G01X900135Y1672824D02*
X900210Y1672792D01*
G01X912999Y1675984D02*
X912704Y1676280D01*
G01Y1676181D02*
X912901Y1675984D01*
G01X898826D02*
X898531Y1676280D01*
G01Y1676181D02*
X898728Y1675984D01*
G01X914431Y1671394D02*
X914511Y1671294D01*
G01X907344Y1671394D02*
X907424Y1671294D01*
G01X900257Y1671394D02*
X900337Y1671294D01*
G01X907678Y1712992D02*
X908973Y1710783D01*
G01X908431Y1711359D02*
X907474Y1712992D01*
G01X908304Y1705880D02*
X907504Y1707244D01*
G01X907827Y1706457D02*
X908165Y1705880D01*
G01X907643Y1712992D02*
X908304Y1711628D01*
G01X907446Y1707244D02*
X907827Y1706457D01*
G01X920827Y1718504D02*
Y1675984D01*
G01X916890Y1714412D02*
Y1680709D01*
G01X914857Y1688780D02*
Y1680709D01*
G01X914232Y1672835D02*
Y1671572D01*
G01X914134Y1672441D02*
Y1669291D01*
G01X911280Y1672835D02*
Y1671572D01*
G01X910920Y1688780D02*
Y1680709D01*
G01X908973Y1681890D02*
Y1710783D01*
G01X908431Y1711359D02*
Y1681890D01*
G01X908391Y1711628D02*
Y1681890D01*
G01X908304Y1711628D02*
Y1705880D01*
G01X908165D02*
Y1681890D01*
G01X907850D02*
Y1712205D01*
G01X907679D02*
Y1681890D01*
G01X907146Y1672835D02*
Y1671572D01*
G01X905474Y1681890D02*
Y1712205D01*
G01X905303D02*
Y1681890D01*
G01X904988Y1705880D02*
Y1681890D01*
G01X904849Y1705880D02*
Y1711628D01*
G01X904761Y1681890D02*
Y1711628D01*
G01X904722Y1681890D02*
Y1711359D01*
G01X904291Y1672441D02*
Y1669291D01*
G01X904193Y1672835D02*
Y1671572D01*
G01X904180Y1710783D02*
Y1681890D01*
G01X903433Y1688583D02*
Y1680709D01*
G01X901806Y1688583D02*
Y1680709D01*
G01X900684Y1688780D02*
Y1680709D01*
G01X900059Y1672835D02*
Y1671572D01*
G01X899961Y1672441D02*
Y1669291D01*
G01X898531Y1680709D02*
Y1705906D01*
G01X897113D02*
Y1680709D01*
G01X897106Y1672835D02*
Y1671572D01*
G01X896747Y1688780D02*
Y1680709D01*
G01X894800Y1681890D02*
Y1710783D01*
G01X905326Y1706457D02*
X904988Y1705880D01*
G01X905648Y1707244D02*
X904849Y1705880D01*
G01X905679Y1712992D02*
X904722Y1711359D01*
G01X904180Y1710783D02*
X905475Y1712992D01*
G01X905326Y1706457D02*
X905707Y1707244D01*
G01X904849Y1711628D02*
X905509Y1712992D01*
G01X911090Y1675984D02*
X911287Y1676181D01*
G01Y1676280D02*
X910991Y1675984D01*
G01X896917D02*
X897113Y1676181D01*
G01Y1676280D02*
X896818Y1675984D01*
G01X905088Y1711946D02*
X904978Y1711778D01*
G01X905185Y1712082D02*
X905088Y1711946D01*
G01X905260Y1712173D02*
X905185Y1712082D01*
G01X905303Y1712205D02*
X905260Y1712173D01*
G01X907893D02*
X907850Y1712205D01*
G01X907968Y1712082D02*
X907893Y1712173D01*
G01X908064Y1711946D02*
X907968Y1712082D01*
G01X908175Y1711778D02*
X908064Y1711946D01*
G01X907678Y1712992D02*
X905475D01*
G01X907850Y1712205D02*
X905303D01*
G01X904761Y1711628D02*
X908391D01*
G01X907297Y1712992D02*
X907679Y1712205D01*
G01X919252Y1718504D02*
X916890Y1714412D01*
G01X905474Y1712205D02*
X905856Y1712992D01*
G01X979575Y-335933D02*
Y-354870D01*
G01X955217Y-122638D02*
X951870Y-125984D01*
G01X944587Y-104331D02*
Y-125984D01*
G01X987500Y-120617D02*
X987598Y-120620D01*
G01X987428Y-120611D02*
X987500Y-120617D01*
G01X987402Y-120613D02*
X987428Y-120611D01*
G01X982500Y-120617D02*
X982598Y-120620D01*
G01X982428Y-120611D02*
X982500Y-120617D01*
G01X982402Y-120613D02*
X982428Y-120611D01*
G01X977500Y-120617D02*
X977598Y-120620D01*
G01X977428Y-120611D02*
X977500Y-120617D01*
G01X977402Y-120613D02*
X977428Y-120611D01*
G01X972500Y-120617D02*
X972598Y-120620D01*
G01X972428Y-120611D02*
X972500Y-120617D01*
G01X972402Y-120613D02*
X972428Y-120611D01*
G01X967500Y-120617D02*
X967598Y-120620D01*
G01X967428Y-120611D02*
X967500Y-120617D01*
G01X967402Y-120613D02*
X967428Y-120611D01*
G01X962500Y-120617D02*
X962598Y-120620D01*
G01X962428Y-120611D02*
X962500Y-120617D01*
G01X962402Y-120613D02*
X962428Y-120611D01*
G01X961022Y-119666D02*
X961024Y-119667D01*
G01X961017Y-119665D02*
X961022Y-119666D01*
G01X961007Y-119665D02*
X961017D01*
G01X966022Y-119666D02*
X966024Y-119667D01*
G01X966017Y-119665D02*
X966022Y-119666D01*
G01X966007Y-119665D02*
X966017D01*
G01X971022Y-119666D02*
X971024Y-119667D01*
G01X971017Y-119665D02*
X971022Y-119666D01*
G01X971007Y-119665D02*
X971017D01*
G01X976022Y-119666D02*
X976024Y-119667D01*
G01X976017Y-119665D02*
X976022Y-119666D01*
G01X976007Y-119665D02*
X976017D01*
G01X981022Y-119666D02*
X981024Y-119667D01*
G01X981017Y-119665D02*
X981022Y-119666D01*
G01X981007Y-119665D02*
X981017D01*
G01X986022Y-119666D02*
X986024Y-119667D01*
G01X986017Y-119665D02*
X986022Y-119666D01*
G01X986007Y-119665D02*
X986017D01*
G01X991022Y-119666D02*
X991024Y-119667D01*
G01X991017Y-119665D02*
X991022Y-119666D01*
G01X991007Y-119665D02*
X991017D01*
G01X987396Y-120632D02*
X987402Y-120613D01*
G01X987382Y-120646D02*
X987396Y-120632D01*
G01X987362Y-120652D02*
X987382Y-120646D01*
G01X982396Y-120632D02*
X982402Y-120613D01*
G01X982382Y-120646D02*
X982396Y-120632D01*
G01X982362Y-120652D02*
X982382Y-120646D01*
G01X977396Y-120632D02*
X977402Y-120613D01*
G01X977382Y-120646D02*
X977396Y-120632D01*
G01X977362Y-120652D02*
X977382Y-120646D01*
G01X972396Y-120632D02*
X972402Y-120613D01*
G01X972382Y-120646D02*
X972396Y-120632D01*
G01X972362Y-120652D02*
X972382Y-120646D01*
G01X967396Y-120632D02*
X967402Y-120613D01*
G01X967382Y-120646D02*
X967396Y-120632D01*
G01X967362Y-120652D02*
X967382Y-120646D01*
G01X962396Y-120632D02*
X962402Y-120613D01*
G01X962382Y-120646D02*
X962396Y-120632D01*
G01X962362Y-120652D02*
X962382Y-120646D01*
G01X961016Y-120650D02*
X961007D01*
G01X961022Y-120651D02*
X961016Y-120650D01*
G01X961024Y-120652D02*
X961022Y-120651D01*
G01X966016Y-120650D02*
X966007D01*
G01X966022Y-120651D02*
X966016Y-120650D01*
G01X966024Y-120652D02*
X966022Y-120651D01*
G01X971016Y-120650D02*
X971007D01*
G01X971022Y-120651D02*
X971016Y-120650D01*
G01X971024Y-120652D02*
X971022Y-120651D01*
G01X976016Y-120650D02*
X976007D01*
G01X976022Y-120651D02*
X976016Y-120650D01*
G01X976024Y-120652D02*
X976022Y-120651D01*
G01X981016Y-120650D02*
X981007D01*
G01X981022Y-120651D02*
X981016Y-120650D01*
G01X981024Y-120652D02*
X981022Y-120651D01*
G01X986016Y-120650D02*
X986007D01*
G01X986022Y-120651D02*
X986016Y-120650D01*
G01X986024Y-120652D02*
X986022Y-120651D01*
G01X991016Y-120650D02*
X991007D01*
G01X991022Y-120651D02*
X991016Y-120650D01*
G01X991024Y-120652D02*
X991022Y-120651D01*
G01X962393Y-120637D02*
X962378Y-120648D01*
G01X962402Y-120613D02*
X962393Y-120637D01*
G01X967393D02*
X967378Y-120648D01*
G01X967402Y-120613D02*
X967393Y-120637D01*
G01X972393D02*
X972378Y-120648D01*
G01X972402Y-120613D02*
X972393Y-120637D01*
G01X977393D02*
X977378Y-120648D01*
G01X977402Y-120613D02*
X977393Y-120637D01*
G01X982393D02*
X982378Y-120648D01*
G01X982402Y-120613D02*
X982393Y-120637D01*
G01X987393D02*
X987378Y-120648D01*
G01X987402Y-120613D02*
X987393Y-120637D01*
G01X962369Y-120650D02*
X962376D01*
G01X962364D02*
X962369D01*
G01X962362Y-120652D02*
X962364Y-120650D01*
G01X967369D02*
X967376D01*
G01X967364D02*
X967369D01*
G01X967362Y-120652D02*
X967364Y-120650D01*
G01X972369D02*
X972376D01*
G01X972364D02*
X972369D01*
G01X972362Y-120652D02*
X972364Y-120650D01*
G01X977369D02*
X977376D01*
G01X977364D02*
X977369D01*
G01X977362Y-120652D02*
X977364Y-120650D01*
G01X982369D02*
X982376D01*
G01X982364D02*
X982369D01*
G01X982362Y-120652D02*
X982364Y-120650D01*
G01X987369D02*
X987376D01*
G01X987364D02*
X987369D01*
G01X987362Y-120652D02*
X987364Y-120650D01*
G01X962409Y-119665D02*
X962418D01*
G01X962404Y-119666D02*
X962409Y-119665D01*
G01X962402Y-119667D02*
X962404Y-119666D01*
G01X967409Y-119665D02*
X967418D01*
G01X967404Y-119666D02*
X967409Y-119665D01*
G01X967402Y-119667D02*
X967404Y-119666D01*
G01X972409Y-119665D02*
X972418D01*
G01X972404Y-119666D02*
X972409Y-119665D01*
G01X972402Y-119667D02*
X972404Y-119666D01*
G01X977409Y-119665D02*
X977418D01*
G01X977404Y-119666D02*
X977409Y-119665D01*
G01X977402Y-119667D02*
X977404Y-119666D01*
G01X982409Y-119665D02*
X982418D01*
G01X982404Y-119666D02*
X982409Y-119665D01*
G01X982402Y-119667D02*
X982404Y-119666D01*
G01X987409Y-119665D02*
X987418D01*
G01X987404Y-119666D02*
X987409Y-119665D01*
G01X987402Y-119667D02*
X987404Y-119666D01*
G01X962545Y-120642D02*
X962519Y-120650D01*
G01X962572Y-120632D02*
X962545Y-120642D01*
G01X962598Y-120620D02*
X962572Y-120632D01*
G01X967545Y-120642D02*
X967519Y-120650D01*
G01X967572Y-120632D02*
X967545Y-120642D01*
G01X967598Y-120620D02*
X967572Y-120632D01*
G01X972545Y-120642D02*
X972519Y-120650D01*
G01X972572Y-120632D02*
X972545Y-120642D01*
G01X972598Y-120620D02*
X972572Y-120632D01*
G01X977545Y-120642D02*
X977519Y-120650D01*
G01X977572Y-120632D02*
X977545Y-120642D01*
G01X977598Y-120620D02*
X977572Y-120632D01*
G01X982545Y-120642D02*
X982519Y-120650D01*
G01X982572Y-120632D02*
X982545Y-120642D01*
G01X982598Y-120620D02*
X982572Y-120632D01*
G01X987545Y-120642D02*
X987519Y-120650D01*
G01X987572Y-120632D02*
X987545Y-120642D01*
G01X987598Y-120620D02*
X987572Y-120632D01*
G01X951004Y-115157D02*
G03I-1102J0D01*
G01X944626Y-117717D02*
G03X945807Y-118898I1181J0D01*
G01Y-111417D02*
G03X944626Y-112598I0J-1181D01*
G01X951476Y-115157D02*
G03I-1574J0D01*
G01X949311Y-116339D02*
X945082Y-118648D01*
G01X951004Y-113976D02*
X952972Y-112672D01*
G01X957894Y-116142D02*
X956713Y-117323D01*
G01X991024Y-125000D02*
Y-119667D01*
G01X990531Y-119665D02*
Y-120650D01*
G01X987894D02*
Y-119665D01*
G01X987402Y-119667D02*
Y-125000D01*
G01X987362D02*
Y-120652D01*
G01X986024Y-125000D02*
Y-119667D01*
G01X985531Y-119665D02*
Y-120650D01*
G01X982894D02*
Y-119665D01*
G01X982402Y-119667D02*
Y-125000D01*
G01X982362D02*
Y-120652D01*
G01X981024Y-125000D02*
Y-119667D01*
G01X980531Y-119665D02*
Y-120650D01*
G01X990828D02*
X990827Y-119665D01*
G01X987597D02*
X987598Y-120620D01*
G01X985828Y-120650D02*
X985827Y-119665D01*
G01X982597D02*
X982598Y-120620D01*
G01X980828Y-120650D02*
X980827Y-119665D01*
G01X977894Y-120650D02*
Y-119665D01*
G01X977402Y-119667D02*
Y-125000D01*
G01X977362D02*
Y-120652D01*
G01X976024Y-125000D02*
Y-119667D01*
G01X975531Y-119665D02*
Y-120650D01*
G01X972894D02*
Y-119665D01*
G01X972402Y-119667D02*
Y-125000D01*
G01X972362D02*
Y-120652D01*
G01X971024Y-125000D02*
Y-119667D01*
G01X970531Y-119665D02*
Y-120650D01*
G01X967894D02*
Y-119665D01*
G01X967402Y-119667D02*
Y-125000D01*
G01X967362D02*
Y-120652D01*
G01X966024Y-125000D02*
Y-119667D01*
G01X965531Y-119665D02*
Y-120650D01*
G01X962894D02*
Y-119665D01*
G01X962402Y-119667D02*
Y-125000D01*
G01X962362D02*
Y-120652D01*
G01X961024Y-125000D02*
Y-119667D01*
G01X960531Y-119665D02*
Y-120650D01*
G01X957894Y-116142D02*
Y-110630D01*
G01X956713Y-117323D02*
Y-109449D01*
G01X955217Y-122638D02*
Y-107677D01*
G01X954350Y-111417D02*
Y-107677D01*
G01Y-118898D02*
Y-122047D01*
G01X952972D02*
Y-107677D01*
G01X951004Y-116339D02*
Y-113976D01*
G01X949311Y-116339D02*
Y-113976D01*
G01X944626Y-117717D02*
Y-112598D01*
G01X977597Y-119665D02*
X977598Y-120620D01*
G01X975828Y-120650D02*
X975827Y-119665D01*
G01X972597D02*
X972598Y-120620D01*
G01X970828Y-120650D02*
X970827Y-119665D01*
G01X967597D02*
X967598Y-120620D01*
G01X965828Y-120650D02*
X965827Y-119665D01*
G01X962597D02*
X962598Y-120620D01*
G01X960828Y-120650D02*
X960827Y-119665D01*
G01X951870Y-104331D02*
X955217Y-107677D01*
G01X957894Y-110630D02*
X956713Y-109449D01*
G01X952972Y-117642D02*
X951004Y-116339D01*
G01X945082Y-111666D02*
X949311Y-113976D01*
G01X987376Y-120650D02*
X987385D01*
G01X982376D02*
X982385D01*
G01X977376D02*
X977385D01*
G01X972376D02*
X972385D01*
G01X967376D02*
X967385D01*
G01X962376D02*
X962385D01*
G01X992008Y-107677D02*
X952972D01*
G01X956713Y-109449D02*
X1091713D01*
G01X957894Y-110630D02*
X1090531D01*
G01X945807Y-111417D02*
X954350D01*
G01X949311Y-113976D02*
X951004D01*
G01X994350Y-116142D02*
X957894D01*
G01X951004Y-116339D02*
X949311D01*
G01X993169Y-117323D02*
X956713D01*
G01X954350Y-118898D02*
X945807D01*
G01X962894Y-119665D02*
X960531D01*
G01X967894D02*
X965531D01*
G01X972894D02*
X970531D01*
G01X977894D02*
X975531D01*
G01X982894D02*
X980531D01*
G01X987894D02*
X985531D01*
G01X992894D02*
X990531D01*
G01Y-120650D02*
X992894D01*
G01X985531D02*
X987894D01*
G01X980531D02*
X982894D01*
G01X975531D02*
X977894D01*
G01X970531D02*
X972894D01*
G01X965531D02*
X967894D01*
G01X960531D02*
X962894D01*
G01X962402Y-121831D02*
X961024D01*
G01X967402D02*
X966024D01*
G01X972402D02*
X971024D01*
G01X977402D02*
X976024D01*
G01X982402D02*
X981024D01*
G01X987402D02*
X986024D01*
G01X992402D02*
X991024D01*
G01X1095453Y-122047D02*
X952972D01*
G01X1093209Y-122638D02*
X955217D01*
G01X991024Y-125000D02*
X992402D01*
G01X986024D02*
X987402D01*
G01X981024D02*
X982402D01*
G01X976024D02*
X977402D01*
G01X971024D02*
X972402D01*
G01X966024D02*
X967402D01*
G01X961024D02*
X962402D01*
G01X954564Y-42570D02*
G03X962732Y-57821I73076J29324D01*
G01X969882Y-29528D02*
Y-21654D01*
G01Y-29528D02*
G03X981693I5906J0D01*
G01Y-21654D02*
Y-29528D01*
G01X969882D02*
G03X981693I5906J1D01*
G01X954565Y-42571D02*
G03X962731Y-57820I73077J29322D01*
G01X981693Y-21654D02*
Y-29528D01*
G01X969882Y-21654D02*
Y-29528D01*
G01X981693Y-21654D02*
G03X969882I-5906J0D01*
G01X981693D02*
G03X969882I-5906J1D01*
G01Y564961D02*
G03X981693I5906J0D01*
G01D02*
G03X969882I-5906J0D01*
G01X981693D02*
G03I-5906J0D01*
G01X971398Y1102252D02*
G03X978323Y1089121I37662J11471D01*
G01X971398Y1102252D02*
G03X951437I-9980J-3039D01*
G01X944512Y1089121D02*
G03X951437Y1102252I-30737J24602D01*
G01X971398D02*
G03X978323Y1089122I37661J11472D01*
G01X971398Y1102252D02*
G03X951437I-9980J-3039D01*
G01X944512Y1089122D02*
G03X951437Y1102252I-30737J24602D01*
G01X971398Y1444772D02*
G03X978323Y1431641I37662J11471D01*
G01X971398Y1444772D02*
G03X951437I-9980J-3039D01*
G01X944512Y1431641D02*
G03X951437Y1444772I-30737J24602D01*
G01X971398D02*
G03X978323Y1431641I37662J11471D01*
G01X944512D02*
G03X951437Y1444772I-30737J24602D01*
G01X971398D02*
G03X951437I-9980J-3040D01*
G01X969202Y1591723D02*
X969544Y1592028D01*
G01X968946Y1591335D02*
X969202Y1591723D01*
G01X968774Y1590865D02*
X968946Y1591335D01*
G01X968707Y1590313D02*
X968774Y1590865D01*
G01X976289Y1591723D02*
X976631Y1592028D01*
G01X976032Y1591335D02*
X976289Y1591723D01*
G01X975861Y1590865D02*
X976032Y1591335D01*
G01X975794Y1590313D02*
X975861Y1590865D01*
G01X983376Y1591723D02*
X983718Y1592028D01*
G01X983119Y1591335D02*
X983376Y1591723D01*
G01X982947Y1590865D02*
X983119Y1591335D01*
G01X982880Y1590313D02*
X982947Y1590865D01*
G01X969177Y1591805D02*
X969544Y1592028D01*
G01X968914Y1591522D02*
X969177Y1591805D01*
G01X968759Y1591207D02*
X968914Y1591522D01*
G01X968707Y1590885D02*
X968759Y1591207D01*
G01X976263Y1591805D02*
X976631Y1592028D01*
G01X976001Y1591522D02*
X976263Y1591805D01*
G01X975845Y1591207D02*
X976001Y1591522D01*
G01X975794Y1590885D02*
X975845Y1591207D01*
G01X983350Y1591805D02*
X983718Y1592028D01*
G01X983087Y1591522D02*
X983350Y1591805D01*
G01X982932Y1591207D02*
X983087Y1591522D01*
G01X982880Y1590885D02*
X982932Y1591207D01*
G01X990437Y1591805D02*
X990804Y1592028D01*
G01X990174Y1591522D02*
X990437Y1591805D01*
G01X990019Y1591207D02*
X990174Y1591522D01*
G01X989967Y1590885D02*
X990019Y1591207D01*
G01X990462Y1591723D02*
X990804Y1592028D01*
G01X990206Y1591335D02*
X990462Y1591723D01*
G01X990034Y1590865D02*
X990206Y1591335D01*
G01X989967Y1590313D02*
X990034Y1590865D01*
G01X971366Y1591805D02*
X971000Y1592028D01*
G01X971628Y1591524D02*
X971366Y1591805D01*
G01X971785Y1591209D02*
X971628Y1591524D01*
G01X971837Y1590885D02*
X971785Y1591209D01*
G01X978452Y1591805D02*
X978086Y1592028D01*
G01X978715Y1591524D02*
X978452Y1591805D01*
G01X978872Y1591209D02*
X978715Y1591524D01*
G01X978924Y1590885D02*
X978872Y1591209D01*
G01X985539Y1591805D02*
X985173Y1592028D01*
G01X985802Y1591524D02*
X985539Y1591805D01*
G01X985958Y1591209D02*
X985802Y1591524D01*
G01X986010Y1590885D02*
X985958Y1591209D01*
G01X971770Y1590863D02*
X971837Y1590313D01*
G01X971599Y1591333D02*
X971770Y1590863D01*
G01X971342Y1591722D02*
X971599Y1591333D01*
G01X971000Y1592028D02*
X971342Y1591722D01*
G01X978857Y1590863D02*
X978924Y1590313D01*
G01X978686Y1591333D02*
X978857Y1590863D01*
G01X978429Y1591722D02*
X978686Y1591333D01*
G01X978086Y1592028D02*
X978429Y1591722D01*
G01X985944Y1590863D02*
X986010Y1590313D01*
G01X985772Y1591333D02*
X985944Y1590863D01*
G01X985515Y1591722D02*
X985772Y1591333D01*
G01X985173Y1592028D02*
X985515Y1591722D01*
G01X992259Y1592028D02*
G03X990804I-727J-1386D01*
G01X993500Y1610256D02*
G03I-1968J0D01*
G01X988071Y1613858D02*
G03I-1457J0D01*
G01X975472D02*
G03I-1456J0D01*
G01X988071Y1603032D02*
G03I-1457J0D01*
G01X986414Y1610256D02*
G03I-1969J0D01*
G01X988071Y1597126D02*
G03I-1457J0D01*
G01Y1591221D02*
G03I-1457J0D01*
G01X985173Y1592028D02*
G03X983718I-727J-1386D01*
G01X975472Y1603032D02*
G03I-1456J0D01*
G01X979327Y1610256D02*
G03I-1968J0D01*
G01X972241D02*
G03I-1969J0D01*
G01X975472Y1597126D02*
G03I-1456J0D01*
G01Y1591221D02*
G03I-1456J0D01*
G01X978086Y1592028D02*
G03X976631I-728J-1386D01*
G01X971000D02*
G03X969544I-728J-1386D01*
G01X973556Y1591768D02*
X973458Y1591801D01*
G01X973130Y1591165D02*
X973228Y1591131D01*
G01X973261Y1590561D02*
X973163Y1590595D01*
G01X974869Y1591768D02*
X975000Y1591734D01*
G01X975033Y1591935D02*
X974869Y1591969D01*
G01X973589Y1591935D02*
X973425Y1591969D01*
G01X973097Y1590997D02*
X973261Y1590963D01*
G01X973130Y1590427D02*
X973294Y1590394D01*
G01X966831Y1595827D02*
X993799D01*
G01X976631Y1592028D02*
X971000D01*
G01X969544D02*
X966729D01*
G01X983718D02*
X978086D01*
G01X990804D02*
X985173D01*
G01X973425Y1591969D02*
X973261D01*
G01X974869D02*
X974737D01*
G01X973458Y1591801D02*
X973228D01*
G01X974737Y1591768D02*
X974869D01*
G01X975197Y1591433D02*
X975394D01*
G01X973228Y1591131D02*
X973458D01*
G01X973261Y1590963D02*
X973425D01*
G01X972999Y1590762D02*
X972835D01*
G01X973458Y1590561D02*
X973261D01*
G01X973294Y1590394D02*
X973425D01*
G01X974213D02*
X974409D01*
G01X1051217Y1587303D02*
X966729D01*
G01X1051217Y1584941D02*
X966729D01*
G01X971807Y1584547D02*
X968737D01*
G01X993067D02*
X989996D01*
G01X970626Y1583366D02*
X969918D01*
G01X991886D02*
X991178D01*
G01X966831Y1582382D02*
X993799D01*
G01X973261Y1591969D02*
X973097Y1591935D01*
G01X974737Y1591969D02*
X974574Y1591935D01*
G01X973425Y1590963D02*
X973589Y1590997D01*
G01X973425Y1590394D02*
X973589Y1590427D01*
G01X974606Y1591734D02*
X974737Y1591768D01*
G01X975000Y1591734D02*
X975098Y1591667D01*
G01X973655Y1591700D02*
X973556Y1591768D01*
G01X973031Y1591231D02*
X973130Y1591165D01*
G01X973163Y1590595D02*
X973064Y1590662D01*
G01X973753Y1591835D02*
X973589Y1591935D01*
G01X972933Y1591098D02*
X973097Y1590997D01*
G01X972966Y1590528D02*
X973130Y1590427D01*
G01X975164Y1591868D02*
X975033Y1591935D01*
G01X975295Y1591734D02*
X975164Y1591868D01*
G01X972966Y1591298D02*
X973031Y1591231D01*
G01X972835Y1591198D02*
X972933Y1591098D01*
G01X991178Y1583366D02*
X989996Y1584547D01*
G01D02*
X991178Y1583366D01*
G01X989996Y1584547D02*
X991178Y1583366D01*
G01X969918D02*
X968737Y1584547D01*
G01D02*
X969918Y1583366D01*
G01X968737Y1584547D02*
X969918Y1583366D01*
G01X973852Y1591700D02*
X973753Y1591835D01*
G01X972867Y1590662D02*
X972966Y1590528D01*
G01X975098Y1591667D02*
X975164Y1591567D01*
G01X973720Y1591600D02*
X973655Y1591700D01*
G01X973064Y1590662D02*
X972999Y1590762D01*
G01X973917Y1591533D02*
X973852Y1591700D01*
G01X972769Y1591365D02*
X972835Y1591198D01*
G01X975361Y1591600D02*
X975295Y1591734D01*
G01X975164Y1591567D02*
X975197Y1591433D01*
G01X973753Y1591500D02*
X973720Y1591600D01*
G01X972933Y1591399D02*
X972966Y1591298D01*
G01X972835Y1590762D02*
X972867Y1590662D01*
G01X973950Y1591298D02*
X973917Y1591533D01*
G01X975394Y1591433D02*
X975361Y1591600D01*
G01X989996Y1587303D02*
Y1584547D01*
G01X989967Y1590885D02*
Y1584941D01*
G01X986010Y1590885D02*
Y1584941D01*
G01X982880Y1590885D02*
Y1584941D01*
G01X978924Y1590885D02*
Y1584941D01*
G01X975794Y1590885D02*
Y1584941D01*
G01X974409Y1590394D02*
Y1591433D01*
G01X974213D02*
Y1590394D01*
G01X973950Y1591064D02*
Y1591298D01*
G01X973786Y1591131D02*
Y1591064D01*
G01X973753Y1591399D02*
Y1591500D01*
G01X972933D02*
Y1591399D01*
G01X972769Y1591533D02*
Y1591365D01*
G01X971837Y1590885D02*
Y1584941D01*
G01X971807Y1584547D02*
Y1587303D01*
G01X968737D02*
Y1584547D01*
G01X968707Y1590885D02*
Y1584941D01*
G01X966831Y1706299D02*
Y1582382D01*
G01X966729Y1626791D02*
Y1584941D01*
G01X974245Y1591600D02*
X974213Y1591433D01*
G01X973786Y1591064D02*
X973753Y1590863D01*
G01X973917Y1590830D02*
X973950Y1591064D01*
G01X973753Y1590863D02*
X973720Y1590762D01*
G01Y1591298D02*
X973753Y1591399D01*
G01X972966Y1591600D02*
X972933Y1591500D01*
G01X974409Y1591433D02*
X974442Y1591567D01*
G01X973852Y1590662D02*
X973917Y1590830D01*
G01X972835Y1591700D02*
X972769Y1591533D01*
G01X974442Y1591567D02*
X974508Y1591667D01*
G01X973720Y1590762D02*
X973655Y1590662D01*
G01X974311Y1591734D02*
X974245Y1591600D01*
G01X973753Y1590528D02*
X973852Y1590662D01*
G01X972933Y1591835D02*
X972835Y1591700D01*
G01X973031D02*
X972966Y1591600D01*
G01X970626Y1583366D02*
X971807Y1584547D01*
G01X970626Y1583366D02*
X971807Y1584547D01*
G01X974442Y1591868D02*
X974311Y1591734D01*
G01X973655Y1591231D02*
X973720Y1591298D01*
G01X973589Y1590427D02*
X973753Y1590528D01*
G01X973097Y1591935D02*
X972933Y1591835D01*
G01X973655Y1590662D02*
X973556Y1590595D01*
G01X973589Y1590997D02*
X973786Y1591131D01*
G01X974508Y1591667D02*
X974606Y1591734D01*
G01X973556Y1591165D02*
X973655Y1591231D01*
G01X973130Y1591768D02*
X973031Y1591700D01*
G01X973556Y1590595D02*
X973458Y1590561D01*
G01Y1591131D02*
X973556Y1591165D01*
G01X973228Y1591801D02*
X973130Y1591768D01*
G01X974574Y1591935D02*
X974442Y1591868D01*
G01X988071Y1648307D02*
G03I-1457J0D01*
G01Y1642402D02*
G03I-1457J0D01*
G01Y1636496D02*
G03I-1457J0D01*
G01X975472Y1648307D02*
G03I-1456J0D01*
G01Y1642402D02*
G03I-1456J0D01*
G01Y1636496D02*
G03I-1456J0D01*
G01X989957Y1629941D02*
G03X993107I1575J0D01*
G01X988071Y1625669D02*
G03I-1457J0D01*
G01Y1619764D02*
G03I-1457J0D01*
G01X975472Y1625669D02*
G03I-1456J0D01*
G01Y1619764D02*
G03I-1456J0D01*
G01X968304Y1628366D02*
G03X966729Y1626791I0J-1575D01*
G01X970272Y1628366D02*
G03X971847Y1629941I0J1575D01*
G01X982870D02*
G03X986020I1575J0D01*
G01X975784D02*
G03X978933I1574J0D01*
G01X966831Y1659429D02*
X993799D01*
G01X968638Y1650138D02*
X966831D01*
G01X975725D02*
X971906D01*
G01X982811D02*
X978993D01*
G01X989898D02*
X986079D01*
G01X974406Y1648839D02*
X973225D01*
G01X981493D02*
X980311D01*
G01X988579D02*
X987398D01*
G01X990774Y1634523D02*
X992289D01*
G01X971030D02*
X969515D01*
G01X978116D02*
X976601D01*
G01X985203D02*
X983688D01*
G01X993799Y1629830D02*
X966831D01*
G01X970272Y1628366D02*
X968304D01*
G01X993799Y1627307D02*
X966831D01*
G01X990774Y1634523D02*
X989898Y1635400D01*
G01X983688Y1634523D02*
X982811Y1635400D01*
G01X976601Y1634523D02*
X975725Y1635400D01*
G01X968638D02*
X969515Y1634523D01*
G01X988579Y1648839D02*
X989898Y1646554D01*
G01X981493Y1648839D02*
X982811Y1646554D01*
G01X974406Y1648839D02*
X975725Y1646554D01*
G01X989957Y1635341D02*
Y1629941D01*
G01X989898Y1650138D02*
Y1635400D01*
G01X986079D02*
Y1650138D01*
G01X986020Y1635341D02*
Y1629941D01*
G01X982870Y1635341D02*
Y1629941D01*
G01X982811Y1650138D02*
Y1635400D01*
G01X978993D02*
Y1650138D01*
G01X978933Y1635341D02*
Y1629941D01*
G01X975784Y1635341D02*
Y1629941D01*
G01X975725Y1650138D02*
Y1635400D01*
G01X971906D02*
Y1650138D01*
G01X971847Y1635341D02*
Y1629941D01*
G01X968638Y1650138D02*
Y1635400D01*
G01X987398Y1648839D02*
X986079Y1646554D01*
G01X980311Y1648839D02*
X978993Y1646554D01*
G01X973225Y1648839D02*
X971906Y1646554D01*
G01X986079Y1635400D02*
X985203Y1634523D01*
G01X978993Y1635400D02*
X978116Y1634523D01*
G01X971906Y1635400D02*
X971030Y1634523D01*
G01X990650Y1670079D02*
G03X991240Y1670669I0J590D01*
G01X969390D02*
G03X969980Y1670079I590J0D01*
G01X966831Y1706299D02*
X993799D01*
G01X969390Y1705512D02*
X968209D01*
G01X975591Y1705315D02*
X972441D01*
G01X988189D02*
X985039D01*
G01X972441Y1704724D02*
X968996D01*
G01X985039D02*
X975591D01*
G01X991634D02*
X988189D01*
G01X975591Y1697441D02*
X972441D01*
G01X988189D02*
X985039D01*
G01X991240Y1670669D02*
X969390D01*
G01X968075Y1670079D02*
X992555D01*
G01X991634Y1667570D02*
X968996D01*
G01Y1704724D02*
X967421Y1706299D01*
G01X988189Y1705315D02*
Y1697441D01*
G01X985039Y1705315D02*
Y1697441D01*
G01X975591Y1705315D02*
Y1697441D01*
G01X972441Y1705315D02*
Y1697441D01*
G01X969390Y1670079D02*
Y1706299D01*
G01X968996Y1667570D02*
Y1704724D01*
G01X968075Y1670079D02*
Y1706299D01*
G01X979575Y1841823D02*
Y1822886D01*
G01X1037396Y-120632D02*
X1037402Y-120613D01*
G01X1037382Y-120646D02*
X1037396Y-120632D01*
G01X1037362Y-120652D02*
X1037382Y-120646D01*
G01X1032396Y-120632D02*
X1032402Y-120613D01*
G01X1032382Y-120646D02*
X1032396Y-120632D01*
G01X1032362Y-120652D02*
X1032382Y-120646D01*
G01X1027396Y-120632D02*
X1027402Y-120613D01*
G01X1027382Y-120646D02*
X1027396Y-120632D01*
G01X1027362Y-120652D02*
X1027382Y-120646D01*
G01X1022396Y-120632D02*
X1022402Y-120613D01*
G01X1022382Y-120646D02*
X1022396Y-120632D01*
G01X1022362Y-120652D02*
X1022382Y-120646D01*
G01X1017396Y-120632D02*
X1017402Y-120613D01*
G01X1017382Y-120646D02*
X1017396Y-120632D01*
G01X1017362Y-120652D02*
X1017382Y-120646D01*
G01X1001635Y-107217D02*
X1001644Y-107209D01*
G01X1001625Y-107221D02*
X1001635Y-107217D01*
G01X1001614Y-107223D02*
X1001625Y-107221D01*
G01X1014234Y-107217D02*
X1014242Y-107209D01*
G01X1014224Y-107221D02*
X1014234Y-107217D01*
G01X1014213Y-107223D02*
X1014224Y-107221D01*
G01X1011084Y-107217D02*
X1011093Y-107209D01*
G01X1011074Y-107221D02*
X1011084Y-107217D01*
G01X1011063Y-107223D02*
X1011074Y-107221D01*
G01X1007935Y-107217D02*
X1007943Y-107209D01*
G01X1007924Y-107221D02*
X1007935Y-107217D01*
G01X1007913Y-107223D02*
X1007924Y-107221D01*
G01X1004785Y-107217D02*
X1004793Y-107209D01*
G01X1004775Y-107221D02*
X1004785Y-107217D01*
G01X1004764Y-107223D02*
X1004775Y-107221D01*
G01X998486Y-107217D02*
X998494Y-107209D01*
G01X998476Y-107221D02*
X998486Y-107217D01*
G01X998465Y-107223D02*
X998476Y-107221D01*
G01X1037500Y-120617D02*
X1037598Y-120620D01*
G01X1037428Y-120611D02*
X1037500Y-120617D01*
G01X1037402Y-120613D02*
X1037428Y-120611D01*
G01X1032500Y-120617D02*
X1032598Y-120620D01*
G01X1032428Y-120611D02*
X1032500Y-120617D01*
G01X1032402Y-120613D02*
X1032428Y-120611D01*
G01X1027500Y-120617D02*
X1027598Y-120620D01*
G01X1027428Y-120611D02*
X1027500Y-120617D01*
G01X1027402Y-120613D02*
X1027428Y-120611D01*
G01X1022500Y-120617D02*
X1022598Y-120620D01*
G01X1022428Y-120611D02*
X1022500Y-120617D01*
G01X1022402Y-120613D02*
X1022428Y-120611D01*
G01X1017500Y-120617D02*
X1017598Y-120620D01*
G01X1017428Y-120611D02*
X1017500Y-120617D01*
G01X1017402Y-120613D02*
X1017428Y-120611D01*
G01X992500Y-120617D02*
X992598Y-120620D01*
G01X992428Y-120611D02*
X992500Y-120617D01*
G01X992402Y-120613D02*
X992428Y-120611D01*
G01X1006805Y-106240D02*
X1006798D01*
G01X1006809Y-106239D02*
X1006805Y-106240D01*
G01X1006800Y-106239D02*
X1006809D01*
G01X995539Y-106280D02*
X995551D01*
G01X995526Y-106277D02*
X995539Y-106280D01*
G01X995512Y-106277D02*
X995526D01*
G01X998689Y-106280D02*
X998701D01*
G01X998676Y-106277D02*
X998689Y-106280D01*
G01X998662Y-106277D02*
X998676D01*
G01X1001838Y-106280D02*
X1001850D01*
G01X1001825Y-106277D02*
X1001838Y-106280D01*
G01X1001811Y-106277D02*
X1001825D01*
G01X1004988Y-106280D02*
X1005000D01*
G01X1004975Y-106277D02*
X1004988Y-106280D01*
G01X1004961Y-106277D02*
X1004975D01*
G01X1008137Y-106280D02*
X1008150D01*
G01X1008124Y-106277D02*
X1008137Y-106280D01*
G01X1008111Y-106277D02*
X1008124D01*
G01X1011287Y-106280D02*
X1011299D01*
G01X1011274Y-106277D02*
X1011287Y-106280D01*
G01X1011260Y-106277D02*
X1011274D01*
G01X1014437Y-106280D02*
X1014449D01*
G01X1014424Y-106277D02*
X1014437Y-106280D01*
G01X1014410Y-106277D02*
X1014424D01*
G01X1016022Y-119666D02*
X1016024Y-119667D01*
G01X1016017Y-119665D02*
X1016022Y-119666D01*
G01X1016007Y-119665D02*
X1016017D01*
G01X1021022Y-119666D02*
X1021024Y-119667D01*
G01X1021017Y-119665D02*
X1021022Y-119666D01*
G01X1021007Y-119665D02*
X1021017D01*
G01X1026022Y-119666D02*
X1026024Y-119667D01*
G01X1026017Y-119665D02*
X1026022Y-119666D01*
G01X1026007Y-119665D02*
X1026017D01*
G01X1031022Y-119666D02*
X1031024Y-119667D01*
G01X1031017Y-119665D02*
X1031022Y-119666D01*
G01X1031007Y-119665D02*
X1031017D01*
G01X1036022Y-119666D02*
X1036024Y-119667D01*
G01X1036017Y-119665D02*
X1036022Y-119666D01*
G01X1036007Y-119665D02*
X1036017D01*
G01X1013105Y-106240D02*
X1013097D01*
G01X1013109Y-106239D02*
X1013105Y-106240D01*
G01X1013101Y-106239D02*
X1013109D01*
G01X994002Y-106277D02*
X994015Y-106276D01*
G01X993989Y-106280D02*
X994002Y-106277D01*
G01X993976Y-106280D02*
X993989D01*
G01X997151Y-106277D02*
X997165Y-106276D01*
G01X997139Y-106280D02*
X997151Y-106277D01*
G01X997126Y-106280D02*
X997139D01*
G01X1000301Y-106277D02*
X1000315Y-106276D01*
G01X1000288Y-106280D02*
X1000301Y-106277D01*
G01X1000276Y-106280D02*
X1000288D01*
G01X1003450Y-106277D02*
X1003464Y-106276D01*
G01X1003438Y-106280D02*
X1003450Y-106277D01*
G01X1003425Y-106280D02*
X1003438D01*
G01X1006600Y-106277D02*
X1006614Y-106276D01*
G01X1006587Y-106280D02*
X1006600Y-106277D01*
G01X1006575Y-106280D02*
X1006587D01*
G01X995526Y-107187D02*
X995512Y-107189D01*
G01X995539Y-107184D02*
X995526Y-107187D01*
G01X995551Y-107185D02*
X995539Y-107184D01*
G01X998675Y-107187D02*
X998662Y-107189D01*
G01X998688Y-107184D02*
X998675Y-107187D01*
G01X998701Y-107185D02*
X998688Y-107184D01*
G01X1001825Y-107187D02*
X1001811Y-107189D01*
G01X1001838Y-107184D02*
X1001825Y-107187D01*
G01X1001850Y-107185D02*
X1001838Y-107184D01*
G01X1004974Y-107187D02*
X1004961Y-107189D01*
G01X1004987Y-107184D02*
X1004974Y-107187D01*
G01X1005000Y-107185D02*
X1004987Y-107184D01*
G01X1008124Y-107187D02*
X1008111Y-107189D01*
G01X1008137Y-107184D02*
X1008124Y-107187D01*
G01X1008150Y-107185D02*
X1008137Y-107184D01*
G01X1011274Y-107187D02*
X1011260Y-107189D01*
G01X1011287Y-107184D02*
X1011274Y-107187D01*
G01X1011299Y-107185D02*
X1011287Y-107184D01*
G01X1014423Y-107187D02*
X1014410Y-107189D01*
G01X1014436Y-107184D02*
X1014423Y-107187D01*
G01X1014449Y-107185D02*
X1014436Y-107184D01*
G01X992396Y-120632D02*
X992402Y-120613D01*
G01X992382Y-120646D02*
X992396Y-120632D01*
G01X992362Y-120652D02*
X992382Y-120646D01*
G01X995336Y-107217D02*
X995344Y-107209D01*
G01X995326Y-107221D02*
X995336Y-107217D01*
G01X995315Y-107223D02*
X995326Y-107221D01*
G01X1009750Y-106277D02*
X1009763Y-106276D01*
G01X1009737Y-106280D02*
X1009750Y-106277D01*
G01X1009724Y-106280D02*
X1009737D01*
G01X1012899Y-106277D02*
X1012913Y-106276D01*
G01X1012887Y-106280D02*
X1012899Y-106277D01*
G01X1012874Y-106280D02*
X1012887D01*
G01X1000506Y-106240D02*
X1000498D01*
G01X1000510Y-106239D02*
X1000506Y-106240D01*
G01X1000504Y-106239D02*
X1000510D01*
G01X1009955Y-106240D02*
X1009947D01*
G01X1009959Y-106239D02*
X1009955Y-106240D01*
G01X1009952Y-106239D02*
X1009959D01*
G01X993989Y-107184D02*
X993976Y-107185D01*
G01X994002Y-107187D02*
X993989Y-107184D01*
G01X994015Y-107188D02*
X994002Y-107187D01*
G01X997139Y-107184D02*
X997126Y-107185D01*
G01X997152Y-107187D02*
X997139Y-107184D01*
G01X997165Y-107188D02*
X997152Y-107187D01*
G01X1000288Y-107184D02*
X1000276Y-107185D01*
G01X1000301Y-107187D02*
X1000288Y-107184D01*
G01X1000315Y-107188D02*
X1000301Y-107187D01*
G01X1003438Y-107184D02*
X1003425Y-107185D01*
G01X1003451Y-107187D02*
X1003438Y-107184D01*
G01X1003464Y-107188D02*
X1003451Y-107187D01*
G01X1006587Y-107184D02*
X1006575Y-107185D01*
G01X1006600Y-107187D02*
X1006587Y-107184D01*
G01X1006614Y-107188D02*
X1006600Y-107187D01*
G01X1009737Y-107184D02*
X1009724Y-107185D01*
G01X1009750Y-107187D02*
X1009737Y-107184D01*
G01X1009763Y-107188D02*
X1009750Y-107187D01*
G01X1012887Y-107184D02*
X1012874Y-107185D01*
G01X1012900Y-107187D02*
X1012887Y-107184D01*
G01X1012913Y-107188D02*
X1012900Y-107187D01*
G01X994207Y-106240D02*
X994199D01*
G01X994211Y-106239D02*
X994207Y-106240D01*
G01X994205Y-106238D02*
X994211Y-106239D01*
G01X995346Y-106253D02*
X995354Y-106277D01*
G01X995331Y-106242D02*
X995346Y-106253D01*
G01X995324Y-106240D02*
X995331Y-106242D01*
G01X998496Y-106253D02*
X998504Y-106277D01*
G01X998481Y-106242D02*
X998496Y-106253D01*
G01X998474Y-106240D02*
X998481Y-106242D01*
G01X1001645Y-106253D02*
X1001654Y-106277D01*
G01X1001630Y-106242D02*
X1001645Y-106253D01*
G01X1001624Y-106240D02*
X1001630Y-106242D01*
G01X1004795Y-106253D02*
X1004803Y-106277D01*
G01X1004780Y-106242D02*
X1004795Y-106253D01*
G01X1004773Y-106240D02*
X1004780Y-106242D01*
G01X1007944Y-106253D02*
X1007953Y-106277D01*
G01X1007930Y-106242D02*
X1007944Y-106253D01*
G01X1007923Y-106240D02*
X1007930Y-106242D01*
G01X1011094Y-106253D02*
X1011102Y-106277D01*
G01X1011079Y-106242D02*
X1011094Y-106253D01*
G01X1011072Y-106240D02*
X1011079Y-106242D01*
G01X1014244Y-106253D02*
X1014252Y-106277D01*
G01X1014229Y-106242D02*
X1014244Y-106253D01*
G01X1014222Y-106240D02*
X1014229Y-106242D01*
G01X995321Y-107224D02*
X995328D01*
G01X995317D02*
X995321D01*
G01X995315Y-107223D02*
X995317Y-107224D01*
G01X998471D02*
X998478D01*
G01X998467D02*
X998471D01*
G01X998465Y-107223D02*
X998467Y-107224D01*
G01X1001620D02*
X1001628D01*
G01X1001616D02*
X1001620D01*
G01X1001614Y-107223D02*
X1001616Y-107224D01*
G01X1004770D02*
X1004777D01*
G01X1004766D02*
X1004770D01*
G01X1004764Y-107223D02*
X1004766Y-107224D01*
G01X1007920D02*
X1007927D01*
G01X1007915D02*
X1007920D01*
G01X1007913Y-107223D02*
X1007915Y-107224D01*
G01X1011069D02*
X1011076D01*
G01X1011065D02*
X1011069D01*
G01X1011063Y-107223D02*
X1011065Y-107224D01*
G01X1014219D02*
X1014226D01*
G01X1014215D02*
X1014219D01*
G01X1014213Y-107223D02*
X1014215Y-107224D01*
G01X1003656Y-106240D02*
X1003648D01*
G01X1003660Y-106239D02*
X1003656Y-106240D01*
G01X1003657Y-106238D02*
X1003660Y-106239D01*
G01X997356Y-106240D02*
X997349D01*
G01X997361Y-106239D02*
X997356Y-106240D01*
G01X997359Y-106238D02*
X997361Y-106239D01*
G01X995359Y-107185D02*
X995366D01*
G01X995356Y-107184D02*
X995359Y-107185D01*
G01X995354Y-107183D02*
X995356Y-107184D01*
G01X998509Y-107185D02*
X998515D01*
G01X998505Y-107184D02*
X998509Y-107185D01*
G01X998504Y-107183D02*
X998505Y-107184D01*
G01X1001659Y-107185D02*
X1001665D01*
G01X1001655Y-107184D02*
X1001659Y-107185D01*
G01X1001654Y-107183D02*
X1001655Y-107184D01*
G01X1004808Y-107185D02*
X1004815D01*
G01X1004804Y-107184D02*
X1004808Y-107185D01*
G01X1004803Y-107183D02*
X1004804Y-107184D01*
G01X1007958Y-107185D02*
X1007964D01*
G01X1007954Y-107184D02*
X1007958Y-107185D01*
G01X1007953Y-107183D02*
X1007954Y-107184D01*
G01X1011107Y-107185D02*
X1011114D01*
G01X1011104Y-107184D02*
X1011107Y-107185D01*
G01X1011102Y-107183D02*
X1011104Y-107184D01*
G01X1014257Y-107185D02*
X1014263D01*
G01X1014253Y-107184D02*
X1014257Y-107185D01*
G01X1014252Y-107183D02*
X1014253Y-107184D01*
G01X1016016Y-120650D02*
X1016007D01*
G01X1016022Y-120651D02*
X1016016Y-120650D01*
G01X1016024Y-120652D02*
X1016022Y-120651D01*
G01X1021016Y-120650D02*
X1021007D01*
G01X1021022Y-120651D02*
X1021016Y-120650D01*
G01X1021024Y-120652D02*
X1021022Y-120651D01*
G01X1026016Y-120650D02*
X1026007D01*
G01X1026022Y-120651D02*
X1026016Y-120650D01*
G01X1026024Y-120652D02*
X1026022Y-120651D01*
G01X1031016Y-120650D02*
X1031007D01*
G01X1031022Y-120651D02*
X1031016Y-120650D01*
G01X1031024Y-120652D02*
X1031022Y-120651D01*
G01X1036016Y-120650D02*
X1036007D01*
G01X1036022Y-120651D02*
X1036016Y-120650D01*
G01X1036024Y-120652D02*
X1036022Y-120651D01*
G01X995321Y-106240D02*
X995328D01*
G01X995317Y-106239D02*
X995321Y-106240D01*
G01X995315Y-106237D02*
X995317Y-106239D01*
G01X998470Y-106240D02*
X998478D01*
G01X998466Y-106239D02*
X998470Y-106240D01*
G01X998465Y-106237D02*
X998466Y-106239D01*
G01X1001620Y-106240D02*
X1001628D01*
G01X1001616Y-106239D02*
X1001620Y-106240D01*
G01X1001614Y-106237D02*
X1001616Y-106239D01*
G01X1004770Y-106240D02*
X1004777D01*
G01X1004765Y-106239D02*
X1004770Y-106240D01*
G01X1004764Y-106237D02*
X1004765Y-106239D01*
G01X1007919Y-106240D02*
X1007927D01*
G01X1007915Y-106239D02*
X1007919Y-106240D01*
G01X1007913Y-106237D02*
X1007915Y-106239D01*
G01X1011069Y-106240D02*
X1011076D01*
G01X1011065Y-106239D02*
X1011069Y-106240D01*
G01X1011063Y-106237D02*
X1011065Y-106239D01*
G01X1014219Y-106240D02*
X1014226D01*
G01X1014214Y-106239D02*
X1014219Y-106240D01*
G01X1014213Y-106237D02*
X1014214Y-106239D01*
G01X994187Y-107222D02*
X994199Y-107224D01*
G01X994175Y-107215D02*
X994187Y-107222D01*
G01X994167Y-107205D02*
X994175Y-107215D01*
G01X997336Y-107222D02*
X997349Y-107224D01*
G01X997325Y-107215D02*
X997336Y-107222D01*
G01X997317Y-107205D02*
X997325Y-107215D01*
G01X1000486Y-107222D02*
X1000498Y-107224D01*
G01X1000474Y-107215D02*
X1000486Y-107222D01*
G01X1000467Y-107205D02*
X1000474Y-107215D01*
G01X1003635Y-107222D02*
X1003648Y-107224D01*
G01X1003624Y-107215D02*
X1003635Y-107222D01*
G01X1003616Y-107205D02*
X1003624Y-107215D01*
G01X1006785Y-107222D02*
X1006798Y-107224D01*
G01X1006774Y-107215D02*
X1006785Y-107222D01*
G01X1006766Y-107205D02*
X1006774Y-107215D01*
G01X1013084Y-107222D02*
X1013097Y-107224D01*
G01X1013073Y-107215D02*
X1013084Y-107222D01*
G01X1013065Y-107205D02*
X1013073Y-107215D01*
G01X995359Y-106278D02*
X995366Y-106279D01*
G01X995356Y-106278D02*
X995359D01*
G01X995354Y-106277D02*
X995356Y-106278D01*
G01X998509D02*
X998515Y-106279D01*
G01X998505Y-106278D02*
X998509D01*
G01X998504Y-106277D02*
X998505Y-106278D01*
G01X1001658D02*
X1001665Y-106279D01*
G01X1001655Y-106278D02*
X1001658D01*
G01X1001654Y-106277D02*
X1001655Y-106278D01*
G01X1004808D02*
X1004815Y-106279D01*
G01X1004804Y-106278D02*
X1004808D01*
G01X1004803Y-106277D02*
X1004804Y-106278D01*
G01X1007957D02*
X1007964Y-106279D01*
G01X1007954Y-106278D02*
X1007957D01*
G01X1007953Y-106277D02*
X1007954Y-106278D01*
G01X1011107D02*
X1011114Y-106279D01*
G01X1011104Y-106278D02*
X1011107D01*
G01X1011102Y-106277D02*
X1011104Y-106278D01*
G01X1014257D02*
X1014263Y-106279D01*
G01X1014253Y-106278D02*
X1014257D01*
G01X1014252Y-106277D02*
X1014253Y-106278D01*
G01X995335Y-106241D02*
X995328Y-106240D01*
G01X995341Y-106243D02*
X995335Y-106241D01*
G01X995347Y-106245D02*
X995341Y-106243D01*
G01X995352Y-106249D02*
X995347Y-106245D01*
G01X995357Y-106254D02*
X995352Y-106249D01*
G01X995360Y-106259D02*
X995357Y-106254D01*
G01X998485Y-106241D02*
X998478Y-106240D01*
G01X998491Y-106243D02*
X998485Y-106241D01*
G01X998496Y-106245D02*
X998491Y-106243D01*
G01X998502Y-106249D02*
X998496Y-106245D01*
G01X998506Y-106254D02*
X998502Y-106249D01*
G01X998510Y-106259D02*
X998506Y-106254D01*
G01X1001634Y-106241D02*
X1001628Y-106240D01*
G01X1001640Y-106243D02*
X1001634Y-106241D01*
G01X1001646Y-106245D02*
X1001640Y-106243D01*
G01X1001651Y-106249D02*
X1001646Y-106245D01*
G01X1001656Y-106254D02*
X1001651Y-106249D01*
G01X1001659Y-106259D02*
X1001656Y-106254D01*
G01X1004784Y-106241D02*
X1004777Y-106240D01*
G01X1004790Y-106243D02*
X1004784Y-106241D01*
G01X1004796Y-106245D02*
X1004790Y-106243D01*
G01X1004801Y-106249D02*
X1004796Y-106245D01*
G01X1004806Y-106254D02*
X1004801Y-106249D01*
G01X1004809Y-106259D02*
X1004806Y-106254D01*
G01X1007933Y-106241D02*
X1007927Y-106240D01*
G01X1007939Y-106243D02*
X1007933Y-106241D01*
G01X1007945Y-106245D02*
X1007939Y-106243D01*
G01X1007950Y-106249D02*
X1007945Y-106245D01*
G01X1007955Y-106254D02*
X1007950Y-106249D01*
G01X1007959Y-106259D02*
X1007955Y-106254D01*
G01X1011083Y-106241D02*
X1011076Y-106240D01*
G01X1011089Y-106243D02*
X1011083Y-106241D01*
G01X1011095Y-106245D02*
X1011089Y-106243D01*
G01X1011100Y-106249D02*
X1011095Y-106245D01*
G01X1011105Y-106254D02*
X1011100Y-106249D01*
G01X1011108Y-106259D02*
X1011105Y-106254D01*
G01X1014233Y-106241D02*
X1014226Y-106240D01*
G01X1014239Y-106243D02*
X1014233Y-106241D01*
G01X1014244Y-106245D02*
X1014239Y-106243D01*
G01X1014250Y-106249D02*
X1014244Y-106245D01*
G01X1014254Y-106254D02*
X1014250Y-106249D01*
G01X1014258Y-106259D02*
X1014254Y-106254D01*
G01X994175Y-107195D02*
X994173Y-107183D01*
G01X994180Y-107206D02*
X994175Y-107195D01*
G01X997325D02*
X997323Y-107183D01*
G01X997330Y-107206D02*
X997325Y-107195D01*
G01X1000474D02*
X1000472Y-107183D01*
G01X1000480Y-107206D02*
X1000474Y-107195D01*
G01X1003624D02*
X1003622Y-107183D01*
G01X1003629Y-107206D02*
X1003624Y-107195D01*
G01X1006774D02*
X1006772Y-107183D01*
G01X1006779Y-107206D02*
X1006774Y-107195D01*
G01X1009923D02*
X1009921Y-107183D01*
G01X1009928Y-107206D02*
X1009923Y-107195D01*
G01X1013073D02*
X1013071Y-107183D01*
G01X1013078Y-107206D02*
X1013073Y-107195D01*
G01X995335Y-106243D02*
X995315Y-106237D01*
G01X995349Y-106257D02*
X995335Y-106243D01*
G01X995354Y-106277D02*
X995349Y-106257D01*
G01X998484Y-106243D02*
X998465Y-106237D01*
G01X998499Y-106257D02*
X998484Y-106243D01*
G01X998504Y-106277D02*
X998499Y-106257D01*
G01X1001634Y-106243D02*
X1001614Y-106237D01*
G01X1001648Y-106257D02*
X1001634Y-106243D01*
G01X1001654Y-106277D02*
X1001648Y-106257D01*
G01X1004783Y-106243D02*
X1004764Y-106237D01*
G01X1004798Y-106257D02*
X1004783Y-106243D01*
G01X1004803Y-106277D02*
X1004798Y-106257D01*
G01X1007933Y-106243D02*
X1007913Y-106237D01*
G01X1007948Y-106257D02*
X1007933Y-106243D01*
G01X1007953Y-106277D02*
X1007948Y-106257D01*
G01X1011083Y-106243D02*
X1011063Y-106237D01*
G01X1011097Y-106257D02*
X1011083Y-106243D01*
G01X1011102Y-106277D02*
X1011097Y-106257D01*
G01X1014232Y-106243D02*
X1014213Y-106237D01*
G01X1014247Y-106257D02*
X1014232Y-106243D01*
G01X1014252Y-106277D02*
X1014247Y-106257D01*
G01X994193Y-107217D02*
X994213Y-107223D01*
G01X994178Y-107203D02*
X994193Y-107217D01*
G01X994173Y-107183D02*
X994178Y-107203D01*
G01X997343Y-107217D02*
X997362Y-107223D01*
G01X997328Y-107203D02*
X997343Y-107217D01*
G01X997323Y-107183D02*
X997328Y-107203D01*
G01X1000492Y-107217D02*
X1000512Y-107223D01*
G01X1000478Y-107203D02*
X1000492Y-107217D01*
G01X1000472Y-107183D02*
X1000478Y-107203D01*
G01X1003642Y-107217D02*
X1003661Y-107223D01*
G01X1003627Y-107203D02*
X1003642Y-107217D01*
G01X1003622Y-107183D02*
X1003627Y-107203D01*
G01X1006791Y-107217D02*
X1006811Y-107223D01*
G01X1006777Y-107203D02*
X1006791Y-107217D01*
G01X1006772Y-107183D02*
X1006777Y-107203D01*
G01X1009941Y-107217D02*
X1009961Y-107223D01*
G01X1009926Y-107203D02*
X1009941Y-107217D01*
G01X1009921Y-107183D02*
X1009926Y-107203D01*
G01X1013091Y-107217D02*
X1013110Y-107223D01*
G01X1013076Y-107203D02*
X1013091Y-107217D01*
G01X1013071Y-107183D02*
X1013076Y-107203D01*
G01X1009940Y-107224D02*
X1009947D01*
G01X1009933Y-107221D02*
X1009940Y-107224D01*
G01X1009926Y-107218D02*
X1009933Y-107221D01*
G01X1009921Y-107213D02*
X1009926Y-107218D01*
G01X1009916Y-107207D02*
X1009921Y-107213D01*
G01X1009913Y-107200D02*
X1009916Y-107207D01*
G01X1009911Y-107193D02*
X1009913Y-107200D01*
G01X1009910Y-107185D02*
X1009911Y-107193D01*
G01X994166Y-107202D02*
X994167Y-107205D01*
G01X994164Y-107199D02*
X994166Y-107202D01*
G01X994163Y-107195D02*
X994164Y-107199D01*
G01X994163Y-107192D02*
Y-107195D01*
G01X994162Y-107188D02*
X994163Y-107192D01*
G01X994162Y-107185D02*
Y-107188D01*
G01X995362Y-106262D02*
X995360Y-106259D01*
G01X995363Y-106265D02*
X995362Y-106262D01*
G01X995364Y-106269D02*
X995363Y-106265D01*
G01X995365Y-106272D02*
X995364Y-106269D01*
G01X995365Y-106276D02*
Y-106272D01*
G01X995366Y-106280D02*
X995365Y-106276D01*
G01X997315Y-107202D02*
X997317Y-107205D01*
G01X997314Y-107199D02*
X997315Y-107202D01*
G01X997313Y-107195D02*
X997314Y-107199D01*
G01X997312Y-107192D02*
X997313Y-107195D01*
G01X997312Y-107188D02*
Y-107192D01*
G01X997311Y-107185D02*
X997312Y-107188D01*
G01X998511Y-106262D02*
X998510Y-106259D01*
G01X998513Y-106265D02*
X998511Y-106262D01*
G01X998514Y-106269D02*
X998513Y-106265D01*
G01X998515Y-106272D02*
X998514Y-106269D01*
G01X998515Y-106276D02*
Y-106272D01*
G01Y-106280D02*
Y-106276D01*
G01X1000465Y-107202D02*
X1000467Y-107205D01*
G01X1000463Y-107199D02*
X1000465Y-107202D01*
G01X1000463Y-107195D02*
Y-107199D01*
G01X1000462Y-107192D02*
X1000463Y-107195D01*
G01X1000461Y-107188D02*
X1000462Y-107192D01*
G01X1000461Y-107185D02*
Y-107188D01*
G01X1001661Y-106262D02*
X1001659Y-106259D01*
G01X1001663Y-106265D02*
X1001661Y-106262D01*
G01X1001663Y-106269D02*
Y-106265D01*
G01X1001664Y-106272D02*
X1001663Y-106269D01*
G01X1001665Y-106276D02*
X1001664Y-106272D01*
G01X1001665Y-106280D02*
Y-106276D01*
G01X1003615Y-107202D02*
X1003616Y-107205D01*
G01X1003613Y-107199D02*
X1003615Y-107202D01*
G01X1003612Y-107195D02*
X1003613Y-107199D01*
G01X1003611Y-107192D02*
X1003612Y-107195D01*
G01X1003611Y-107188D02*
Y-107192D01*
G01Y-107185D02*
Y-107188D01*
G01X1004811Y-106262D02*
X1004809Y-106259D01*
G01X1004812Y-106265D02*
X1004811Y-106262D01*
G01X1004813Y-106269D02*
X1004812Y-106265D01*
G01X1004814Y-106272D02*
X1004813Y-106269D01*
G01X1004814Y-106276D02*
Y-106272D01*
G01X1004815Y-106280D02*
X1004814Y-106276D01*
G01X1006764Y-107202D02*
X1006766Y-107205D01*
G01X1006763Y-107199D02*
X1006764Y-107202D01*
G01X1006762Y-107195D02*
X1006763Y-107199D01*
G01X1006761Y-107192D02*
X1006762Y-107195D01*
G01X1006761Y-107188D02*
Y-107192D01*
G01X1006760Y-107185D02*
X1006761Y-107188D01*
G01X1007960Y-106262D02*
X1007959Y-106259D01*
G01X1007962Y-106265D02*
X1007960Y-106262D01*
G01X1007963Y-106269D02*
X1007962Y-106265D01*
G01X1007963Y-106272D02*
Y-106269D01*
G01X1007964Y-106276D02*
X1007963Y-106272D01*
G01X1007964Y-106280D02*
Y-106276D01*
G01X1011110Y-106262D02*
X1011108Y-106259D01*
G01X1011111Y-106265D02*
X1011110Y-106262D01*
G01X1011112Y-106269D02*
X1011111Y-106265D01*
G01X1011113Y-106272D02*
X1011112Y-106269D01*
G01X1011113Y-106276D02*
Y-106272D01*
G01X1011114Y-106280D02*
X1011113Y-106276D01*
G01X1013063Y-107202D02*
X1013065Y-107205D01*
G01X1013062Y-107199D02*
X1013063Y-107202D01*
G01X1013061Y-107195D02*
X1013062Y-107199D01*
G01X1013060Y-107192D02*
X1013061Y-107195D01*
G01X1013060Y-107188D02*
Y-107192D01*
G01X1013059Y-107185D02*
X1013060Y-107188D01*
G01X1014259Y-106262D02*
X1014258Y-106259D01*
G01X1014261Y-106265D02*
X1014259Y-106262D01*
G01X1014262Y-106269D02*
X1014261Y-106265D01*
G01X1014263Y-106272D02*
X1014262Y-106269D01*
G01X1014263Y-106276D02*
Y-106272D01*
G01Y-106280D02*
Y-106276D01*
G01X995353Y-107215D02*
X995348Y-107219D01*
G01X995357Y-107210D02*
X995353Y-107215D01*
G01X995361Y-107204D02*
X995357Y-107210D01*
G01X995363Y-107198D02*
X995361Y-107204D01*
G01X995365Y-107192D02*
X995363Y-107198D01*
G01X995366Y-107185D02*
X995365Y-107192D01*
G01X998502Y-107215D02*
X998497Y-107219D01*
G01X998507Y-107210D02*
X998502Y-107215D01*
G01X998511Y-107204D02*
X998507Y-107210D01*
G01X998513Y-107198D02*
X998511Y-107204D01*
G01X998515Y-107192D02*
X998513Y-107198D01*
G01X998515Y-107185D02*
Y-107192D01*
G01X1001652Y-107215D02*
X1001647Y-107219D01*
G01X1001656Y-107210D02*
X1001652Y-107215D01*
G01X1001660Y-107204D02*
X1001656Y-107210D01*
G01X1001663Y-107198D02*
X1001660Y-107204D01*
G01X1001664Y-107192D02*
X1001663Y-107198D01*
G01X1001665Y-107185D02*
X1001664Y-107192D01*
G01X1004802Y-107215D02*
X1004796Y-107219D01*
G01X1004806Y-107210D02*
X1004802Y-107215D01*
G01X1004810Y-107204D02*
X1004806Y-107210D01*
G01X1004812Y-107198D02*
X1004810Y-107204D01*
G01X1004814Y-107192D02*
X1004812Y-107198D01*
G01X1004815Y-107185D02*
X1004814Y-107192D01*
G01X1007951Y-107215D02*
X1007946Y-107219D01*
G01X1007956Y-107210D02*
X1007951Y-107215D01*
G01X1007959Y-107204D02*
X1007956Y-107210D01*
G01X1007962Y-107198D02*
X1007959Y-107204D01*
G01X1007963Y-107192D02*
X1007962Y-107198D01*
G01X1007964Y-107185D02*
X1007963Y-107192D01*
G01X1011101Y-107215D02*
X1011096Y-107219D01*
G01X1011105Y-107210D02*
X1011101Y-107215D01*
G01X1011109Y-107204D02*
X1011105Y-107210D01*
G01X1011111Y-107198D02*
X1011109Y-107204D01*
G01X1011113Y-107192D02*
X1011111Y-107198D01*
G01X1011114Y-107185D02*
X1011113Y-107192D01*
G01X1014250Y-107215D02*
X1014245Y-107219D01*
G01X1014255Y-107210D02*
X1014250Y-107215D01*
G01X1014259Y-107204D02*
X1014255Y-107210D01*
G01X1014261Y-107198D02*
X1014259Y-107204D01*
G01X1014263Y-107192D02*
X1014261Y-107198D01*
G01X1014263Y-107185D02*
Y-107192D01*
G01X994192Y-106241D02*
X994199Y-106240D01*
G01X994185Y-106243D02*
X994192Y-106241D01*
G01X994178Y-106247D02*
X994185Y-106243D01*
G01X994173Y-106252D02*
X994178Y-106247D01*
G01X994168Y-106257D02*
X994173Y-106252D01*
G01X994165Y-106265D02*
X994168Y-106257D01*
G01X994163Y-106272D02*
X994165Y-106265D01*
G01X994162Y-106280D02*
X994163Y-106272D01*
G01X997341Y-106241D02*
X997349Y-106240D01*
G01X997335Y-106243D02*
X997341Y-106241D01*
G01X997328Y-106247D02*
X997335Y-106243D01*
G01X997322Y-106252D02*
X997328Y-106247D01*
G01X997318Y-106257D02*
X997322Y-106252D01*
G01X997315Y-106265D02*
X997318Y-106257D01*
G01X997312Y-106272D02*
X997315Y-106265D01*
G01X997311Y-106280D02*
X997312Y-106272D01*
G01X1000491Y-106241D02*
X1000498Y-106240D01*
G01X1000484Y-106243D02*
X1000491Y-106241D01*
G01X1000478Y-106247D02*
X1000484Y-106243D01*
G01X1000472Y-106252D02*
X1000478Y-106247D01*
G01X1000467Y-106257D02*
X1000472Y-106252D01*
G01X1000464Y-106265D02*
X1000467Y-106257D01*
G01X1000462Y-106272D02*
X1000464Y-106265D01*
G01X1000461Y-106280D02*
X1000462Y-106272D01*
G01X1003641Y-106241D02*
X1003648Y-106240D01*
G01X1003634Y-106243D02*
X1003641Y-106241D01*
G01X1003627Y-106247D02*
X1003634Y-106243D01*
G01X1003622Y-106252D02*
X1003627Y-106247D01*
G01X1003617Y-106257D02*
X1003622Y-106252D01*
G01X1003614Y-106265D02*
X1003617Y-106257D01*
G01X1003611Y-106272D02*
X1003614Y-106265D01*
G01X1003611Y-106280D02*
Y-106272D01*
G01X1006790Y-106241D02*
X1006798Y-106240D01*
G01X1006783Y-106243D02*
X1006790Y-106241D01*
G01X1006777Y-106247D02*
X1006783Y-106243D01*
G01X1006771Y-106252D02*
X1006777Y-106247D01*
G01X1006767Y-106257D02*
X1006771Y-106252D01*
G01X1006763Y-106265D02*
X1006767Y-106257D01*
G01X1006761Y-106272D02*
X1006763Y-106265D01*
G01X1006760Y-106280D02*
X1006761Y-106272D01*
G01X1009940Y-106241D02*
X1009947Y-106240D01*
G01X1009933Y-106243D02*
X1009940Y-106241D01*
G01X1009926Y-106247D02*
X1009933Y-106243D01*
G01X1009921Y-106252D02*
X1009926Y-106247D01*
G01X1009916Y-106257D02*
X1009921Y-106252D01*
G01X1009913Y-106265D02*
X1009916Y-106257D01*
G01X1009911Y-106272D02*
X1009913Y-106265D01*
G01X1009910Y-106280D02*
X1009911Y-106272D01*
G01X1013089Y-106241D02*
X1013097Y-106240D01*
G01X1013083Y-106243D02*
X1013089Y-106241D01*
G01X1013076Y-106247D02*
X1013083Y-106243D01*
G01X1013070Y-106252D02*
X1013076Y-106247D01*
G01X1013066Y-106257D02*
X1013070Y-106252D01*
G01X1013063Y-106265D02*
X1013066Y-106257D01*
G01X1013060Y-106272D02*
X1013063Y-106265D01*
G01X1013059Y-106280D02*
X1013060Y-106272D01*
G01X995353Y-107194D02*
X995349Y-107204D01*
G01X995354Y-107183D02*
X995353Y-107194D01*
G01X998502D02*
X998498Y-107204D01*
G01X998504Y-107183D02*
X998502Y-107194D01*
G01X1001652D02*
X1001648Y-107204D01*
G01X1001654Y-107183D02*
X1001652Y-107194D01*
G01X1004802D02*
X1004798Y-107204D01*
G01X1004803Y-107183D02*
X1004802Y-107194D01*
G01X1007951D02*
X1007947Y-107204D01*
G01X1007953Y-107183D02*
X1007951Y-107194D01*
G01X1011101D02*
X1011097Y-107204D01*
G01X1011102Y-107183D02*
X1011101Y-107194D01*
G01X1014250D02*
X1014246Y-107204D01*
G01X1014252Y-107183D02*
X1014250Y-107194D01*
G01X997352Y-106240D02*
X997349D01*
G01X997346Y-106242D02*
X997352Y-106240D01*
G01X997331Y-106254D02*
X997346Y-106242D01*
G01X997323Y-106278D02*
X997331Y-106254D01*
G01X1000502Y-106240D02*
X1000498D01*
G01X1000496Y-106242D02*
X1000502Y-106240D01*
G01X1000481Y-106253D02*
X1000496Y-106242D01*
G01X1000472Y-106278D02*
X1000481Y-106253D01*
G01X1006802Y-106240D02*
X1006798D01*
G01X1006795Y-106242D02*
X1006802Y-106240D01*
G01X1006780Y-106253D02*
X1006795Y-106242D01*
G01X1006772Y-106278D02*
X1006780Y-106253D01*
G01X1009951Y-106240D02*
X1009947D01*
G01X1009945Y-106242D02*
X1009951Y-106240D01*
G01X1009930Y-106253D02*
X1009945Y-106242D01*
G01X1009921Y-106278D02*
X1009930Y-106253D01*
G01X994203Y-106240D02*
X994199D01*
G01X994197Y-106242D02*
X994203Y-106240D01*
G01X994181Y-106253D02*
X994197Y-106242D01*
G01X994173Y-106278D02*
X994181Y-106253D01*
G01X1013100Y-106240D02*
X1013097D01*
G01X1013094Y-106242D02*
X1013100Y-106240D01*
G01X1013079Y-106253D02*
X1013094Y-106242D01*
G01X1013071Y-106278D02*
X1013079Y-106253D01*
G01X992393Y-120637D02*
X992378Y-120648D01*
G01X992402Y-120613D02*
X992393Y-120637D01*
G01X1017393D02*
X1017378Y-120648D01*
G01X1017402Y-120613D02*
X1017393Y-120637D01*
G01X1022393D02*
X1022378Y-120648D01*
G01X1022402Y-120613D02*
X1022393Y-120637D01*
G01X1027393D02*
X1027378Y-120648D01*
G01X1027402Y-120613D02*
X1027393Y-120637D01*
G01X1032393D02*
X1032378Y-120648D01*
G01X1032402Y-120613D02*
X1032393Y-120637D01*
G01X1037393D02*
X1037378Y-120648D01*
G01X1037402Y-120613D02*
X1037393Y-120637D01*
G01X1003652Y-106240D02*
X1003648D01*
G01X1003646Y-106241D02*
X1003652Y-106240D01*
G01X1003631Y-106252D02*
X1003646Y-106241D01*
G01X1003622Y-106274D02*
X1003631Y-106252D01*
G01X1001652Y-107193D02*
X1001654Y-107183D01*
G01X1001649Y-107202D02*
X1001652Y-107193D01*
G01X1001644Y-107209D02*
X1001649Y-107202D01*
G01X995353Y-107193D02*
X995354Y-107183D01*
G01X995350Y-107202D02*
X995353Y-107193D01*
G01X995344Y-107209D02*
X995350Y-107202D01*
G01X998503Y-107193D02*
X998504Y-107183D01*
G01X998500Y-107202D02*
X998503Y-107193D01*
G01X998494Y-107209D02*
X998500Y-107202D01*
G01X1004802Y-107193D02*
X1004803Y-107183D01*
G01X1004799Y-107202D02*
X1004802Y-107193D01*
G01X1004793Y-107209D02*
X1004799Y-107202D01*
G01X1007952Y-107193D02*
X1007953Y-107183D01*
G01X1007948Y-107202D02*
X1007952Y-107193D01*
G01X1007943Y-107209D02*
X1007948Y-107202D01*
G01X1011101Y-107193D02*
X1011102Y-107183D01*
G01X1011098Y-107202D02*
X1011101Y-107193D01*
G01X1011093Y-107209D02*
X1011098Y-107202D01*
G01X1014251Y-107193D02*
X1014252Y-107183D01*
G01X1014248Y-107202D02*
X1014251Y-107193D01*
G01X1014242Y-107209D02*
X1014248Y-107202D01*
G01X994168Y-106279D02*
X994162Y-106280D01*
G01X994172Y-106278D02*
X994168Y-106279D01*
G01X994173Y-106277D02*
X994172Y-106278D01*
G01X997318Y-106279D02*
X997311Y-106280D01*
G01X997322Y-106278D02*
X997318Y-106279D01*
G01X997323Y-106277D02*
X997322Y-106278D01*
G01X1000467Y-106279D02*
X1000461Y-106280D01*
G01X1000471Y-106278D02*
X1000467Y-106279D01*
G01X1000472Y-106277D02*
X1000471Y-106278D01*
G01X1003617Y-106279D02*
X1003611Y-106280D01*
G01X1003621Y-106278D02*
X1003617Y-106279D01*
G01X1003622Y-106277D02*
X1003621Y-106278D01*
G01X1006767Y-106279D02*
X1006760Y-106280D01*
G01X1006770Y-106278D02*
X1006767Y-106279D01*
G01X1006772Y-106277D02*
X1006770Y-106278D01*
G01X1009916Y-106279D02*
X1009910Y-106280D01*
G01X1009920Y-106278D02*
X1009916Y-106279D01*
G01X1009921Y-106277D02*
X1009920Y-106278D01*
G01X1013066Y-106279D02*
X1013059Y-106280D01*
G01X1013070Y-106278D02*
X1013066Y-106279D01*
G01X1013071Y-106277D02*
X1013070Y-106278D01*
G01X992369Y-120650D02*
X992376D01*
G01X992364D02*
X992369D01*
G01X992362Y-120652D02*
X992364Y-120650D01*
G01X1017369D02*
X1017376D01*
G01X1017364D02*
X1017369D01*
G01X1017362Y-120652D02*
X1017364Y-120650D01*
G01X1022369D02*
X1022376D01*
G01X1022364D02*
X1022369D01*
G01X1022362Y-120652D02*
X1022364Y-120650D01*
G01X1027369D02*
X1027376D01*
G01X1027364D02*
X1027369D01*
G01X1027362Y-120652D02*
X1027364Y-120650D01*
G01X1032369D02*
X1032376D01*
G01X1032364D02*
X1032369D01*
G01X1032362Y-120652D02*
X1032364Y-120650D01*
G01X1037369D02*
X1037376D01*
G01X1037364D02*
X1037369D01*
G01X1037362Y-120652D02*
X1037364Y-120650D01*
G01X997326Y-106263D02*
X997323Y-106277D01*
G01X997332Y-106251D02*
X997326Y-106263D01*
G01X997351Y-106239D02*
X997332Y-106251D01*
G01X1006774Y-106263D02*
X1006772Y-106277D01*
G01X1006781Y-106251D02*
X1006774Y-106263D01*
G01X1006800Y-106239D02*
X1006781Y-106251D01*
G01X1000475Y-106263D02*
X1000472Y-106277D01*
G01X1000483Y-106250D02*
X1000475Y-106263D01*
G01X1000503Y-106239D02*
X1000483Y-106250D01*
G01X1009924Y-106263D02*
X1009921Y-106277D01*
G01X1009932Y-106250D02*
X1009924Y-106263D01*
G01X1009952Y-106239D02*
X1009932Y-106250D01*
G01X994207Y-107224D02*
X994199D01*
G01X994211D02*
X994207D01*
G01X994213Y-107223D02*
X994211Y-107224D01*
G01X997356D02*
X997349D01*
G01X997361D02*
X997356D01*
G01X997362Y-107223D02*
X997361Y-107224D01*
G01X1000506D02*
X1000498D01*
G01X1000510D02*
X1000506D01*
G01X1000512Y-107223D02*
X1000510Y-107224D01*
G01X1003656D02*
X1003648D01*
G01X1003660D02*
X1003656D01*
G01X1003661Y-107223D02*
X1003660Y-107224D01*
G01X1006805D02*
X1006798D01*
G01X1006809D02*
X1006805D01*
G01X1006811Y-107223D02*
X1006809Y-107224D01*
G01X1009955D02*
X1009947D01*
G01X1009959D02*
X1009955D01*
G01X1009961Y-107223D02*
X1009959Y-107224D01*
G01X1013104D02*
X1013097D01*
G01X1013109D02*
X1013104D01*
G01X1013110Y-107223D02*
X1013109Y-107224D01*
G01X1013074Y-106262D02*
X1013071Y-106277D01*
G01X1013082Y-106250D02*
X1013074Y-106262D01*
G01X1013102Y-106239D02*
X1013082Y-106250D01*
G01X994176Y-106262D02*
X994173Y-106277D01*
G01X994185Y-106249D02*
X994176Y-106262D01*
G01X994205Y-106238D02*
X994185Y-106249D01*
G01X995335Y-107224D02*
X995328D01*
G01X995342Y-107222D02*
X995335Y-107224D01*
G01X995348Y-107219D02*
X995342Y-107222D01*
G01X998485Y-107224D02*
X998478D01*
G01X998491Y-107222D02*
X998485Y-107224D01*
G01X998497Y-107219D02*
X998491Y-107222D01*
G01X1001634Y-107224D02*
X1001628D01*
G01X1001641Y-107222D02*
X1001634Y-107224D01*
G01X1001647Y-107219D02*
X1001641Y-107222D01*
G01X1004784Y-107224D02*
X1004777D01*
G01X1004791Y-107222D02*
X1004784Y-107224D01*
G01X1004796Y-107219D02*
X1004791Y-107222D01*
G01X1007933Y-107224D02*
X1007927D01*
G01X1007940Y-107222D02*
X1007933Y-107224D01*
G01X1007946Y-107219D02*
X1007940Y-107222D01*
G01X1011083Y-107224D02*
X1011076D01*
G01X1011090Y-107222D02*
X1011083Y-107224D01*
G01X1011096Y-107219D02*
X1011090Y-107222D01*
G01X1014233Y-107224D02*
X1014226D01*
G01X1014239Y-107222D02*
X1014233Y-107224D01*
G01X1014245Y-107219D02*
X1014239Y-107222D01*
G01X994168Y-107185D02*
X994162D01*
G01X994172Y-107184D02*
X994168Y-107185D01*
G01X994173Y-107183D02*
X994172Y-107184D01*
G01X997318Y-107185D02*
X997311D01*
G01X997322Y-107184D02*
X997318Y-107185D01*
G01X997323Y-107183D02*
X997322Y-107184D01*
G01X1000467Y-107185D02*
X1000461D01*
G01X1000471Y-107184D02*
X1000467Y-107185D01*
G01X1000472Y-107183D02*
X1000471Y-107184D01*
G01X1003617Y-107185D02*
X1003611D01*
G01X1003621Y-107184D02*
X1003617Y-107185D01*
G01X1003622Y-107183D02*
X1003621Y-107184D01*
G01X1006767Y-107185D02*
X1006760D01*
G01X1006770Y-107184D02*
X1006767Y-107185D01*
G01X1006772Y-107183D02*
X1006770Y-107184D01*
G01X1013066Y-107185D02*
X1013059D01*
G01X1013070Y-107184D02*
X1013066Y-107185D01*
G01X1013071Y-107183D02*
X1013070Y-107184D01*
G01X992409Y-119665D02*
X992418D01*
G01X992404Y-119666D02*
X992409Y-119665D01*
G01X992402Y-119667D02*
X992404Y-119666D01*
G01X1017409Y-119665D02*
X1017418D01*
G01X1017404Y-119666D02*
X1017409Y-119665D01*
G01X1017402Y-119667D02*
X1017404Y-119666D01*
G01X1022409Y-119665D02*
X1022418D01*
G01X1022404Y-119666D02*
X1022409Y-119665D01*
G01X1022402Y-119667D02*
X1022404Y-119666D01*
G01X1027409Y-119665D02*
X1027418D01*
G01X1027404Y-119666D02*
X1027409Y-119665D01*
G01X1027402Y-119667D02*
X1027404Y-119666D01*
G01X1032409Y-119665D02*
X1032418D01*
G01X1032404Y-119666D02*
X1032409Y-119665D01*
G01X1032402Y-119667D02*
X1032404Y-119666D01*
G01X1037409Y-119665D02*
X1037418D01*
G01X1037404Y-119666D02*
X1037409Y-119665D01*
G01X1037402Y-119667D02*
X1037404Y-119666D01*
G01X992545Y-120642D02*
X992519Y-120650D01*
G01X992572Y-120632D02*
X992545Y-120642D01*
G01X992598Y-120620D02*
X992572Y-120632D01*
G01X1017545Y-120642D02*
X1017519Y-120650D01*
G01X1017572Y-120632D02*
X1017545Y-120642D01*
G01X1017598Y-120620D02*
X1017572Y-120632D01*
G01X1022545Y-120642D02*
X1022519Y-120650D01*
G01X1022572Y-120632D02*
X1022545Y-120642D01*
G01X1022598Y-120620D02*
X1022572Y-120632D01*
G01X1027545Y-120642D02*
X1027519Y-120650D01*
G01X1027572Y-120632D02*
X1027545Y-120642D01*
G01X1027598Y-120620D02*
X1027572Y-120632D01*
G01X1032545Y-120642D02*
X1032519Y-120650D01*
G01X1032572Y-120632D02*
X1032545Y-120642D01*
G01X1032598Y-120620D02*
X1032572Y-120632D01*
G01X1037545Y-120642D02*
X1037519Y-120650D01*
G01X1037572Y-120632D02*
X1037545Y-120642D01*
G01X1037598Y-120620D02*
X1037572Y-120632D01*
G01X1003627Y-106258D02*
X1003622Y-106277D01*
G01X1003639Y-106244D02*
X1003627Y-106258D01*
G01X1003657Y-106238D02*
X1003639Y-106244D01*
G01X1009921Y-107183D02*
X1009910Y-107187D01*
G01X994350Y-120079D02*
X993169Y-121260D01*
G01X994350Y-116142D02*
X993169Y-117323D01*
G01X1013110Y-106127D02*
X1013102Y-106239D01*
G01X1003657Y-106237D02*
X1003661Y-106127D01*
G01X997359Y-106237D02*
X997362Y-106126D01*
G01X1006807Y-106237D02*
X1006811Y-106126D01*
G01X1037894Y-120650D02*
Y-119665D01*
G01X1037402Y-119667D02*
Y-125000D01*
G01X1037362D02*
Y-120652D01*
G01X1036024Y-125000D02*
Y-119667D01*
G01X1035531Y-119665D02*
Y-120650D01*
G01X1032894D02*
Y-119665D01*
G01X1032402Y-119667D02*
Y-125000D01*
G01X1032362D02*
Y-120652D01*
G01X1031024Y-125000D02*
Y-119667D01*
G01X1030531Y-119665D02*
Y-120650D01*
G01X1027894D02*
Y-119665D01*
G01X1027402Y-119667D02*
Y-125000D01*
G01X1027362D02*
Y-120652D01*
G01X1026024Y-125000D02*
Y-119667D01*
G01X1025531Y-119665D02*
Y-120650D01*
G01X1022894D02*
Y-119665D01*
G01X1022402Y-119667D02*
Y-125000D01*
G01X1022362D02*
Y-120652D01*
G01X1021024Y-125000D02*
Y-119667D01*
G01X1020531Y-119665D02*
Y-120650D01*
G01X1017894D02*
Y-119665D01*
G01X1017402Y-119667D02*
Y-125000D01*
G01X1017362D02*
Y-120652D01*
G01X1016417Y-104331D02*
Y-107677D01*
G01X1016024Y-125000D02*
Y-119667D01*
G01X1015531Y-119665D02*
Y-120650D01*
G01X1015256Y-117323D02*
Y-121260D01*
G01X1014449Y-107185D02*
Y-106280D01*
G01X1014409Y-107224D02*
Y-106240D01*
G01X1014252Y-101299D02*
Y-107183D01*
G01X1014213Y-101299D02*
Y-107223D01*
G01X1014075Y-116142D02*
Y-120079D01*
G01X1013110Y-107223D02*
Y-101299D01*
G01X1013071Y-107183D02*
Y-101299D01*
G01X1012913Y-106240D02*
Y-107224D01*
G01X1012874Y-106280D02*
Y-107185D01*
G01X1011299D02*
Y-106280D01*
G01X1011260Y-107224D02*
Y-106240D01*
G01X1011102Y-101299D02*
Y-107183D01*
G01X1011063Y-101299D02*
Y-107223D01*
G01X1009961D02*
Y-101299D01*
G01X1009921Y-107183D02*
Y-101299D01*
G01X1009764Y-106240D02*
Y-107224D01*
G01X1009724Y-106280D02*
Y-107185D01*
G01X1008150D02*
Y-106280D01*
G01X1008110Y-107224D02*
Y-106240D01*
G01X1007953Y-101299D02*
Y-107183D01*
G01X1007913Y-101299D02*
Y-107223D01*
G01X1006811Y-105493D02*
Y-105059D01*
G01Y-107223D02*
Y-101299D01*
G01X1006772Y-107183D02*
Y-101299D01*
G01X1006614Y-106240D02*
Y-107224D01*
G01X1006575Y-106280D02*
Y-107185D01*
G01X1005000D02*
Y-106280D01*
G01X1004961Y-107224D02*
Y-106240D01*
G01X1004803Y-101299D02*
Y-107183D01*
G01X1004764Y-101299D02*
Y-107223D01*
G01X1003661Y-105493D02*
Y-105059D01*
G01Y-107223D02*
Y-101299D01*
G01X1003622Y-107183D02*
Y-101299D01*
G01X1003465Y-106240D02*
Y-107224D01*
G01X1003425Y-106280D02*
Y-107185D01*
G01X1001850D02*
Y-106280D01*
G01X1001811Y-107224D02*
Y-106240D01*
G01X1001654Y-101299D02*
Y-107183D01*
G01X1001614Y-101299D02*
Y-107223D01*
G01X1000512D02*
Y-101299D01*
G01X1000472Y-107183D02*
Y-101299D01*
G01X1000315Y-106240D02*
Y-107224D01*
G01X1000276Y-106280D02*
Y-107185D01*
G01X998701D02*
Y-106280D01*
G01X998661Y-107224D02*
Y-106240D01*
G01X998504Y-101299D02*
Y-107183D01*
G01X998465Y-101299D02*
Y-107223D01*
G01X997362Y-105493D02*
Y-105059D01*
G01Y-107223D02*
Y-101299D01*
G01X997323Y-107183D02*
Y-101299D01*
G01X997165Y-106240D02*
Y-107224D01*
G01X997126Y-106280D02*
Y-107185D01*
G01X995551D02*
Y-106280D01*
G01X995512Y-107224D02*
Y-106240D01*
G01X995354Y-101299D02*
Y-107183D01*
G01X995315Y-101299D02*
Y-107223D01*
G01X994350Y-120079D02*
Y-116142D01*
G01X994213Y-107223D02*
Y-101299D01*
G01X994173Y-107183D02*
Y-101299D01*
G01X994016Y-106240D02*
Y-107224D01*
G01X993976Y-106280D02*
Y-107185D01*
G01X993169Y-121260D02*
Y-117323D01*
G01X992894Y-120650D02*
Y-119665D01*
G01X992402Y-119667D02*
Y-125000D01*
G01X992362D02*
Y-120652D01*
G01X992008Y-104331D02*
Y-107677D01*
G01X1037597Y-119665D02*
X1037598Y-120620D01*
G01X1035828Y-120650D02*
X1035827Y-119665D01*
G01X1032597D02*
X1032598Y-120620D01*
G01X1030828Y-120650D02*
X1030827Y-119665D01*
G01X1027597D02*
X1027598Y-120620D01*
G01X1025828Y-120650D02*
X1025827Y-119665D01*
G01X1022597D02*
X1022598Y-120620D01*
G01X1020828Y-120650D02*
X1020827Y-119665D01*
G01X1017597D02*
X1017598Y-120620D01*
G01X1015828Y-120650D02*
X1015827Y-119665D01*
G01X992597D02*
X992598Y-120620D01*
G01X1014075Y-116142D02*
X1015256Y-117323D01*
G01X1014075Y-120079D02*
X1015256Y-121260D01*
G01X1013071Y-101299D02*
X1014252D01*
G01X1009921D02*
X1011102D01*
G01X1006772D02*
X1007953D01*
G01X1003622D02*
X1004803D01*
G01X1000472D02*
X1001654D01*
G01X997323D02*
X998504D01*
G01X994173D02*
X995354D01*
G01X1014215Y-107224D02*
X1014226D01*
G01X1011065D02*
X1011076D01*
G01X1007915D02*
X1007927D01*
G01X1004766D02*
X1004777D01*
G01X1001616D02*
X1001628D01*
G01X998467D02*
X998478D01*
G01X995317D02*
X995328D01*
G01X1037376Y-120650D02*
X1037385D01*
G01X1032376D02*
X1032385D01*
G01X1027376D02*
X1027385D01*
G01X1022376D02*
X1022385D01*
G01X1017376D02*
X1017385D01*
G01X992376D02*
X992385D01*
G01X992008Y-104331D02*
X1016417D01*
G01Y-104724D02*
X992008D01*
G01X995354Y-105059D02*
X994173D01*
G01X998504D02*
X997323D01*
G01X1004803D02*
X1003622D01*
G01X1001654D02*
X1000472D01*
G01X1007953D02*
X1006772D01*
G01X1014252D02*
X1013071D01*
G01X1011102D02*
X1009921D01*
G01X995512Y-106240D02*
X994016D01*
G01X998661D02*
X997165D01*
G01X1004961D02*
X1003465D01*
G01X1001811D02*
X1000315D01*
G01X1008110D02*
X1006614D01*
G01X1014409D02*
X1012913D01*
G01X1011260D02*
X1009764D01*
G01X1014263Y-106280D02*
X1014410D01*
G01X1012913D02*
X1013059D01*
G01X1009763D02*
X1009910D01*
G01X1011114D02*
X1011260D01*
G01X1006613D02*
X1006760D01*
G01X1007964D02*
X1008111D01*
G01X1004815D02*
X1004961D01*
G01X1003464D02*
X1003611D01*
G01X1000314D02*
X1000461D01*
G01X1001665D02*
X1001811D01*
G01X997165D02*
X997311D01*
G01X998515D02*
X998662D01*
G01X995366D02*
X995512D01*
G01X994015D02*
X994162D01*
G01Y-107185D02*
X994015D01*
G01X997311D02*
X997165D01*
G01X998662D02*
X998515D01*
G01X995512D02*
X995366D01*
G01X1003611D02*
X1003464D01*
G01X1000461D02*
X1000314D01*
G01X1001811D02*
X1001665D01*
G01X1006760D02*
X1006613D01*
G01X1008111D02*
X1007964D01*
G01X1004961D02*
X1004815D01*
G01X1013059D02*
X1012913D01*
G01X1009910D02*
X1009763D01*
G01X1011260D02*
X1011114D01*
G01X1014410D02*
X1014263D01*
G01X1012913Y-107224D02*
X1014409D01*
G01X1009764D02*
X1011260D01*
G01X1006614D02*
X1008110D01*
G01X1003465D02*
X1004961D01*
G01X1000315D02*
X1001811D01*
G01X997165D02*
X998661D01*
G01X994016D02*
X995512D01*
G01X1095453Y-107677D02*
X1016417D01*
G01X1090531Y-116142D02*
X1014075D01*
G01X1091713Y-117323D02*
X1015256D01*
G01X1017894Y-119665D02*
X1015531D01*
G01X1022894D02*
X1020531D01*
G01X1027894D02*
X1025531D01*
G01X1032894D02*
X1030531D01*
G01X1037894D02*
X1035531D01*
G01X1014075Y-120079D02*
X994350D01*
G01X1035531Y-120650D02*
X1037894D01*
G01X1030531D02*
X1032894D01*
G01X1025531D02*
X1027894D01*
G01X1020531D02*
X1022894D01*
G01X1015531D02*
X1017894D01*
G01X1015256Y-121260D02*
X993169D01*
G01X1017402Y-121831D02*
X1016024D01*
G01X1022402D02*
X1021024D01*
G01X1027402D02*
X1026024D01*
G01X1032402D02*
X1031024D01*
G01X1037402D02*
X1036024D01*
G01Y-125000D02*
X1037402D01*
G01X1031024D02*
X1032402D01*
G01X1026024D02*
X1027402D01*
G01X1021024D02*
X1022402D01*
G01X1016024D02*
X1017402D01*
G01X994199Y-107224D02*
X994210D01*
G01X997349D02*
X997360D01*
G01X1000498D02*
X1000509D01*
G01X1003648D02*
X1003659D01*
G01X1006798D02*
X1006809D01*
G01X1009947D02*
X1009958D01*
G01X1013097D02*
X1013108D01*
G01X1004189Y1591198D02*
X1004140Y1590885D01*
G01X1004348Y1591522D02*
X1004189Y1591198D01*
G01X1004618Y1591810D02*
X1004348Y1591522D01*
G01X1004978Y1592028D02*
X1004618Y1591810D01*
G01X1011275Y1591198D02*
X1011227Y1590885D01*
G01X1011434Y1591522D02*
X1011275Y1591198D01*
G01X1011704Y1591810D02*
X1011434Y1591522D01*
G01X1012064Y1592028D02*
X1011704Y1591810D01*
G01X1018362Y1591198D02*
X1018313Y1590885D01*
G01X1018521Y1591522D02*
X1018362Y1591198D01*
G01X1018791Y1591810D02*
X1018521Y1591522D01*
G01X1019151Y1592028D02*
X1018791Y1591810D01*
G01X1025448Y1591198D02*
X1025400Y1590885D01*
G01X1025607Y1591522D02*
X1025448Y1591198D01*
G01X1025878Y1591810D02*
X1025607Y1591522D01*
G01X1026237Y1592028D02*
X1025878Y1591810D01*
G01X1032535Y1591198D02*
X1032487Y1590885D01*
G01X1032694Y1591522D02*
X1032535Y1591198D01*
G01X1032964Y1591810D02*
X1032694Y1591522D01*
G01X1033324Y1592028D02*
X1032964Y1591810D01*
G01X1039622Y1591198D02*
X1039573Y1590885D01*
G01X1039781Y1591522D02*
X1039622Y1591198D01*
G01X997523Y1591805D02*
X997891Y1592028D01*
G01X997261Y1591522D02*
X997523Y1591805D01*
G01X997105Y1591207D02*
X997261Y1591522D01*
G01X997054Y1590885D02*
X997105Y1591207D01*
G01X997549Y1591723D02*
X997891Y1592028D01*
G01X997292Y1591335D02*
X997549Y1591723D01*
G01X997120Y1590865D02*
X997292Y1591335D01*
G01X997054Y1590313D02*
X997120Y1590865D01*
G01X1004635Y1591723D02*
X1004978Y1592028D01*
G01X1004379Y1591335D02*
X1004635Y1591723D01*
G01X1004207Y1590865D02*
X1004379Y1591335D01*
G01X1004140Y1590313D02*
X1004207Y1590865D01*
G01X1011722Y1591723D02*
X1012064Y1592028D01*
G01X1011465Y1591335D02*
X1011722Y1591723D01*
G01X1011294Y1590865D02*
X1011465Y1591335D01*
G01X1011227Y1590313D02*
X1011294Y1590865D01*
G01X1018809Y1591723D02*
X1019151Y1592028D01*
G01X1018552Y1591335D02*
X1018809Y1591723D01*
G01X1018380Y1590865D02*
X1018552Y1591335D01*
G01X1018313Y1590313D02*
X1018380Y1590865D01*
G01X1025895Y1591723D02*
X1026237Y1592028D01*
G01X1025639Y1591335D02*
X1025895Y1591723D01*
G01X1025467Y1590865D02*
X1025639Y1591335D01*
G01X1025400Y1590313D02*
X1025467Y1590865D01*
G01X1032982Y1591723D02*
X1033324Y1592028D01*
G01X1032725Y1591335D02*
X1032982Y1591723D01*
G01X1032554Y1590865D02*
X1032725Y1591335D01*
G01X1032487Y1590313D02*
X1032554Y1590865D01*
G01X1039573Y1590313D02*
X1039640Y1590865D01*
G01X992626Y1591805D02*
X992259Y1592028D01*
G01X992888Y1591524D02*
X992626Y1591805D01*
G01X993045Y1591209D02*
X992888Y1591524D01*
G01X993097Y1590885D02*
X993045Y1591209D01*
G01X993030Y1590863D02*
X993097Y1590313D01*
G01X992859Y1591333D02*
X993030Y1590863D01*
G01X992602Y1591722D02*
X992859Y1591333D01*
G01X992259Y1592028D02*
X992602Y1591722D01*
G01X1000117Y1590863D02*
X1000183Y1590313D01*
G01X999946Y1591333D02*
X1000117Y1590863D01*
G01X999689Y1591722D02*
X999946Y1591333D01*
G01X999346Y1592028D02*
X999689Y1591722D01*
G01X1007204Y1590863D02*
X1007270Y1590313D01*
G01X1007032Y1591333D02*
X1007204Y1590863D01*
G01X1006775Y1591722D02*
X1007032Y1591333D01*
G01X1006433Y1592028D02*
X1006775Y1591722D01*
G01X1014290Y1590863D02*
X1014357Y1590313D01*
G01X1014119Y1591333D02*
X1014290Y1590863D01*
G01X1013862Y1591722D02*
X1014119Y1591333D01*
G01X1013519Y1592028D02*
X1013862Y1591722D01*
G01X1021377Y1590863D02*
X1021443Y1590313D01*
G01X1021206Y1591333D02*
X1021377Y1590863D01*
G01X1020948Y1591722D02*
X1021206Y1591333D01*
G01X1020606Y1592028D02*
X1020948Y1591722D01*
G01X1000134Y1591199D02*
X1000183Y1590885D01*
G01X999981Y1591514D02*
X1000134Y1591199D01*
G01X999719Y1591801D02*
X999981Y1591514D01*
G01X999346Y1592028D02*
X999719Y1591801D01*
G01X1007220Y1591199D02*
X1007270Y1590885D01*
G01X1007068Y1591514D02*
X1007220Y1591199D01*
G01X1006805Y1591801D02*
X1007068Y1591514D01*
G01X1006433Y1592028D02*
X1006805Y1591801D01*
G01X1014307Y1591199D02*
X1014357Y1590885D01*
G01X1014155Y1591514D02*
X1014307Y1591199D01*
G01X1013892Y1591801D02*
X1014155Y1591514D01*
G01X1013519Y1592028D02*
X1013892Y1591801D01*
G01X1021394Y1591199D02*
X1021443Y1590885D01*
G01X1021241Y1591514D02*
X1021394Y1591199D01*
G01X1020978Y1591801D02*
X1021241Y1591514D01*
G01X1020606Y1592028D02*
X1020978Y1591801D01*
G01X1028480Y1591199D02*
X1028530Y1590885D01*
G01X1028328Y1591514D02*
X1028480Y1591199D01*
G01X1028065Y1591801D02*
X1028328Y1591514D01*
G01X1027693Y1592028D02*
X1028065Y1591801D01*
G01X1035567Y1591199D02*
X1035617Y1590885D01*
G01X1035415Y1591514D02*
X1035567Y1591199D01*
G01X1035152Y1591801D02*
X1035415Y1591514D01*
G01X1034779Y1592028D02*
X1035152Y1591801D01*
G01X1028463Y1590863D02*
X1028530Y1590313D01*
G01X1028292Y1591333D02*
X1028463Y1590863D01*
G01X1028035Y1591722D02*
X1028292Y1591333D01*
G01X1027693Y1592028D02*
X1028035Y1591722D01*
G01X1035550Y1590863D02*
X1035617Y1590313D01*
G01X1035379Y1591333D02*
X1035550Y1590863D01*
G01X1035122Y1591722D02*
X1035379Y1591333D01*
G01X1034779Y1592028D02*
X1035122Y1591722D01*
G01X1034779Y1592028D02*
G03X1033324I-728J-1386D01*
G01X1043107Y1610256D02*
G03I-1969J0D01*
G01X1036020D02*
G03I-1968J0D01*
G01X1032165Y1613858D02*
G03I-1456J0D01*
G01X1016417D02*
G03I-1456J0D01*
G01X1032165Y1603032D02*
G03I-1456J0D01*
G01X1028933Y1610256D02*
G03I-1968J0D01*
G01X1032165Y1597126D02*
G03I-1456J0D01*
G01Y1591221D02*
G03I-1456J0D01*
G01X1027693Y1592028D02*
G03X1026237I-728J-1386D01*
G01X1016417Y1603032D02*
G03I-1456J0D01*
G01X1021847Y1610256D02*
G03I-1969J0D01*
G01X1014760D02*
G03I-1968J0D01*
G01X1016417Y1597126D02*
G03I-1456J0D01*
G01Y1591221D02*
G03I-1456J0D01*
G01X1020606Y1592028D02*
G03X1019151I-727J-1386D01*
G01X1013519D02*
G03X1012064I-727J-1386D01*
G01X1003819Y1613858D02*
G03I-1457J0D01*
G01Y1603032D02*
G03I-1457J0D01*
G01Y1597126D02*
G03I-1457J0D01*
G01Y1591221D02*
G03I-1457J0D01*
G01X1006433Y1592028D02*
G03X1004978I-727J-1386D01*
G01X999346D02*
G03X997891I-727J-1386D01*
G01X1007674Y1610256D02*
G03I-1969J0D01*
G01X1000587D02*
G03I-1968J0D01*
G01X1023524Y1595827D02*
X1050492D01*
G01X995177D02*
X1022146D01*
G01X997891Y1592028D02*
X992259D01*
G01X1004978D02*
X999346D01*
G01X1012064D02*
X1006433D01*
G01X1019151D02*
X1013519D01*
G01X1026237D02*
X1020606D01*
G01X1033324D02*
X1027693D01*
G01X1040411D02*
X1034779D01*
G01X1000154Y1584547D02*
X997083D01*
G01X1021414D02*
X1018343D01*
G01X1028500D02*
X1025430D01*
G01X998973Y1583366D02*
X998264D01*
G01X1020233D02*
X1019524D01*
G01X1027319D02*
X1026611D01*
G01X1023524Y1582382D02*
X1050492D01*
G01X995177D02*
X1022146D01*
G01X1026611Y1583366D02*
X1025430Y1584547D01*
G01D02*
X1026611Y1583366D01*
G01X1025430Y1584547D02*
X1026611Y1583366D01*
G01X1019524D02*
X1018343Y1584547D01*
G01D02*
X1019524Y1583366D01*
G01X1018343Y1584547D02*
X1019524Y1583366D01*
G01X998264D02*
X997083Y1584547D01*
G01D02*
X998264Y1583366D01*
G01X997083Y1584547D02*
X998264Y1583366D01*
G01X1035617Y1590885D02*
Y1584941D01*
G01X1032487Y1590885D02*
Y1584941D01*
G01X1028530Y1590885D02*
Y1584941D01*
G01X1028500Y1584547D02*
Y1587303D01*
G01X1025430D02*
Y1584547D01*
G01X1025400Y1590885D02*
Y1584941D01*
G01X1023524Y1706299D02*
Y1582382D01*
G01X1022146D02*
Y1706299D01*
G01X1021443Y1590885D02*
Y1584941D01*
G01X1021414Y1587303D02*
Y1584547D01*
G01X1018343Y1587303D02*
Y1584547D01*
G01X1018313Y1590885D02*
Y1584941D01*
G01X1014357Y1590885D02*
Y1584941D01*
G01X1011227Y1590885D02*
Y1584941D01*
G01X1007270Y1590885D02*
Y1584941D01*
G01X1004140Y1590885D02*
Y1584941D01*
G01X1000183Y1590885D02*
Y1584941D01*
G01X1000154Y1584547D02*
Y1587303D01*
G01X997083D02*
Y1584547D01*
G01X997054Y1590885D02*
Y1584941D01*
G01X995177Y1706299D02*
Y1582382D01*
G01X993799D02*
Y1706299D01*
G01X993097Y1590885D02*
Y1584941D01*
G01X993067Y1587303D02*
Y1584547D01*
G01X1027319Y1583366D02*
X1028500Y1584547D01*
G01X1027319Y1583366D02*
X1028500Y1584547D01*
G01X1020233Y1583366D02*
X1021414Y1584547D01*
G01X1020233Y1583366D02*
X1021414Y1584547D01*
G01X998973Y1583366D02*
X1000154Y1584547D01*
G01X998973Y1583366D02*
X1000154Y1584547D01*
G01X991886Y1583366D02*
X993067Y1584547D01*
G01X991886Y1583366D02*
X993067Y1584547D01*
G01X1032165Y1648307D02*
G03I-1456J0D01*
G01Y1642402D02*
G03I-1456J0D01*
G01Y1636496D02*
G03I-1456J0D01*
G01X1016417Y1648307D02*
G03I-1456J0D01*
G01Y1642402D02*
G03I-1456J0D01*
G01Y1636496D02*
G03I-1456J0D01*
G01X1032477Y1629941D02*
G03X1035626I1574J0D01*
G01X1032165Y1625669D02*
G03I-1456J0D01*
G01Y1619764D02*
G03I-1456J0D01*
G01X1016417Y1625669D02*
G03I-1456J0D01*
G01Y1619764D02*
G03I-1456J0D01*
G01X1025390Y1629941D02*
G03X1028540I1575J0D01*
G01X1018304D02*
G03X1021453I1574J0D01*
G01X1011217D02*
G03X1014367I1575J0D01*
G01X1003819Y1648307D02*
G03I-1457J0D01*
G01Y1642402D02*
G03I-1457J0D01*
G01Y1636496D02*
G03I-1457J0D01*
G01Y1625669D02*
G03I-1457J0D01*
G01Y1619764D02*
G03I-1457J0D01*
G01X1004130Y1629941D02*
G03X1007280I1575J0D01*
G01X997044D02*
G03X1000193I1574J0D01*
G01X1023524Y1659429D02*
X1050492D01*
G01X995177D02*
X1022146D01*
G01X993799Y1650138D02*
X993166D01*
G01X996985D02*
X995177D01*
G01X1004071D02*
X1000252D01*
G01X1011158D02*
X1007339D01*
G01X1018244D02*
X1014426D01*
G01X1022146D02*
X1021512D01*
G01X1025331D02*
X1023524D01*
G01X1032418D02*
X1028599D01*
G01X1039504D02*
X1035685D01*
G01X995666Y1648839D02*
X994485D01*
G01X1002752D02*
X1001571D01*
G01X1009839D02*
X1008658D01*
G01X1016926D02*
X1015744D01*
G01X1024012D02*
X1022831D01*
G01X1031099D02*
X1029918D01*
G01X1038185D02*
X1037004D01*
G01X1019121Y1634523D02*
X1020636D01*
G01X999376D02*
X997861D01*
G01X1006463D02*
X1004948D01*
G01X1013549D02*
X1012034D01*
G01X1027722D02*
X1026207D01*
G01X1034809D02*
X1033294D01*
G01X1022146Y1629830D02*
X995177D01*
G01X1050492D02*
X1023524D01*
G01X1022146Y1627307D02*
X995177D01*
G01X1050492D02*
X1023524D01*
G01X1040381Y1634523D02*
X1039504Y1635400D01*
G01X1033294Y1634523D02*
X1032418Y1635400D01*
G01X1026207Y1634523D02*
X1025331Y1635400D01*
G01X1019121Y1634523D02*
X1018244Y1635400D01*
G01X1012034Y1634523D02*
X1011158Y1635400D01*
G01X1004948Y1634523D02*
X1004071Y1635400D01*
G01X997861Y1634523D02*
X996985Y1635400D01*
G01X1038185Y1648839D02*
X1039504Y1646554D01*
G01X1031099Y1648839D02*
X1032418Y1646554D01*
G01X1024012Y1648839D02*
X1025331Y1646554D01*
G01X1016926Y1648839D02*
X1018244Y1646554D01*
G01X1009839Y1648839D02*
X1011158Y1646554D01*
G01X1002752Y1648839D02*
X1004071Y1646554D01*
G01X995666Y1648839D02*
X996985Y1646554D01*
G01X1039504Y1650138D02*
Y1635400D01*
G01X1035685D02*
Y1650138D01*
G01X1035626Y1635341D02*
Y1629941D01*
G01X1032477Y1635341D02*
Y1629941D01*
G01X1032418Y1650138D02*
Y1635400D01*
G01X1028599D02*
Y1650138D01*
G01X1028540Y1635341D02*
Y1629941D01*
G01X1025390Y1635341D02*
Y1629941D01*
G01X1025331Y1650138D02*
Y1635400D01*
G01X1021512D02*
Y1650138D01*
G01X1021453Y1635341D02*
Y1629941D01*
G01X1018304Y1635341D02*
Y1629941D01*
G01X1018244Y1650138D02*
Y1635400D01*
G01X1014426D02*
Y1650138D01*
G01X1014367Y1635341D02*
Y1629941D01*
G01X1011217Y1635341D02*
Y1629941D01*
G01X1011158Y1650138D02*
Y1635400D01*
G01X1007339D02*
Y1650138D01*
G01X1007280Y1635341D02*
Y1629941D01*
G01X1004130Y1635341D02*
Y1629941D01*
G01X1004071Y1650138D02*
Y1635400D01*
G01X1000252D02*
Y1650138D01*
G01X1000193Y1635341D02*
Y1629941D01*
G01X997044Y1635341D02*
Y1629941D01*
G01X996985Y1650138D02*
Y1635400D01*
G01X993166D02*
Y1650138D01*
G01X993107Y1635341D02*
Y1629941D01*
G01X1037004Y1648839D02*
X1035685Y1646554D01*
G01X1029918Y1648839D02*
X1028599Y1646554D01*
G01X1022831Y1648839D02*
X1021512Y1646554D01*
G01X1015744Y1648839D02*
X1014426Y1646554D01*
G01X1008658Y1648839D02*
X1007339Y1646554D01*
G01X1001571Y1648839D02*
X1000252Y1646554D01*
G01X994485Y1648839D02*
X993166Y1646554D01*
G01X1035685Y1635400D02*
X1034809Y1634523D01*
G01X1028599Y1635400D02*
X1027722Y1634523D01*
G01X1021512Y1635400D02*
X1020636Y1634523D01*
G01X1014426Y1635400D02*
X1013549Y1634523D01*
G01X1007339Y1635400D02*
X1006463Y1634523D01*
G01X1000252Y1635400D02*
X999376Y1634523D01*
G01X993166Y1635400D02*
X992289Y1634523D01*
G01X1026083Y1670669D02*
G03X1026673Y1670079I590J0D01*
G01X1018996D02*
G03X1019587Y1670669I0J591D01*
G01X997736D02*
G03X998327Y1670079I591J1D01*
G01X1023524Y1706299D02*
X1050492D01*
G01X995177D02*
X1022146D01*
G01X992421Y1705512D02*
X991240D01*
G01X997736D02*
X996555D01*
G01X1020768D02*
X1019587D01*
G01X1026083D02*
X1024902D01*
G01X1003937Y1705315D02*
X1000787D01*
G01X1016535D02*
X1013386D01*
G01X1032283D02*
X1029134D01*
G01X1000787Y1704724D02*
X997343D01*
G01X1013386D02*
X1003937D01*
G01X1019980D02*
X1016535D01*
G01X1029134D02*
X1025689D01*
G01X1041732D02*
X1032283D01*
G01X1003937Y1697441D02*
X1000787D01*
G01X1016535D02*
X1013386D01*
G01X1032283D02*
X1029134D01*
G01X1019587Y1670669D02*
X997736D01*
G01X1047933D02*
X1026083D01*
G01X1024768Y1670079D02*
X1049248D01*
G01X996421D02*
X1020902D01*
G01X1019980Y1667570D02*
X997343D01*
G01X1048327D02*
X1025689D01*
G01Y1704724D02*
X1024114Y1706299D01*
G01X997343Y1704724D02*
X995768Y1706299D01*
G01X1032283Y1705315D02*
Y1697441D01*
G01X1029134Y1705315D02*
Y1697441D01*
G01X1026083Y1670079D02*
Y1706299D01*
G01X1025689Y1667570D02*
Y1704724D01*
G01X1024768Y1670079D02*
Y1706299D01*
G01X1020902Y1670079D02*
Y1706299D01*
G01X1019980Y1704724D02*
Y1667570D01*
G01X1019587Y1670079D02*
Y1706299D01*
G01X1016535Y1705315D02*
Y1697441D01*
G01X1013386Y1705315D02*
Y1697441D01*
G01X1003937Y1705315D02*
Y1697441D01*
G01X1000787Y1705315D02*
Y1697441D01*
G01X997736Y1670079D02*
Y1706299D01*
G01X997343Y1667570D02*
Y1704724D01*
G01X996421Y1670079D02*
Y1706299D01*
G01X992555Y1670079D02*
Y1706299D01*
G01X991634Y1704724D02*
Y1667570D01*
G01X991240Y1670079D02*
Y1706299D01*
G01X1021555D02*
X1019980Y1704724D01*
G01X993209Y1706299D02*
X991634Y1704724D01*
G01X1087396Y-120632D02*
X1087402Y-120613D01*
G01X1087382Y-120646D02*
X1087396Y-120632D01*
G01X1087362Y-120652D02*
X1087382Y-120646D01*
G01X1082396Y-120632D02*
X1082402Y-120613D01*
G01X1082382Y-120646D02*
X1082396Y-120632D01*
G01X1082362Y-120652D02*
X1082382Y-120646D01*
G01X1077396Y-120632D02*
X1077402Y-120613D01*
G01X1077382Y-120646D02*
X1077396Y-120632D01*
G01X1077362Y-120652D02*
X1077382Y-120646D01*
G01X1072396Y-120632D02*
X1072402Y-120613D01*
G01X1072382Y-120646D02*
X1072396Y-120632D01*
G01X1072362Y-120652D02*
X1072382Y-120646D01*
G01X1067396Y-120632D02*
X1067402Y-120613D01*
G01X1067382Y-120646D02*
X1067396Y-120632D01*
G01X1067362Y-120652D02*
X1067382Y-120646D01*
G01X1062396Y-120632D02*
X1062402Y-120613D01*
G01X1062382Y-120646D02*
X1062396Y-120632D01*
G01X1062362Y-120652D02*
X1062382Y-120646D01*
G01X1057396Y-120632D02*
X1057402Y-120613D01*
G01X1057382Y-120646D02*
X1057396Y-120632D01*
G01X1057362Y-120652D02*
X1057382Y-120646D01*
G01X1052396Y-120632D02*
X1052402Y-120613D01*
G01X1052382Y-120646D02*
X1052396Y-120632D01*
G01X1052362Y-120652D02*
X1052382Y-120646D01*
G01X1047396Y-120632D02*
X1047402Y-120613D01*
G01X1047382Y-120646D02*
X1047396Y-120632D01*
G01X1047362Y-120652D02*
X1047382Y-120646D01*
G01X1042396Y-120632D02*
X1042402Y-120613D01*
G01X1042382Y-120646D02*
X1042396Y-120632D01*
G01X1042362Y-120652D02*
X1042382Y-120646D01*
G01X1087500Y-120617D02*
X1087598Y-120620D01*
G01X1087428Y-120611D02*
X1087500Y-120617D01*
G01X1087402Y-120613D02*
X1087428Y-120611D01*
G01X1082500Y-120617D02*
X1082598Y-120620D01*
G01X1082428Y-120611D02*
X1082500Y-120617D01*
G01X1082402Y-120613D02*
X1082428Y-120611D01*
G01X1077500Y-120617D02*
X1077598Y-120620D01*
G01X1077428Y-120611D02*
X1077500Y-120617D01*
G01X1077402Y-120613D02*
X1077428Y-120611D01*
G01X1072500Y-120617D02*
X1072598Y-120620D01*
G01X1072428Y-120611D02*
X1072500Y-120617D01*
G01X1072402Y-120613D02*
X1072428Y-120611D01*
G01X1067500Y-120617D02*
X1067598Y-120620D01*
G01X1067428Y-120611D02*
X1067500Y-120617D01*
G01X1067402Y-120613D02*
X1067428Y-120611D01*
G01X1062500Y-120617D02*
X1062598Y-120620D01*
G01X1062428Y-120611D02*
X1062500Y-120617D01*
G01X1062402Y-120613D02*
X1062428Y-120611D01*
G01X1057500Y-120617D02*
X1057598Y-120620D01*
G01X1057428Y-120611D02*
X1057500Y-120617D01*
G01X1057402Y-120613D02*
X1057428Y-120611D01*
G01X1052500Y-120617D02*
X1052598Y-120620D01*
G01X1052428Y-120611D02*
X1052500Y-120617D01*
G01X1052402Y-120613D02*
X1052428Y-120611D01*
G01X1047500Y-120617D02*
X1047598Y-120620D01*
G01X1047428Y-120611D02*
X1047500Y-120617D01*
G01X1047402Y-120613D02*
X1047428Y-120611D01*
G01X1042500Y-120617D02*
X1042598Y-120620D01*
G01X1042428Y-120611D02*
X1042500Y-120617D01*
G01X1042402Y-120613D02*
X1042428Y-120611D01*
G01X1041022Y-119666D02*
X1041024Y-119667D01*
G01X1041017Y-119665D02*
X1041022Y-119666D01*
G01X1041007Y-119665D02*
X1041017D01*
G01X1046022Y-119666D02*
X1046024Y-119667D01*
G01X1046017Y-119665D02*
X1046022Y-119666D01*
G01X1046007Y-119665D02*
X1046017D01*
G01X1051022Y-119666D02*
X1051024Y-119667D01*
G01X1051017Y-119665D02*
X1051022Y-119666D01*
G01X1051007Y-119665D02*
X1051017D01*
G01X1056022Y-119666D02*
X1056024Y-119667D01*
G01X1056017Y-119665D02*
X1056022Y-119666D01*
G01X1056007Y-119665D02*
X1056017D01*
G01X1061022Y-119666D02*
X1061024Y-119667D01*
G01X1061017Y-119665D02*
X1061022Y-119666D01*
G01X1061007Y-119665D02*
X1061017D01*
G01X1066022Y-119666D02*
X1066024Y-119667D01*
G01X1066017Y-119665D02*
X1066022Y-119666D01*
G01X1066007Y-119665D02*
X1066017D01*
G01X1071022Y-119666D02*
X1071024Y-119667D01*
G01X1071017Y-119665D02*
X1071022Y-119666D01*
G01X1071007Y-119665D02*
X1071017D01*
G01X1076022Y-119666D02*
X1076024Y-119667D01*
G01X1076017Y-119665D02*
X1076022Y-119666D01*
G01X1076007Y-119665D02*
X1076017D01*
G01X1081022Y-119666D02*
X1081024Y-119667D01*
G01X1081017Y-119665D02*
X1081022Y-119666D01*
G01X1081007Y-119665D02*
X1081017D01*
G01X1086022Y-119666D02*
X1086024Y-119667D01*
G01X1086017Y-119665D02*
X1086022Y-119666D01*
G01X1086007Y-119665D02*
X1086017D01*
G01X1041016Y-120650D02*
X1041007D01*
G01X1041022Y-120651D02*
X1041016Y-120650D01*
G01X1041024Y-120652D02*
X1041022Y-120651D01*
G01X1046016Y-120650D02*
X1046007D01*
G01X1046022Y-120651D02*
X1046016Y-120650D01*
G01X1046024Y-120652D02*
X1046022Y-120651D01*
G01X1051016Y-120650D02*
X1051007D01*
G01X1051022Y-120651D02*
X1051016Y-120650D01*
G01X1051024Y-120652D02*
X1051022Y-120651D01*
G01X1056016Y-120650D02*
X1056007D01*
G01X1056022Y-120651D02*
X1056016Y-120650D01*
G01X1056024Y-120652D02*
X1056022Y-120651D01*
G01X1061016Y-120650D02*
X1061007D01*
G01X1061022Y-120651D02*
X1061016Y-120650D01*
G01X1061024Y-120652D02*
X1061022Y-120651D01*
G01X1066016Y-120650D02*
X1066007D01*
G01X1066022Y-120651D02*
X1066016Y-120650D01*
G01X1066024Y-120652D02*
X1066022Y-120651D01*
G01X1071016Y-120650D02*
X1071007D01*
G01X1071022Y-120651D02*
X1071016Y-120650D01*
G01X1071024Y-120652D02*
X1071022Y-120651D01*
G01X1076016Y-120650D02*
X1076007D01*
G01X1076022Y-120651D02*
X1076016Y-120650D01*
G01X1076024Y-120652D02*
X1076022Y-120651D01*
G01X1081016Y-120650D02*
X1081007D01*
G01X1081022Y-120651D02*
X1081016Y-120650D01*
G01X1081024Y-120652D02*
X1081022Y-120651D01*
G01X1086016Y-120650D02*
X1086007D01*
G01X1086022Y-120651D02*
X1086016Y-120650D01*
G01X1086024Y-120652D02*
X1086022Y-120651D01*
G01X1042393Y-120637D02*
X1042378Y-120648D01*
G01X1042402Y-120613D02*
X1042393Y-120637D01*
G01X1047393D02*
X1047378Y-120648D01*
G01X1047402Y-120613D02*
X1047393Y-120637D01*
G01X1052393D02*
X1052378Y-120648D01*
G01X1052402Y-120613D02*
X1052393Y-120637D01*
G01X1057393D02*
X1057378Y-120648D01*
G01X1057402Y-120613D02*
X1057393Y-120637D01*
G01X1062393D02*
X1062378Y-120648D01*
G01X1062402Y-120613D02*
X1062393Y-120637D01*
G01X1067393D02*
X1067378Y-120648D01*
G01X1067402Y-120613D02*
X1067393Y-120637D01*
G01X1072393D02*
X1072378Y-120648D01*
G01X1072402Y-120613D02*
X1072393Y-120637D01*
G01X1077393D02*
X1077378Y-120648D01*
G01X1077402Y-120613D02*
X1077393Y-120637D01*
G01X1082393D02*
X1082378Y-120648D01*
G01X1082402Y-120613D02*
X1082393Y-120637D01*
G01X1087393D02*
X1087378Y-120648D01*
G01X1087402Y-120613D02*
X1087393Y-120637D01*
G01X1042369Y-120650D02*
X1042376D01*
G01X1042364D02*
X1042369D01*
G01X1042362Y-120652D02*
X1042364Y-120650D01*
G01X1047369D02*
X1047376D01*
G01X1047364D02*
X1047369D01*
G01X1047362Y-120652D02*
X1047364Y-120650D01*
G01X1052369D02*
X1052376D01*
G01X1052364D02*
X1052369D01*
G01X1052362Y-120652D02*
X1052364Y-120650D01*
G01X1057369D02*
X1057376D01*
G01X1057364D02*
X1057369D01*
G01X1057362Y-120652D02*
X1057364Y-120650D01*
G01X1062369D02*
X1062376D01*
G01X1062364D02*
X1062369D01*
G01X1062362Y-120652D02*
X1062364Y-120650D01*
G01X1067369D02*
X1067376D01*
G01X1067364D02*
X1067369D01*
G01X1067362Y-120652D02*
X1067364Y-120650D01*
G01X1072369D02*
X1072376D01*
G01X1072364D02*
X1072369D01*
G01X1072362Y-120652D02*
X1072364Y-120650D01*
G01X1077369D02*
X1077376D01*
G01X1077364D02*
X1077369D01*
G01X1077362Y-120652D02*
X1077364Y-120650D01*
G01X1082369D02*
X1082376D01*
G01X1082364D02*
X1082369D01*
G01X1082362Y-120652D02*
X1082364Y-120650D01*
G01X1087369D02*
X1087376D01*
G01X1087364D02*
X1087369D01*
G01X1087362Y-120652D02*
X1087364Y-120650D01*
G01X1042409Y-119665D02*
X1042418D01*
G01X1042404Y-119666D02*
X1042409Y-119665D01*
G01X1042402Y-119667D02*
X1042404Y-119666D01*
G01X1047409Y-119665D02*
X1047418D01*
G01X1047404Y-119666D02*
X1047409Y-119665D01*
G01X1047402Y-119667D02*
X1047404Y-119666D01*
G01X1052409Y-119665D02*
X1052418D01*
G01X1052404Y-119666D02*
X1052409Y-119665D01*
G01X1052402Y-119667D02*
X1052404Y-119666D01*
G01X1057409Y-119665D02*
X1057418D01*
G01X1057404Y-119666D02*
X1057409Y-119665D01*
G01X1057402Y-119667D02*
X1057404Y-119666D01*
G01X1062409Y-119665D02*
X1062418D01*
G01X1062404Y-119666D02*
X1062409Y-119665D01*
G01X1062402Y-119667D02*
X1062404Y-119666D01*
G01X1067409Y-119665D02*
X1067418D01*
G01X1067404Y-119666D02*
X1067409Y-119665D01*
G01X1067402Y-119667D02*
X1067404Y-119666D01*
G01X1072409Y-119665D02*
X1072418D01*
G01X1072404Y-119666D02*
X1072409Y-119665D01*
G01X1072402Y-119667D02*
X1072404Y-119666D01*
G01X1077409Y-119665D02*
X1077418D01*
G01X1077404Y-119666D02*
X1077409Y-119665D01*
G01X1077402Y-119667D02*
X1077404Y-119666D01*
G01X1082409Y-119665D02*
X1082418D01*
G01X1082404Y-119666D02*
X1082409Y-119665D01*
G01X1082402Y-119667D02*
X1082404Y-119666D01*
G01X1087409Y-119665D02*
X1087418D01*
G01X1087404Y-119666D02*
X1087409Y-119665D01*
G01X1087402Y-119667D02*
X1087404Y-119666D01*
G01X1042545Y-120642D02*
X1042519Y-120650D01*
G01X1042572Y-120632D02*
X1042545Y-120642D01*
G01X1042598Y-120620D02*
X1042572Y-120632D01*
G01X1047545Y-120642D02*
X1047519Y-120650D01*
G01X1047572Y-120632D02*
X1047545Y-120642D01*
G01X1047598Y-120620D02*
X1047572Y-120632D01*
G01X1052545Y-120642D02*
X1052519Y-120650D01*
G01X1052572Y-120632D02*
X1052545Y-120642D01*
G01X1052598Y-120620D02*
X1052572Y-120632D01*
G01X1057545Y-120642D02*
X1057519Y-120650D01*
G01X1057572Y-120632D02*
X1057545Y-120642D01*
G01X1057598Y-120620D02*
X1057572Y-120632D01*
G01X1062545Y-120642D02*
X1062519Y-120650D01*
G01X1062572Y-120632D02*
X1062545Y-120642D01*
G01X1062598Y-120620D02*
X1062572Y-120632D01*
G01X1067545Y-120642D02*
X1067519Y-120650D01*
G01X1067572Y-120632D02*
X1067545Y-120642D01*
G01X1067598Y-120620D02*
X1067572Y-120632D01*
G01X1072545Y-120642D02*
X1072519Y-120650D01*
G01X1072572Y-120632D02*
X1072545Y-120642D01*
G01X1072598Y-120620D02*
X1072572Y-120632D01*
G01X1077545Y-120642D02*
X1077519Y-120650D01*
G01X1077572Y-120632D02*
X1077545Y-120642D01*
G01X1077598Y-120620D02*
X1077572Y-120632D01*
G01X1082545Y-120642D02*
X1082519Y-120650D01*
G01X1082572Y-120632D02*
X1082545Y-120642D01*
G01X1082598Y-120620D02*
X1082572Y-120632D01*
G01X1087545Y-120642D02*
X1087519Y-120650D01*
G01X1087572Y-120632D02*
X1087545Y-120642D01*
G01X1087598Y-120620D02*
X1087572Y-120632D01*
G01X1087894Y-120650D02*
Y-119665D01*
G01X1087402Y-119667D02*
Y-125000D01*
G01X1087362D02*
Y-120652D01*
G01X1086024Y-125000D02*
Y-119667D01*
G01X1085531Y-119665D02*
Y-120650D01*
G01X1082894D02*
Y-119665D01*
G01X1082402Y-119667D02*
Y-125000D01*
G01X1082362D02*
Y-120652D01*
G01X1081024Y-125000D02*
Y-119667D01*
G01X1080531Y-119665D02*
Y-120650D01*
G01X1077894D02*
Y-119665D01*
G01X1077402Y-119667D02*
Y-125000D01*
G01X1077362D02*
Y-120652D01*
G01X1076024Y-125000D02*
Y-119667D01*
G01X1075531Y-119665D02*
Y-120650D01*
G01X1072894D02*
Y-119665D01*
G01X1072402Y-119667D02*
Y-125000D01*
G01X1072362D02*
Y-120652D01*
G01X1071024Y-125000D02*
Y-119667D01*
G01X1070531Y-119665D02*
Y-120650D01*
G01X1087597Y-119665D02*
X1087598Y-120620D01*
G01X1085828Y-120650D02*
X1085827Y-119665D01*
G01X1082597D02*
X1082598Y-120620D01*
G01X1080828Y-120650D02*
X1080827Y-119665D01*
G01X1077597D02*
X1077598Y-120620D01*
G01X1075828Y-120650D02*
X1075827Y-119665D01*
G01X1072597D02*
X1072598Y-120620D01*
G01X1070828Y-120650D02*
X1070827Y-119665D01*
G01X1067894Y-120650D02*
Y-119665D01*
G01X1067402Y-119667D02*
Y-125000D01*
G01X1067362D02*
Y-120652D01*
G01X1066024Y-125000D02*
Y-119667D01*
G01X1065531Y-119665D02*
Y-120650D01*
G01X1062894D02*
Y-119665D01*
G01X1062402Y-119667D02*
Y-125000D01*
G01X1062362D02*
Y-120652D01*
G01X1061024Y-125000D02*
Y-119667D01*
G01X1060531Y-119665D02*
Y-120650D01*
G01X1057894D02*
Y-119665D01*
G01X1057402Y-119667D02*
Y-125000D01*
G01X1057362D02*
Y-120652D01*
G01X1056024Y-125000D02*
Y-119667D01*
G01X1055531Y-119665D02*
Y-120650D01*
G01X1052894D02*
Y-119665D01*
G01X1052402Y-119667D02*
Y-125000D01*
G01X1052362D02*
Y-120652D01*
G01X1051024Y-125000D02*
Y-119667D01*
G01X1050531Y-119665D02*
Y-120650D01*
G01X1047894D02*
Y-119665D01*
G01X1047402Y-119667D02*
Y-125000D01*
G01X1047362D02*
Y-120652D01*
G01X1046024Y-125000D02*
Y-119667D01*
G01X1045531Y-119665D02*
Y-120650D01*
G01X1042894D02*
Y-119665D01*
G01X1042402Y-119667D02*
Y-125000D01*
G01X1042362D02*
Y-120652D01*
G01X1041024Y-125000D02*
Y-119667D01*
G01X1040531Y-119665D02*
Y-120650D01*
G01X1067597Y-119665D02*
X1067598Y-120620D01*
G01X1065828Y-120650D02*
X1065827Y-119665D01*
G01X1062597D02*
X1062598Y-120620D01*
G01X1060828Y-120650D02*
X1060827Y-119665D01*
G01X1057597D02*
X1057598Y-120620D01*
G01X1055828Y-120650D02*
X1055827Y-119665D01*
G01X1052597D02*
X1052598Y-120620D01*
G01X1050828Y-120650D02*
X1050827Y-119665D01*
G01X1047597D02*
X1047598Y-120620D01*
G01X1045828Y-120650D02*
X1045827Y-119665D01*
G01X1042597D02*
X1042598Y-120620D01*
G01X1040828Y-120650D02*
X1040827Y-119665D01*
G01X1087376Y-120650D02*
X1087385D01*
G01X1082376D02*
X1082385D01*
G01X1077376D02*
X1077385D01*
G01X1072376D02*
X1072385D01*
G01X1067376D02*
X1067385D01*
G01X1062376D02*
X1062385D01*
G01X1057376D02*
X1057385D01*
G01X1052376D02*
X1052385D01*
G01X1047376D02*
X1047385D01*
G01X1042376D02*
X1042385D01*
G01X1042894Y-119665D02*
X1040531D01*
G01X1047894D02*
X1045531D01*
G01X1052894D02*
X1050531D01*
G01X1057894D02*
X1055531D01*
G01X1062894D02*
X1060531D01*
G01X1067894D02*
X1065531D01*
G01X1072894D02*
X1070531D01*
G01X1077894D02*
X1075531D01*
G01X1082894D02*
X1080531D01*
G01X1087894D02*
X1085531D01*
G01Y-120650D02*
X1087894D01*
G01X1080531D02*
X1082894D01*
G01X1075531D02*
X1077894D01*
G01X1070531D02*
X1072894D01*
G01X1065531D02*
X1067894D01*
G01X1060531D02*
X1062894D01*
G01X1055531D02*
X1057894D01*
G01X1050531D02*
X1052894D01*
G01X1045531D02*
X1047894D01*
G01X1040531D02*
X1042894D01*
G01X1042402Y-121831D02*
X1041024D01*
G01X1047402D02*
X1046024D01*
G01X1052402D02*
X1051024D01*
G01X1057402D02*
X1056024D01*
G01X1062402D02*
X1061024D01*
G01X1067402D02*
X1066024D01*
G01X1072402D02*
X1071024D01*
G01X1077402D02*
X1076024D01*
G01X1082402D02*
X1081024D01*
G01X1087402D02*
X1086024D01*
G01Y-125000D02*
X1087402D01*
G01X1081024D02*
X1082402D01*
G01X1076024D02*
X1077402D01*
G01X1071024D02*
X1072402D01*
G01X1066024D02*
X1067402D01*
G01X1061024D02*
X1062402D01*
G01X1056024D02*
X1057402D01*
G01X1051024D02*
X1052402D01*
G01X1046024D02*
X1047402D01*
G01X1041024D02*
X1042402D01*
G01X1040051Y1591810D02*
X1039781Y1591522D01*
G01X1040411Y1592028D02*
X1040051Y1591810D01*
G01X1046730Y1590878D02*
X1046660Y1590313D01*
G01X1046906Y1591350D02*
X1046730Y1590878D01*
G01X1047164Y1591733D02*
X1046906Y1591350D01*
G01X1047497Y1592028D02*
X1047164Y1591733D01*
G01X1040069Y1591723D02*
X1040411Y1592028D01*
G01X1039812Y1591335D02*
X1040069Y1591723D01*
G01X1039640Y1590865D02*
X1039812Y1591335D01*
G01X1047130Y1591805D02*
X1047497Y1592028D01*
G01X1046867Y1591522D02*
X1047130Y1591805D01*
G01X1046711Y1591207D02*
X1046867Y1591522D01*
G01X1046660Y1590885D02*
X1046711Y1591207D01*
G01X1042232Y1591805D02*
X1041866Y1592028D01*
G01X1042494Y1591524D02*
X1042232Y1591805D01*
G01X1042651Y1591209D02*
X1042494Y1591524D01*
G01X1042703Y1590885D02*
X1042651Y1591209D01*
G01X1042637Y1590863D02*
X1042703Y1590313D01*
G01X1042465Y1591333D02*
X1042637Y1590863D01*
G01X1042208Y1591722D02*
X1042465Y1591333D01*
G01X1041866Y1592028D02*
X1042208Y1591722D01*
G01X1049723Y1590863D02*
X1049790Y1590313D01*
G01X1049552Y1591333D02*
X1049723Y1590863D01*
G01X1049295Y1591722D02*
X1049552Y1591333D01*
G01X1048952Y1592028D02*
X1049295Y1591722D01*
G01X1049740Y1591199D02*
X1049790Y1590885D01*
G01X1049588Y1591514D02*
X1049740Y1591199D01*
G01X1049325Y1591801D02*
X1049588Y1591514D01*
G01X1048952Y1592028D02*
X1049325Y1591801D01*
G01X1044764Y1613858D02*
G03I-1457J0D01*
G01Y1603032D02*
G03I-1457J0D01*
G01Y1597126D02*
G03I-1457J0D01*
G01Y1591221D02*
G03I-1457J0D01*
G01X1048952Y1592028D02*
G03X1047497I-727J-1386D01*
G01X1041866D02*
G03X1040411I-727J-1386D01*
G01X1050193Y1610256D02*
G03I-1968J0D01*
G01X1044062Y1591947D02*
X1043930Y1592014D01*
G01X1043767Y1591846D02*
X1043898Y1591813D01*
G01X1043930Y1592014D02*
X1043767Y1592047D01*
G01X1042454D02*
X1042651D01*
G01X1043767D02*
X1043635D01*
G01X1047497Y1592028D02*
X1041866D01*
G01X1051217D02*
X1048952D01*
G01X1043635Y1591846D02*
X1043767D01*
G01X1044094Y1591511D02*
X1044291D01*
G01X1043110Y1590472D02*
X1043307D01*
G01X1042651D02*
X1042454D01*
G01X1049760Y1584547D02*
X1046689D01*
G01X1048579Y1583366D02*
X1047870D01*
G01X1043635Y1592047D02*
X1043471Y1592014D01*
G01X1043504Y1591813D02*
X1043635Y1591846D01*
G01X1043898Y1591813D02*
X1043996Y1591746D01*
G01X1044193Y1591813D02*
X1044062Y1591947D01*
G01X1047870Y1583366D02*
X1046689Y1584547D01*
G01D02*
X1047870Y1583366D01*
G01X1046689Y1584547D02*
X1047870Y1583366D01*
G01X1043996Y1591746D02*
X1044062Y1591645D01*
G01X1044259Y1591679D02*
X1044193Y1591813D01*
G01X1044291Y1591511D02*
X1044259Y1591679D01*
G01X1044062Y1591645D02*
X1044094Y1591511D01*
G01X1051217Y1584941D02*
Y1626791D01*
G01X1050492Y1582382D02*
Y1706299D01*
G01X1049790Y1590885D02*
Y1584941D01*
G01X1049760Y1587303D02*
Y1584547D01*
G01X1046689Y1587303D02*
Y1584547D01*
G01X1046660Y1590885D02*
Y1584941D01*
G01X1043307Y1590472D02*
Y1591511D01*
G01X1043110D02*
Y1590472D01*
G01X1042848Y1590975D02*
Y1590707D01*
G01X1042703Y1590885D02*
Y1584941D01*
G01X1042651Y1592047D02*
Y1590741D01*
G01X1042454Y1590472D02*
Y1592047D01*
G01X1039573Y1590885D02*
Y1584941D01*
G01X1043307Y1591511D02*
X1043340Y1591645D01*
G01X1043143Y1591679D02*
X1043110Y1591511D01*
G01X1043209Y1591813D02*
X1043143Y1591679D01*
G01X1043340Y1591645D02*
X1043406Y1591746D01*
G01X1048579Y1583366D02*
X1049760Y1584547D01*
G01X1048579Y1583366D02*
X1049760Y1584547D01*
G01X1043340Y1591947D02*
X1043209Y1591813D01*
G01X1042848Y1590707D02*
X1042651Y1590472D01*
G01Y1590741D02*
X1042848Y1590975D01*
G01X1043471Y1592014D02*
X1043340Y1591947D01*
G01X1043406Y1591746D02*
X1043504Y1591813D01*
G01X1044764Y1648307D02*
G03I-1457J0D01*
G01Y1642402D02*
G03I-1457J0D01*
G01Y1636496D02*
G03I-1457J0D01*
G01Y1625669D02*
G03I-1457J0D01*
G01Y1619764D02*
G03I-1457J0D01*
G01X1051217Y1626791D02*
G03X1049642Y1628366I-1575J0D01*
G01X1046650Y1629941D02*
G03X1048225Y1628366I1575J0D01*
G01X1039563Y1629941D02*
G03X1042713I1575J0D01*
G01X1046591Y1650138D02*
X1042772D01*
G01X1050492D02*
X1049859D01*
G01X1042283Y1649134D02*
X1042480D01*
G01X1042940D02*
X1043137D01*
G01X1044055D02*
X1044252D01*
G01X1045272Y1648839D02*
X1044091D01*
G01X1043268Y1648732D02*
X1043924D01*
G01X1043300Y1648598D02*
X1043891D01*
G01X1042480Y1647559D02*
X1042283D01*
G01X1043727D02*
X1043465D01*
G01X1047467Y1634523D02*
X1048982D01*
G01X1041896D02*
X1040381D01*
G01X1049642Y1628366D02*
X1048225D01*
G01X1047467Y1634523D02*
X1046591Y1635400D01*
G01X1045272Y1648839D02*
X1046591Y1646554D01*
G01X1043137Y1649134D02*
X1043268Y1648732D01*
G01X1043596Y1647693D02*
X1043300Y1648598D01*
G01X1043465Y1647559D02*
X1042940Y1649134D01*
G01X1049859Y1650138D02*
Y1635400D01*
G01X1046650Y1635341D02*
Y1629941D01*
G01X1046591Y1650138D02*
Y1635400D01*
G01X1042772D02*
Y1650138D01*
G01X1042713Y1629941D02*
Y1635341D01*
G01X1042677Y1648062D02*
Y1647794D01*
G01X1042480Y1649134D02*
Y1647827D01*
G01X1042283Y1647559D02*
Y1649134D01*
G01X1039563Y1635341D02*
Y1629941D01*
G01X1044252Y1649134D02*
X1043727Y1647559D01*
G01X1043891Y1648598D02*
X1043596Y1647693D01*
G01X1043924Y1648732D02*
X1044055Y1649134D01*
G01X1044091Y1648839D02*
X1042772Y1646554D01*
G01X1042677Y1647794D02*
X1042480Y1647559D01*
G01Y1647827D02*
X1042677Y1648062D01*
G01X1049859Y1635400D02*
X1048982Y1634523D01*
G01X1042772Y1635400D02*
X1041896Y1634523D01*
G01X1047343Y1670079D02*
G03X1047933Y1670669I0J590D01*
G01X1049114Y1705512D02*
X1047933D01*
G01X1044882Y1705315D02*
X1041732D01*
G01X1048327Y1704724D02*
X1044882D01*
G01Y1697441D02*
X1041732D01*
G01X1049248Y1670079D02*
Y1706299D01*
G01X1048327Y1704724D02*
Y1667570D01*
G01X1047933Y1670079D02*
Y1706299D01*
G01X1044882Y1705315D02*
Y1697441D01*
G01X1041732Y1705315D02*
Y1697441D01*
G01X1049902Y1706299D02*
X1048327Y1704724D01*
G01X1112303Y-125984D02*
G03X1114272Y-124016I0J1969D01*
G01X1103839Y-104331D02*
Y-125984D01*
G01X1093209Y-122638D02*
X1096555Y-125984D01*
G01D02*
X1112303D01*
G01X1112894Y-119094D02*
G03X1113484Y-118504I0J590D01*
G01Y-111811D02*
G03X1112894Y-111220I-591J0D01*
G01X1111713Y-113976D02*
G03X1109744I-984J0D01*
G01Y-116339D02*
G03X1111713I985J0D01*
G01X1103799Y-112598D02*
G03X1102618Y-111417I-1181J0D01*
G01Y-118898D02*
G03X1103799Y-117717I0J1181D01*
G01X1100413Y-115157D02*
G03I-1889J0D01*
G01X1114272Y-106299D02*
G03X1112303Y-104331I-1968J0D01*
G01X1100886Y-115157D02*
G03I-2362J0D01*
G01X1099114Y-113976D02*
X1103343Y-111666D01*
G01X1097421Y-116339D02*
X1095453Y-117642D01*
G01X1091713Y-109449D02*
X1090531Y-110630D01*
G01X1096555Y-104331D02*
X1093209Y-107677D01*
G01X1114272Y-106299D02*
Y-124016D01*
G01X1113484Y-111811D02*
Y-118504D01*
G01X1111713Y-116339D02*
Y-113976D01*
G01X1109744D02*
Y-116339D01*
G01X1108366Y-119094D02*
Y-111220D01*
G01X1106791D02*
Y-119094D01*
G01X1103799Y-112598D02*
Y-117717D01*
G01X1099114Y-113976D02*
Y-116339D01*
G01X1097421Y-113976D02*
Y-116339D01*
G01X1095453Y-122047D02*
Y-107677D01*
G01X1094075Y-122047D02*
Y-118898D01*
G01Y-107677D02*
Y-111417D01*
G01X1093209Y-107677D02*
Y-122638D01*
G01X1091713Y-109449D02*
Y-117323D01*
G01X1090531Y-110630D02*
Y-116142D01*
G01D02*
X1091713Y-117323D01*
G01X1095453Y-112672D02*
X1097421Y-113976D01*
G01X1103343Y-118648D02*
X1099114Y-116339D01*
G01X1112303Y-104331D02*
X1096555D01*
G01X1106791Y-111220D02*
X1112894D01*
G01X1094075Y-111417D02*
X1102618D01*
G01X1097421Y-113976D02*
X1099114D01*
G01Y-116339D02*
X1097421D01*
G01X1102618Y-118898D02*
X1094075D01*
G01X1106791Y-119094D02*
X1112894D01*
G01X1132480Y1602362D02*
G03X1131496Y1603346I-984J0D01*
G01X1096339D02*
G03X1095354Y1602362I-1J-984D01*
G01X1121142Y1601181D02*
G03I-1457J0D01*
G01X1127835D02*
G03I-1457J0D01*
G01X1131496Y1586417D02*
G03X1132480Y1587402I0J984D01*
G01X1121142Y1588583D02*
G03I-1457J0D01*
G01X1127835D02*
G03I-1457J0D01*
G01X1109606Y1601181D02*
G03I-1456J0D01*
G01X1102913D02*
G03I-1456J0D01*
G01X1095354Y1587402D02*
G03X1096339Y1586417I985J0D01*
G01X1109606Y1588583D02*
G03I-1456J0D01*
G01X1102913D02*
G03I-1456J0D01*
G01X1095354Y1605906D02*
X1132480D01*
G01X1095354Y1605512D02*
X1132480D01*
G01X1095354Y1605118D02*
X1132480D01*
G01X1095354Y1604528D02*
X1132480D01*
G01X1097126Y1604134D02*
X1130709D01*
G01X1096339Y1603346D02*
X1131496D01*
G01X1095354Y1602362D02*
X1094764D01*
G01X1133071D02*
X1132480D01*
G01X1115058Y1602165D02*
X1129528D01*
G01X1098307D02*
X1112777D01*
G01X1095354Y1600000D02*
X1094764D01*
G01X1133071D02*
X1132480D01*
G01X1116535Y1599606D02*
X1129528D01*
G01X1111299D02*
X1098307D01*
G01X1111299Y1597835D02*
X1098307D01*
G01X1129528D02*
X1116535D01*
G01X1112777Y1596357D02*
X1098307D01*
G01X1129528D02*
X1115058D01*
G01Y1593407D02*
X1129528D01*
G01X1098307D02*
X1112777D01*
G01X1116535Y1591929D02*
X1129528D01*
G01X1098307D02*
X1111299D01*
G01Y1590157D02*
X1098307D01*
G01X1129528D02*
X1116535D01*
G01X1095354Y1589764D02*
X1094764D01*
G01X1133071D02*
X1132480D01*
G01X1112777Y1587598D02*
X1098307D01*
G01X1129528D02*
X1115058D01*
G01X1095354Y1587402D02*
X1094764D01*
G01X1133071D02*
X1132480D01*
G01X1131496Y1586417D02*
X1096339D01*
G01X1097126Y1585630D02*
X1130709D01*
G01X1132480Y1585236D02*
X1095354D01*
G01Y1584646D02*
X1132480D01*
G01Y1584252D02*
X1095354D01*
G01Y1583858D02*
X1132480D01*
G01X1130709Y1585630D02*
X1132480Y1583858D01*
G01X1112777Y1596357D02*
X1111299Y1597835D01*
G01X1115058Y1593407D02*
X1116535Y1591929D01*
G01X1095354Y1605906D02*
X1097126Y1604134D01*
G01X1116535Y1599606D02*
X1115058Y1602165D01*
G01X1111299Y1590157D02*
X1112777Y1587598D01*
G01X1133071Y1589764D02*
Y1587402D01*
G01Y1602362D02*
Y1600000D01*
G01X1132480Y1605906D02*
Y1583858D01*
G01X1130709Y1604134D02*
Y1585630D01*
G01X1129528Y1593407D02*
Y1587598D01*
G01Y1602165D02*
Y1596357D01*
G01X1116535Y1590157D02*
Y1591929D01*
G01Y1599606D02*
Y1597835D01*
G01X1115058Y1596357D02*
Y1602165D01*
G01Y1587598D02*
Y1593407D01*
G01X1112777D02*
Y1587598D01*
G01Y1602165D02*
Y1596357D01*
G01X1111299Y1591929D02*
Y1590157D01*
G01Y1599606D02*
Y1597835D01*
G01X1098307Y1596357D02*
Y1602165D01*
G01Y1587598D02*
Y1593407D01*
G01X1097126Y1604134D02*
Y1585630D01*
G01X1095354Y1605906D02*
Y1583858D01*
G01X1094764Y1589764D02*
Y1587402D01*
G01Y1602362D02*
Y1600000D01*
G01X1116535Y1590157D02*
X1115058Y1587598D01*
G01X1111299Y1599606D02*
X1112777Y1602165D01*
G01X1130709Y1604134D02*
X1132480Y1605906D01*
G01X1111299Y1591929D02*
X1112777Y1593407D01*
G01X1116535Y1597835D02*
X1115058Y1596357D01*
G01X1097126Y1585630D02*
X1095354Y1583858D01*
G01X1111417Y1630787D02*
G03X1097638I-6889J0D01*
G01D02*
G03X1111417I6890J0D01*
G01Y1630788D02*
G03I-6889J0D01*
G01X1181102Y-148819D02*
Y-3937D01*
G01X1177165Y-152756D02*
G03X1181102Y-148819I0J3937D01*
G01X1177165Y-152756D02*
G03X1181102Y-148819I0J3937D01*
G01D02*
Y-3937D01*
G01Y-94488D02*
G03X1188976I3937J0D01*
G01Y-125197D02*
G03X1181102I-3937J0D01*
G01Y-94488D02*
G03X1188976I3937J0D01*
G01Y-125197D02*
G03X1181102I-3937J0D01*
G01X1185039Y0D02*
G03X1181102Y-3937I0J-3937D01*
G01X1185039Y0D02*
G03X1181102Y-3937I0J-3937D01*
G01X1164984Y557625D02*
G03X1198795I16906J-13531D01*
G01X1164984Y557626D02*
G03X1198795I16906J-13531D01*
G01X1191870Y570756D02*
G03X1171909I-9980J-3039D01*
G01X1164984Y557625D02*
G03X1171909Y570756I-30737J24602D01*
G01X1191870D02*
G03X1171909I-9980J-3039D01*
G01X1164984Y557626D02*
G03X1171909Y570756I-30736J24602D01*
G01X1164984Y971011D02*
G03X1198795I16906J-13531D01*
G01X1164984D02*
G03X1198795I16906J-13531D01*
G01X1191870Y984142D02*
G03X1171909I-9980J-3039D01*
G01X1164984Y971011D02*
G03X1171909Y984142I-30737J24602D01*
G01X1164984Y971011D02*
G03X1171909Y984142I-30737J24602D01*
G01X1191870D02*
G03X1171909I-9980J-3040D01*
G01X1195669Y1382677D02*
X1172047D01*
G01D02*
Y1464567D01*
G01X1164173Y1378740D02*
Y1468504D01*
G01Y1378740D02*
G03X1168110Y1374804I3937J1D01*
G01X1930906Y1374803D02*
X1168110D01*
G01X1195669Y1382677D02*
X1172047D01*
G01D02*
Y1464567D01*
G01X1164173Y1378740D02*
G03X1168110Y1374803I3937J0D01*
G01X1930906D02*
X1168110D01*
G01X1164173Y1378740D02*
Y1468504D01*
G01X1172047Y1464567D02*
X1216535D01*
G01X1168110Y1472441D02*
G03X1164173Y1468504I0J-3937D01*
G01X1172047Y1464567D02*
X1216535D01*
G01X1168110Y1472441D02*
G03X1164173Y1468504I0J-3937D01*
G01X1168110Y1472441D02*
X1216535D01*
G01X1168110D02*
X1216535D01*
G01X1164984Y1561562D02*
G03X1198795I16906J-13531D01*
G01X1164984D02*
G03X1171909Y1574693I-30737J24602D01*
G01X1164984Y1561563D02*
G03X1171909Y1574693I-30736J24602D01*
G01X1164984Y1561563D02*
G03X1198795I16906J-13531D01*
G01X1191870Y1574693D02*
G03X1171909I-9980J-3039D01*
G01X1191870D02*
G03X1171909I-9980J-3039D01*
G01X1199244Y-335933D02*
Y-354870D01*
G01X1188976Y-148819D02*
G03X1192913Y-152756I3937J0D01*
G01D02*
X1919843D01*
G01X1188976Y-148819D02*
Y-125197D01*
G01Y-148819D02*
G03X1192913Y-152756I3937J0D01*
G01X1188976Y-148819D02*
Y-125197D01*
G01X1192913Y-152756D02*
X1919843D01*
G01X1188976Y-94488D02*
Y-7874D01*
G01Y-94488D02*
Y-7874D01*
G01D02*
X1315748D01*
G01X1185039Y0D02*
X1366142D01*
G01X1188976Y-7874D02*
X1315748D01*
G01X1185039Y0D02*
X1366142D01*
G01X1191870Y570756D02*
G03X1198795Y557626I37662J11472D01*
G01X1191870Y570756D02*
G03X1198795Y557626I37662J11472D01*
G01X1191870Y984142D02*
G03X1198795Y971011I37662J11471D01*
G01X1191870Y984142D02*
G03X1198795Y971011I37662J11471D01*
G01X1226378Y1382677D02*
G03Y1374803I0J-3937D01*
G01X1195669D02*
G03Y1382677I0J3937D01*
G01X1524606D02*
X1226378D01*
G01X1524606D02*
X1226378D01*
G01D02*
G03Y1374803I0J-3937D01*
G01X1195669D02*
G03Y1382677I0J3937D01*
G01X1216535Y1464567D02*
G03X1228346Y1476378I0J11811D01*
G01X1216535Y1464567D02*
G03X1228346Y1476378I0J11811D01*
G01Y1592126D02*
Y1476378D01*
G01X1220472D02*
Y1654331D01*
G01X1216535Y1472441D02*
G03X1220472Y1476378I0J3937D01*
G01X1228346Y1592126D02*
Y1476378D01*
G01X1216535Y1472441D02*
G03X1220472Y1476378I0J3937D01*
G01Y1654331D02*
Y1476378D01*
G01X1191870Y1574693D02*
G03X1198795Y1561562I37662J11471D01*
G01X1191870Y1574693D02*
G03X1198795Y1561563I37662J11472D01*
G01X1228346Y1592126D02*
G03X1220472I-3937J0D01*
G01X1228346D02*
G03X1220472I-3937J0D01*
G01X1232283Y1658268D02*
G03X1228346Y1654331I0J-3937D01*
G01X1220472Y1622835D02*
G03X1228346I3937J0D01*
G01X1232283Y1658268D02*
X1442382D01*
G01X1228346Y1654331D02*
Y1622835D01*
G01X1220472Y1654331D02*
G03X1216535Y1658268I-3937J0D01*
G01X1232283D02*
G03X1228346Y1654331I0J-3937D01*
G01X1220472Y1622835D02*
G03X1228346I3937J0D01*
G01Y1654331D02*
Y1622835D01*
G01X1232283Y1658268D02*
X1442382D01*
G01X1220472Y1654331D02*
G03X1216535Y1658268I-3937J0D01*
G01X1199244Y1841823D02*
Y1822886D01*
G01X1246358Y51969D02*
G03X1255020I4331J0D01*
G01D02*
G03X1246358I-4331J0D01*
G01X1263091Y36220D02*
G03X1285531I11220J0D01*
G01D02*
G03X1263091I-11220J0D01*
G01X1255020Y51969D02*
G03I-4331J0D01*
G01X1285531Y36221D02*
G03I-11220J0D01*
G01X1277756Y139311D02*
G03X1278346Y138720I591J0D01*
G01X1280512Y142461D02*
G03Y140492I0J-984D01*
G01X1282795Y153681D02*
G03I-1102J0D01*
G01X1277953Y149587D02*
G03X1279134Y148406I1181J0D01*
G01X1283268Y153681D02*
G03I-1575J0D01*
G01X1270866Y139902D02*
G03X1272835Y137933I1969J0D01*
G01X1277165Y161673D02*
X1275984Y160492D01*
G01X1274213Y158996D02*
X1270866Y155650D01*
G01X1278202Y148861D02*
X1280512Y153091D01*
G01D02*
Y154783D01*
G01X1277953Y149587D02*
Y158130D01*
G01X1277756Y145413D02*
Y139311D01*
G01X1277165Y161673D02*
Y294311D01*
G01X1275984Y160492D02*
Y295492D01*
G01X1274213Y195787D02*
Y156752D01*
G01X1270866Y155650D02*
Y139902D01*
G01X1280512Y154783D02*
X1279208Y156752D01*
G01X1282677Y161673D02*
X1277165D01*
G01X1283858Y160492D02*
X1275984D01*
G01X1289173Y158996D02*
X1274213D01*
G01X1277953Y158130D02*
X1274213D01*
G01Y156752D02*
X1288583D01*
G01X1282874Y154783D02*
X1280512D01*
G01X1282874Y153091D02*
X1280512D01*
G01X1284252Y148406D02*
X1279134D01*
G01X1292520Y148366D02*
X1270866D01*
G01X1285630Y145413D02*
X1277756D01*
G01Y143839D02*
X1285630D01*
G01X1282874Y142461D02*
X1280512D01*
G01Y140492D02*
X1282874D01*
G01X1285039Y138720D02*
X1278346D01*
G01X1290551Y137933D02*
X1272835D01*
G01X1272778Y199114D02*
X1272773Y199094D01*
G01X1272793Y199129D02*
X1272778Y199114D01*
G01X1272813Y199134D02*
X1272793Y199129D01*
G01X1272778Y202264D02*
X1272773Y202244D01*
G01X1272793Y202278D02*
X1272778Y202264D01*
G01X1272813Y202283D02*
X1272793Y202278D01*
G01X1272778Y205413D02*
X1272773Y205394D01*
G01X1272793Y205428D02*
X1272778Y205413D01*
G01X1272813Y205433D02*
X1272793Y205428D01*
G01X1272778Y208563D02*
X1272773Y208543D01*
G01X1272793Y208578D02*
X1272778Y208563D01*
G01X1272813Y208583D02*
X1272793Y208578D01*
G01X1272778Y211713D02*
X1272773Y211693D01*
G01X1272793Y211727D02*
X1272778Y211713D01*
G01X1272813Y211732D02*
X1272793Y211727D01*
G01X1273753Y197972D02*
X1273758Y197992D01*
G01X1273739Y197958D02*
X1273753Y197972D01*
G01X1273719Y197953D02*
X1273739Y197958D01*
G01X1273753Y201122D02*
X1273758Y201142D01*
G01X1273739Y201108D02*
X1273753Y201122D01*
G01X1273719Y201102D02*
X1273739Y201108D01*
G01X1273753Y204272D02*
X1273758Y204291D01*
G01X1273739Y204257D02*
X1273753Y204272D01*
G01X1273719Y204252D02*
X1273739Y204257D01*
G01X1273753Y207421D02*
X1273758Y207441D01*
G01X1273739Y207407D02*
X1273753Y207421D01*
G01X1273719Y207402D02*
X1273739Y207407D01*
G01X1273753Y210571D02*
X1273758Y210591D01*
G01X1273739Y210557D02*
X1273753Y210571D01*
G01X1273719Y210551D02*
X1273739Y210557D01*
G01X1273737Y197945D02*
X1273741Y197947D01*
G01X1273734Y197944D02*
X1273737Y197945D01*
G01X1273731Y197943D02*
X1273734Y197944D01*
G01X1273728Y197942D02*
X1273731Y197943D01*
G01X1273724Y197942D02*
X1273728D01*
G01X1273720D02*
X1273724D01*
G01X1272798Y199142D02*
X1272795Y199140D01*
G01X1272801Y199143D02*
X1272798Y199142D01*
G01X1272804Y199144D02*
X1272801Y199143D01*
G01X1272808Y199144D02*
X1272804D01*
G01X1272811Y199145D02*
X1272808Y199144D01*
G01X1272815Y199145D02*
X1272811D01*
G01X1273737Y201095D02*
X1273741Y201096D01*
G01X1273734Y201094D02*
X1273737Y201095D01*
G01X1273731Y201093D02*
X1273734Y201094D01*
G01X1273728Y201092D02*
X1273731Y201093D01*
G01X1273724Y201091D02*
X1273728Y201092D01*
G01X1273720Y201091D02*
X1273724D01*
G01X1272798Y202291D02*
X1272795Y202290D01*
G01X1272801Y202293D02*
X1272798Y202291D01*
G01X1272804Y202294D02*
X1272801Y202293D01*
G01X1272808Y202294D02*
X1272804D01*
G01X1272811Y202295D02*
X1272808Y202294D01*
G01X1272815Y202295D02*
X1272811D01*
G01X1273737Y204244D02*
X1273741Y204246D01*
G01X1273734Y204243D02*
X1273737Y204244D01*
G01X1273731Y204242D02*
X1273734Y204243D01*
G01X1273728Y204241D02*
X1273731Y204242D01*
G01X1273724Y204241D02*
X1273728D01*
G01X1273720D02*
X1273724D01*
G01X1272798Y205441D02*
X1272795Y205439D01*
G01X1272801Y205442D02*
X1272798Y205441D01*
G01X1272804Y205443D02*
X1272801Y205442D01*
G01X1272808Y205444D02*
X1272804Y205443D01*
G01X1272811Y205444D02*
X1272808D01*
G01X1272815D02*
X1272811D01*
G01X1273737Y207394D02*
X1273741Y207396D01*
G01X1273734Y207393D02*
X1273737Y207394D01*
G01X1273731Y207392D02*
X1273734Y207393D01*
G01X1273728Y207391D02*
X1273731Y207392D01*
G01X1273724Y207391D02*
X1273728D01*
G01X1273720D02*
X1273724D01*
G01X1272798Y208591D02*
X1272795Y208589D01*
G01X1272801Y208592D02*
X1272798Y208591D01*
G01X1272804Y208593D02*
X1272801Y208592D01*
G01X1272808Y208593D02*
X1272804D01*
G01X1272811Y208594D02*
X1272808Y208593D01*
G01X1272815Y208594D02*
X1272811D01*
G01X1273737Y210544D02*
X1273741Y210545D01*
G01X1273734Y210543D02*
X1273737Y210544D01*
G01X1273731Y210541D02*
X1273734Y210543D01*
G01X1273728Y210541D02*
X1273731D01*
G01X1273724Y210540D02*
X1273728Y210541D01*
G01X1273720Y210540D02*
X1273724D01*
G01X1272798Y211740D02*
X1272795Y211739D01*
G01X1272801Y211741D02*
X1272798Y211740D01*
G01X1272804Y211743D02*
X1272801Y211741D01*
G01X1272808Y211743D02*
X1272804D01*
G01X1272811Y211744D02*
X1272808Y211743D01*
G01X1272815Y211744D02*
X1272811D01*
G01X1273750Y199132D02*
X1273754Y199127D01*
G01X1273746Y199137D02*
X1273750Y199132D01*
G01X1273740Y199141D02*
X1273746Y199137D01*
G01X1273734Y199143D02*
X1273740Y199141D01*
G01X1273727Y199145D02*
X1273734Y199143D01*
G01X1273720Y199145D02*
X1273727D01*
G01X1273750Y202282D02*
X1273754Y202277D01*
G01X1273746Y202286D02*
X1273750Y202282D01*
G01X1273740Y202290D02*
X1273746Y202286D01*
G01X1273734Y202293D02*
X1273740Y202290D01*
G01X1273727Y202294D02*
X1273734Y202293D01*
G01X1273720Y202295D02*
X1273727Y202294D01*
G01X1273750Y205431D02*
X1273754Y205426D01*
G01X1273746Y205436D02*
X1273750Y205431D01*
G01X1273740Y205440D02*
X1273746Y205436D01*
G01X1273734Y205442D02*
X1273740Y205440D01*
G01X1273727Y205444D02*
X1273734Y205442D01*
G01X1273720Y205444D02*
X1273727D01*
G01X1273750Y208581D02*
X1273754Y208576D01*
G01X1273746Y208585D02*
X1273750Y208581D01*
G01X1273740Y208589D02*
X1273746Y208585D01*
G01X1273734Y208592D02*
X1273740Y208589D01*
G01X1273727Y208594D02*
X1273734Y208592D01*
G01X1273720Y208594D02*
X1273727D01*
G01X1273750Y211731D02*
X1273754Y211726D01*
G01X1273746Y211735D02*
X1273750Y211731D01*
G01X1273740Y211739D02*
X1273746Y211735D01*
G01X1273734Y211741D02*
X1273740Y211739D01*
G01X1273727Y211743D02*
X1273734Y211741D01*
G01X1273720Y211744D02*
X1273727Y211743D01*
G01X1272776Y197971D02*
Y197979D01*
G01X1272779Y197965D02*
X1272776Y197971D01*
G01X1272782Y197958D02*
X1272779Y197965D01*
G01X1272787Y197952D02*
X1272782Y197958D01*
G01X1272793Y197948D02*
X1272787Y197952D01*
G01X1272800Y197944D02*
X1272793Y197948D01*
G01X1272807Y197943D02*
X1272800Y197944D01*
G01X1272815Y197942D02*
X1272807Y197943D01*
G01X1272776Y201121D02*
Y201128D01*
G01X1272779Y201114D02*
X1272776Y201121D01*
G01X1272782Y201108D02*
X1272779Y201114D01*
G01X1272787Y201102D02*
X1272782Y201108D01*
G01X1272793Y201097D02*
X1272787Y201102D01*
G01X1272800Y201094D02*
X1272793Y201097D01*
G01X1272807Y201092D02*
X1272800Y201094D01*
G01X1272815Y201091D02*
X1272807Y201092D01*
G01X1272776Y204270D02*
Y204278D01*
G01X1272779Y204264D02*
X1272776Y204270D01*
G01X1272782Y204257D02*
X1272779Y204264D01*
G01X1272787Y204252D02*
X1272782Y204257D01*
G01X1272793Y204247D02*
X1272787Y204252D01*
G01X1272800Y204244D02*
X1272793Y204247D01*
G01X1272807Y204242D02*
X1272800Y204244D01*
G01X1272815Y204241D02*
X1272807Y204242D01*
G01X1272776Y207420D02*
Y207428D01*
G01X1272779Y207413D02*
X1272776Y207420D01*
G01X1272782Y207407D02*
X1272779Y207413D01*
G01X1272787Y207401D02*
X1272782Y207407D01*
G01X1272793Y207396D02*
X1272787Y207401D01*
G01X1272800Y207393D02*
X1272793Y207396D01*
G01X1272807Y207391D02*
X1272800Y207393D01*
G01X1272815Y207391D02*
X1272807D01*
G01X1272776Y210570D02*
Y210577D01*
G01X1272779Y210563D02*
X1272776Y210570D01*
G01X1272782Y210557D02*
X1272779Y210563D01*
G01X1272787Y210551D02*
X1272782Y210557D01*
G01X1272793Y210546D02*
X1272787Y210551D01*
G01X1272800Y210543D02*
X1272793Y210546D01*
G01X1272807Y210541D02*
X1272800Y210543D01*
G01X1272815Y210540D02*
X1272807Y210541D01*
G01X1273730Y199133D02*
X1273739Y199128D01*
G01X1273719Y199134D02*
X1273730Y199133D01*
G01Y202282D02*
X1273739Y202278D01*
G01X1273719Y202283D02*
X1273730Y202282D01*
G01Y205432D02*
X1273739Y205428D01*
G01X1273719Y205433D02*
X1273730Y205432D01*
G01Y208581D02*
X1273739Y208577D01*
G01X1273719Y208583D02*
X1273730Y208581D01*
G01Y211731D02*
X1273739Y211727D01*
G01X1273719Y211732D02*
X1273730Y211731D01*
G01X1272776Y201132D02*
Y201128D01*
G01X1272777Y201126D02*
X1272776Y201132D01*
G01X1272789Y201111D02*
X1272777Y201126D01*
G01X1272814Y201102D02*
X1272789Y201111D01*
G01X1272776Y204282D02*
Y204278D01*
G01X1272777Y204276D02*
X1272776Y204282D01*
G01X1272789Y204260D02*
X1272777Y204276D01*
G01X1272813Y204252D02*
X1272789Y204260D01*
G01X1272776Y210581D02*
Y210577D01*
G01X1272777Y210575D02*
X1272776Y210581D01*
G01X1272789Y210559D02*
X1272777Y210575D01*
G01X1272813Y210551D02*
X1272789Y210559D01*
G01X1272776Y197983D02*
Y197979D01*
G01X1272777Y197976D02*
X1272776Y197983D01*
G01X1272789Y197961D02*
X1272777Y197976D01*
G01X1272813Y197953D02*
X1272789Y197961D01*
G01X1272776Y207431D02*
Y207428D01*
G01X1272777Y207426D02*
X1272776Y207431D01*
G01X1272787Y207411D02*
X1272777Y207426D01*
G01X1272810Y207402D02*
X1272787Y207411D01*
G01X1273728Y205432D02*
X1273719Y205433D01*
G01X1273737Y205429D02*
X1273728Y205432D01*
G01X1273745Y205424D02*
X1273737Y205429D01*
G01X1273728Y199133D02*
X1273719Y199134D01*
G01X1273737Y199130D02*
X1273728Y199133D01*
G01X1273745Y199124D02*
X1273737Y199130D01*
G01X1273728Y202282D02*
X1273719Y202283D01*
G01X1273737Y202279D02*
X1273728Y202282D01*
G01X1273745Y202274D02*
X1273737Y202279D01*
G01X1273728Y208581D02*
X1273719Y208583D01*
G01X1273737Y208578D02*
X1273728Y208581D01*
G01X1273745Y208573D02*
X1273737Y208578D01*
G01X1273728Y211731D02*
X1273719Y211732D01*
G01X1273737Y211728D02*
X1273728Y211731D01*
G01X1273745Y211723D02*
X1273737Y211728D01*
G01X1272815Y197948D02*
Y197942D01*
G01X1272814Y197952D02*
X1272815Y197948D01*
G01X1272813Y197953D02*
X1272814Y197952D01*
G01X1272815Y201098D02*
Y201091D01*
G01X1272814Y201101D02*
X1272815Y201098D01*
G01X1272813Y201102D02*
X1272814Y201101D01*
G01X1272815Y204247D02*
Y204241D01*
G01X1272814Y204251D02*
X1272815Y204247D01*
G01X1272813Y204252D02*
X1272814Y204251D01*
G01X1272815Y207397D02*
Y207391D01*
G01X1272814Y207400D02*
X1272815Y207397D01*
G01X1272813Y207402D02*
X1272814Y207400D01*
G01X1272815Y210546D02*
Y210540D01*
G01X1272814Y210550D02*
X1272815Y210546D01*
G01X1272813Y210551D02*
X1272814Y210550D01*
G01X1272798Y201105D02*
X1272813Y201102D01*
G01X1272787Y201112D02*
X1272798Y201105D01*
G01X1272775Y201131D02*
X1272787Y201112D01*
G01X1272798Y210554D02*
X1272813Y210551D01*
G01X1272787Y210561D02*
X1272798Y210554D01*
G01X1272775Y210580D02*
X1272787Y210561D01*
G01X1272798Y204255D02*
X1272813Y204252D01*
G01X1272786Y204263D02*
X1272798Y204255D01*
G01X1272774Y204283D02*
X1272786Y204263D01*
G01X1273760Y197986D02*
Y197979D01*
G01X1273759Y197991D02*
X1273760Y197986D01*
G01X1273758Y197992D02*
X1273759Y197991D01*
G01X1273760Y201136D02*
Y201128D01*
G01X1273759Y201141D02*
X1273760Y201136D01*
G01X1273758Y201142D02*
X1273759Y201141D01*
G01X1273760Y204285D02*
Y204278D01*
G01X1273759Y204290D02*
X1273760Y204285D01*
G01X1273758Y204291D02*
X1273759Y204290D01*
G01X1273760Y207435D02*
Y207428D01*
G01X1273759Y207440D02*
X1273760Y207435D01*
G01X1273758Y207441D02*
X1273759Y207440D01*
G01X1273760Y210585D02*
Y210577D01*
G01X1273759Y210589D02*
X1273760Y210585D01*
G01X1273758Y210591D02*
X1273759Y210589D01*
G01X1272798Y197956D02*
X1272813Y197953D01*
G01X1272785Y197964D02*
X1272798Y197956D01*
G01X1272774Y197985D02*
X1272785Y197964D01*
G01X1273759Y199115D02*
X1273760Y199108D01*
G01X1273757Y199121D02*
X1273759Y199115D01*
G01X1273754Y199127D02*
X1273757Y199121D01*
G01X1273759Y202265D02*
X1273760Y202258D01*
G01X1273757Y202271D02*
X1273759Y202265D01*
G01X1273754Y202277D02*
X1273757Y202271D01*
G01X1273759Y205414D02*
X1273760Y205407D01*
G01X1273757Y205420D02*
X1273759Y205414D01*
G01X1273754Y205426D02*
X1273757Y205420D01*
G01X1273759Y208564D02*
X1273760Y208557D01*
G01X1273757Y208570D02*
X1273759Y208564D01*
G01X1273754Y208576D02*
X1273757Y208570D01*
G01X1273759Y211713D02*
X1273760Y211707D01*
G01X1273757Y211720D02*
X1273759Y211713D01*
G01X1273754Y211726D02*
X1273757Y211720D01*
G01X1273721Y197948D02*
Y197942D01*
G01X1273720Y197952D02*
X1273721Y197948D01*
G01X1273719Y197953D02*
X1273720Y197952D01*
G01X1273721Y201097D02*
Y201091D01*
G01X1273720Y201101D02*
X1273721Y201097D01*
G01X1273719Y201102D02*
X1273720Y201101D01*
G01X1273721Y204247D02*
Y204241D01*
G01X1273720Y204251D02*
X1273721Y204247D01*
G01X1273719Y204252D02*
X1273720Y204251D01*
G01X1273721Y207396D02*
Y207391D01*
G01X1273720Y207400D02*
X1273721Y207396D01*
G01X1273719Y207402D02*
X1273720Y207400D01*
G01X1273721Y210546D02*
Y210540D01*
G01X1273720Y210550D02*
X1273721Y210546D01*
G01X1273719Y210551D02*
X1273720Y210550D01*
G01X1272793Y207407D02*
X1272813Y207402D01*
G01X1272780Y207419D02*
X1272793Y207407D01*
G01X1272773Y207437D02*
X1272780Y207419D01*
G01X1273752Y205415D02*
X1273745Y205424D01*
G01X1273757Y205405D02*
X1273752Y205415D01*
G01X1273759Y205394D02*
X1273757Y205405D01*
G01X1273752Y199116D02*
X1273745Y199124D01*
G01X1273757Y199106D02*
X1273752Y199116D01*
G01X1273759Y199094D02*
X1273757Y199106D01*
G01X1273752Y202265D02*
X1273745Y202274D01*
G01X1273757Y202255D02*
X1273752Y202265D01*
G01X1273759Y202244D02*
X1273757Y202255D01*
G01X1273752Y208565D02*
X1273745Y208573D01*
G01X1273757Y208554D02*
X1273752Y208565D01*
G01X1273759Y208543D02*
X1273757Y208554D01*
G01X1273752Y211714D02*
X1273745Y211723D01*
G01X1273757Y211704D02*
X1273752Y211714D01*
G01X1273759Y211693D02*
X1273757Y211704D01*
G01X1272775Y210585D02*
X1272776Y210577D01*
G01X1272774Y210589D02*
X1272775Y210585D01*
G01Y210580D02*
X1272774Y210589D01*
G01X1272816Y211917D02*
X1272815Y211929D01*
G01X1272813Y211904D02*
X1272816Y211917D01*
G01X1272813Y211890D02*
Y211904D01*
G01X1272816Y208767D02*
X1272815Y208780D01*
G01X1272813Y208754D02*
X1272816Y208767D01*
G01X1272813Y208741D02*
Y208754D01*
G01X1272816Y205618D02*
X1272815Y205630D01*
G01X1272813Y205605D02*
X1272816Y205618D01*
G01X1272813Y205591D02*
Y205605D01*
G01X1272816Y202468D02*
X1272815Y202480D01*
G01X1272813Y202455D02*
X1272816Y202468D01*
G01X1272813Y202441D02*
Y202455D01*
G01X1272816Y199319D02*
X1272815Y199331D01*
G01X1272813Y199306D02*
X1272816Y199319D01*
G01X1272813Y199292D02*
Y199306D01*
G01Y210380D02*
X1272811Y210393D01*
G01X1272816Y210367D02*
X1272813Y210380D01*
G01X1272815Y210354D02*
X1272816Y210367D01*
G01X1272813Y207230D02*
X1272811Y207244D01*
G01X1272816Y207217D02*
X1272813Y207230D01*
G01X1272815Y207205D02*
X1272816Y207217D01*
G01X1272813Y204081D02*
X1272811Y204094D01*
G01X1272816Y204068D02*
X1272813Y204081D01*
G01X1272815Y204055D02*
X1272816Y204068D01*
G01X1272813Y200931D02*
X1272811Y200944D01*
G01X1272816Y200918D02*
X1272813Y200931D01*
G01X1272815Y200906D02*
X1272816Y200918D01*
G01X1272813Y197781D02*
X1272811Y197795D01*
G01X1272816Y197769D02*
X1272813Y197781D01*
G01X1272815Y197756D02*
X1272816Y197769D01*
G01X1273723Y211904D02*
X1273724Y211890D01*
G01X1273720Y211917D02*
X1273723Y211904D01*
G01X1273720Y211929D02*
Y211917D01*
G01X1273723Y208754D02*
X1273724Y208741D01*
G01X1273720Y208767D02*
X1273723Y208754D01*
G01X1273720Y208780D02*
Y208767D01*
G01X1273723Y205604D02*
X1273724Y205591D01*
G01X1273720Y205617D02*
X1273723Y205604D01*
G01X1273720Y205630D02*
Y205617D01*
G01X1273723Y202455D02*
X1273724Y202441D01*
G01X1273720Y202468D02*
X1273723Y202455D01*
G01X1273720Y202480D02*
Y202468D01*
G01X1273723Y199305D02*
X1273724Y199292D01*
G01X1273720Y199318D02*
X1273723Y199305D01*
G01X1273720Y199331D02*
Y199318D01*
G01X1272775Y204285D02*
X1272776Y204278D01*
G01X1272774Y204290D02*
X1272775Y204285D01*
G01X1272774Y204283D02*
Y204290D01*
G01X1273720Y210367D02*
Y210354D01*
G01X1273722Y210380D02*
X1273720Y210367D01*
G01X1273724Y210393D02*
X1273722Y210380D01*
G01X1273720Y207217D02*
Y207205D01*
G01X1273722Y207230D02*
X1273720Y207217D01*
G01X1273724Y207244D02*
X1273722Y207230D01*
G01X1273720Y204068D02*
Y204055D01*
G01X1273722Y204081D02*
X1273720Y204068D01*
G01X1273724Y204094D02*
X1273722Y204081D01*
G01X1273720Y200918D02*
Y200906D01*
G01X1273722Y200931D02*
X1273720Y200918D01*
G01X1273724Y200944D02*
X1273722Y200931D01*
G01X1273720Y197769D02*
Y197756D01*
G01X1273722Y197781D02*
X1273720Y197769D01*
G01X1273724Y197795D02*
X1273722Y197781D01*
G01X1272775Y197987D02*
X1272776Y197979D01*
G01X1272774Y197991D02*
X1272775Y197987D01*
G01X1272774Y197985D02*
Y197991D01*
G01X1272789Y211724D02*
X1272813Y211732D01*
G01X1272777Y211709D02*
X1272789Y211724D01*
G01X1272776Y211703D02*
X1272777Y211709D01*
G01X1272789Y208574D02*
X1272813Y208583D01*
G01X1272777Y208560D02*
X1272789Y208574D01*
G01X1272776Y208553D02*
X1272777Y208560D01*
G01X1272789Y205425D02*
X1272813Y205433D01*
G01X1272777Y205410D02*
X1272789Y205425D01*
G01X1272776Y205404D02*
X1272777Y205410D01*
G01X1272789Y202275D02*
X1272813Y202283D01*
G01X1272777Y202261D02*
X1272789Y202275D01*
G01X1272776Y202254D02*
X1272777Y202261D01*
G01X1272789Y199126D02*
X1272813Y199134D01*
G01X1272777Y199111D02*
X1272789Y199126D01*
G01X1272776Y199104D02*
X1272777Y199111D01*
G01X1273760Y211699D02*
Y211706D01*
G01X1273759Y211695D02*
X1273760Y211699D01*
G01X1273759Y211693D02*
Y211695D01*
G01X1273760Y208550D02*
Y208557D01*
G01X1273759Y208545D02*
X1273760Y208550D01*
G01X1273759Y208543D02*
Y208545D01*
G01X1273760Y205400D02*
Y205407D01*
G01X1273759Y205396D02*
X1273760Y205400D01*
G01X1273759Y205394D02*
Y205396D01*
G01X1273760Y202250D02*
Y202257D01*
G01X1273759Y202246D02*
X1273760Y202250D01*
G01X1273759Y202244D02*
Y202246D01*
G01X1273760Y199101D02*
Y199108D01*
G01X1273759Y199096D02*
X1273760Y199101D01*
G01X1273759Y199094D02*
Y199096D01*
G01X1272775Y207435D02*
X1272776Y207428D01*
G01X1272774Y207440D02*
X1272775Y207435D01*
G01X1272773Y207437D02*
X1272774Y207440D01*
G01X1272775Y201136D02*
X1272776Y201128D01*
G01X1272774Y201141D02*
X1272775Y201136D01*
G01X1272773Y201138D02*
X1272774Y201141D01*
G01X1273720Y211737D02*
Y211744D01*
G01Y211734D02*
Y211737D01*
G01X1273719Y211732D02*
X1273720Y211734D01*
G01Y208588D02*
Y208594D01*
G01Y208584D02*
Y208588D01*
G01X1273719Y208583D02*
X1273720Y208584D01*
G01Y205438D02*
Y205444D01*
G01Y205435D02*
Y205438D01*
G01X1273719Y205433D02*
X1273720Y205435D01*
G01Y202289D02*
Y202295D01*
G01Y202285D02*
Y202289D01*
G01X1273719Y202283D02*
X1273720Y202285D01*
G01Y199139D02*
Y199145D01*
G01Y199135D02*
Y199139D01*
G01X1273719Y199134D02*
X1273720Y199135D01*
G01X1272775Y211699D02*
X1272776Y211707D01*
G01X1272774Y211694D02*
X1272775Y211699D01*
G01X1272773Y211693D02*
X1272774Y211694D01*
G01X1272775Y208550D02*
X1272776Y208557D01*
G01X1272774Y208545D02*
X1272775Y208550D01*
G01X1272773Y208543D02*
X1272774Y208545D01*
G01X1272775Y205400D02*
X1272776Y205407D01*
G01X1272774Y205395D02*
X1272775Y205400D01*
G01X1272773Y205394D02*
X1272774Y205395D01*
G01X1272775Y202250D02*
X1272776Y202258D01*
G01X1272774Y202246D02*
X1272775Y202250D01*
G01X1272773Y202244D02*
X1272774Y202246D01*
G01X1272775Y199101D02*
X1272776Y199108D01*
G01X1272774Y199096D02*
X1272775Y199101D01*
G01X1272773Y199094D02*
X1272774Y199096D01*
G01X1273757Y210565D02*
X1273760Y210577D01*
G01X1273751Y210554D02*
X1273757Y210565D01*
G01X1273741Y210545D02*
X1273751Y210554D01*
G01X1273757Y207415D02*
X1273760Y207428D01*
G01X1273751Y207404D02*
X1273757Y207415D01*
G01X1273741Y207396D02*
X1273751Y207404D01*
G01X1273757Y204265D02*
X1273760Y204278D01*
G01X1273751Y204254D02*
X1273757Y204265D01*
G01X1273741Y204246D02*
X1273751Y204254D01*
G01X1273757Y201116D02*
X1273760Y201128D01*
G01X1273751Y201105D02*
X1273757Y201116D01*
G01X1273741Y201096D02*
X1273751Y201105D01*
G01X1273757Y197966D02*
X1273760Y197979D01*
G01X1273751Y197955D02*
X1273757Y197966D01*
G01X1273741Y197947D02*
X1273751Y197955D01*
G01X1272814Y211737D02*
Y211744D01*
G01Y211733D02*
Y211737D01*
G01X1272812Y211732D02*
X1272814Y211733D01*
G01Y208588D02*
Y208594D01*
G01Y208584D02*
Y208588D01*
G01X1272812Y208583D02*
X1272814Y208584D01*
G01Y205438D02*
Y205444D01*
G01Y205434D02*
Y205438D01*
G01X1272812Y205433D02*
X1272814Y205434D01*
G01Y202289D02*
Y202295D01*
G01Y202285D02*
Y202289D01*
G01X1272812Y202283D02*
X1272814Y202285D01*
G01Y199139D02*
Y199145D01*
G01Y199135D02*
Y199139D01*
G01X1272812Y199134D02*
X1272814Y199135D01*
G01X1272776Y211713D02*
Y211707D01*
G01X1272778Y211719D02*
X1272776Y211713D01*
G01X1272781Y211725D02*
X1272778Y211719D01*
G01X1272785Y211730D02*
X1272781Y211725D01*
G01X1272789Y211735D02*
X1272785Y211730D01*
G01X1272795Y211739D02*
X1272789Y211735D01*
G01X1272776Y208563D02*
Y208557D01*
G01X1272778Y208570D02*
X1272776Y208563D01*
G01X1272781Y208575D02*
X1272778Y208570D01*
G01X1272785Y208581D02*
X1272781Y208575D01*
G01X1272789Y208585D02*
X1272785Y208581D01*
G01X1272795Y208589D02*
X1272789Y208585D01*
G01X1272776Y205414D02*
Y205407D01*
G01X1272778Y205420D02*
X1272776Y205414D01*
G01X1272781Y205426D02*
X1272778Y205420D01*
G01X1272785Y205431D02*
X1272781Y205426D01*
G01X1272789Y205435D02*
X1272785Y205431D01*
G01X1272795Y205439D02*
X1272789Y205435D01*
G01X1272776Y202264D02*
Y202258D01*
G01X1272778Y202270D02*
X1272776Y202264D01*
G01X1272781Y202276D02*
X1272778Y202270D01*
G01X1272785Y202281D02*
X1272781Y202276D01*
G01X1272789Y202286D02*
X1272785Y202281D01*
G01X1272795Y202290D02*
X1272789Y202286D01*
G01X1272776Y199115D02*
Y199108D01*
G01X1272778Y199121D02*
X1272776Y199115D01*
G01X1272781Y199126D02*
X1272778Y199121D01*
G01X1272785Y199132D02*
X1272781Y199126D01*
G01X1272789Y199136D02*
X1272785Y199132D01*
G01X1272795Y199140D02*
X1272789Y199136D01*
G01X1273731Y210553D02*
X1273719Y210551D01*
G01X1273741Y210558D02*
X1273731Y210553D01*
G01Y207404D02*
X1273719Y207402D01*
G01X1273741Y207409D02*
X1273731Y207404D01*
G01Y204254D02*
X1273719Y204252D01*
G01X1273741Y204259D02*
X1273731Y204254D01*
G01Y201104D02*
X1273719Y201102D01*
G01X1273741Y201109D02*
X1273731Y201104D01*
G01Y197955D02*
X1273719Y197953D01*
G01X1273741Y197960D02*
X1273731Y197955D01*
G01X1273759Y199097D02*
X1273760Y199108D01*
G01X1273759Y202246D02*
X1273760Y202257D01*
G01X1273759Y205396D02*
X1273760Y205407D01*
G01X1273759Y208546D02*
X1273760Y208557D01*
G01X1273759Y211695D02*
X1273760Y211706D01*
G01Y210394D02*
Y211890D01*
G01Y207244D02*
Y208740D01*
G01Y204094D02*
Y205591D01*
G01Y200945D02*
Y202441D01*
G01Y197795D02*
Y199291D01*
G01X1273720Y197942D02*
Y197795D01*
G01Y201091D02*
Y200944D01*
G01Y202441D02*
Y202295D01*
G01Y199292D02*
Y199145D01*
G01Y207391D02*
Y207244D01*
G01Y204241D02*
Y204094D01*
G01Y205591D02*
Y205444D01*
G01Y210540D02*
Y210393D01*
G01Y211890D02*
Y211744D01*
G01Y208741D02*
Y208594D01*
G01X1272815Y210393D02*
Y210540D01*
G01Y211744D02*
Y211891D01*
G01Y208594D02*
Y208741D01*
G01Y207243D02*
Y207391D01*
G01Y204094D02*
Y204241D01*
G01Y205444D02*
Y205591D01*
G01Y200944D02*
Y201091D01*
G01Y202295D02*
Y202442D01*
G01Y199145D02*
Y199292D01*
G01Y197794D02*
Y197942D01*
G01X1272776Y202441D02*
Y200945D01*
G01Y199291D02*
Y197795D01*
G01Y205591D02*
Y204094D01*
G01Y211890D02*
Y210394D01*
G01Y208740D02*
Y207244D01*
G01X1271594Y199134D02*
Y197953D01*
G01Y202283D02*
Y201102D01*
G01Y208583D02*
Y207402D01*
G01Y205433D02*
Y204252D01*
G01Y211732D02*
Y210551D01*
G01X1271260Y220197D02*
Y195787D01*
G01X1270866D02*
Y220197D01*
G01X1267835Y210551D02*
Y211732D01*
G01Y207402D02*
Y208583D01*
G01Y204252D02*
Y205433D01*
G01Y201102D02*
Y202283D01*
G01Y197953D02*
Y199134D01*
G01X1273760Y210577D02*
X1273759Y210588D01*
G01X1273760Y207428D02*
X1273759Y207439D01*
G01X1273760Y204278D02*
X1273759Y204289D01*
G01X1273760Y201128D02*
X1273759Y201139D01*
G01X1273760Y197979D02*
X1273759Y197990D01*
G01X1272773Y207437D02*
X1272662Y207441D01*
G01X1272773Y201138D02*
X1272662Y201142D01*
G01X1272773Y210587D02*
X1272662Y210591D01*
G01X1273720Y211929D02*
X1272815D01*
G01X1273760Y211890D02*
X1272776D01*
G01X1273719Y211732D02*
X1267835D01*
G01Y211693D02*
X1273759D01*
G01X1272028Y210591D02*
X1271594D01*
G01X1273758D02*
X1267835D01*
G01X1273719Y210551D02*
X1267835D01*
G01X1272776Y210394D02*
X1273760D01*
G01X1272815Y210354D02*
X1273720D01*
G01Y208780D02*
X1272815D01*
G01X1273760Y208740D02*
X1272776D01*
G01X1273719Y208583D02*
X1267835D01*
G01Y208543D02*
X1273759D01*
G01X1272028Y207441D02*
X1271594D01*
G01X1273758D02*
X1267835D01*
G01X1273719Y207402D02*
X1267835D01*
G01X1272776Y207244D02*
X1273760D01*
G01X1272815Y207205D02*
X1273720D01*
G01Y205630D02*
X1272815D01*
G01X1273760Y205591D02*
X1272776D01*
G01X1273719Y205433D02*
X1267835D01*
G01Y205394D02*
X1273759D01*
G01X1273758Y204291D02*
X1267835D01*
G01X1273719Y204252D02*
X1267835D01*
G01X1272776Y204094D02*
X1273760D01*
G01X1272815Y204055D02*
X1273720D01*
G01Y202480D02*
X1272815D01*
G01X1273760Y202441D02*
X1272776D01*
G01X1273719Y202283D02*
X1267835D01*
G01Y202244D02*
X1273759D01*
G01X1272028Y201142D02*
X1271594D01*
G01X1273758D02*
X1267835D01*
G01X1273719Y201102D02*
X1267835D01*
G01X1272776Y200945D02*
X1273760D01*
G01X1272815Y200906D02*
X1273720D01*
G01Y199331D02*
X1272815D01*
G01X1273760Y199291D02*
X1272776D01*
G01X1273719Y199134D02*
X1267835D01*
G01Y199094D02*
X1273759D01*
G01X1273758Y197992D02*
X1267835D01*
G01X1273719Y197953D02*
X1267835D01*
G01X1272776Y197795D02*
X1273760D01*
G01X1272815Y197756D02*
X1273720D01*
G01X1274213Y195787D02*
X1270866D01*
G01X1272778Y214862D02*
X1272773Y214843D01*
G01X1272793Y214877D02*
X1272778Y214862D01*
G01X1272813Y214882D02*
X1272793Y214877D01*
G01X1272778Y218012D02*
X1272773Y217992D01*
G01X1272793Y218026D02*
X1272778Y218012D01*
G01X1272813Y218031D02*
X1272793Y218026D01*
G01X1273753Y213720D02*
X1273758Y213740D01*
G01X1273739Y213706D02*
X1273753Y213720D01*
G01X1273719Y213701D02*
X1273739Y213706D01*
G01X1273753Y216870D02*
X1273758Y216890D01*
G01X1273739Y216856D02*
X1273753Y216870D01*
G01X1273719Y216850D02*
X1273739Y216856D01*
G01X1273759Y213719D02*
X1273760Y213727D01*
G01X1273757Y213713D02*
X1273759Y213719D01*
G01X1273753Y213706D02*
X1273757Y213713D01*
G01X1273748Y213700D02*
X1273753Y213706D01*
G01X1273742Y213696D02*
X1273748Y213700D01*
G01X1273735Y213693D02*
X1273742Y213696D01*
G01X1273728Y213691D02*
X1273735Y213693D01*
G01X1273720Y213690D02*
X1273728Y213691D01*
G01X1272798Y214890D02*
X1272795Y214888D01*
G01X1272801Y214891D02*
X1272798Y214890D01*
G01X1272804Y214892D02*
X1272801Y214891D01*
G01X1272808Y214893D02*
X1272804Y214892D01*
G01X1272811Y214893D02*
X1272808D01*
G01X1272815D02*
X1272811D01*
G01X1273737Y216843D02*
X1273741Y216844D01*
G01X1273734Y216842D02*
X1273737Y216843D01*
G01X1273731Y216841D02*
X1273734Y216842D01*
G01X1273728Y216840D02*
X1273731Y216841D01*
G01X1273724Y216839D02*
X1273728Y216840D01*
G01X1273720Y216839D02*
X1273724D01*
G01X1272798Y218039D02*
X1272795Y218038D01*
G01X1272801Y218041D02*
X1272798Y218039D01*
G01X1272804Y218042D02*
X1272801Y218041D01*
G01X1272808Y218042D02*
X1272804D01*
G01X1272811Y218043D02*
X1272808Y218042D01*
G01X1272815Y218043D02*
X1272811D01*
G01X1273750Y214880D02*
X1273754Y214875D01*
G01X1273746Y214885D02*
X1273750Y214880D01*
G01X1273740Y214889D02*
X1273746Y214885D01*
G01X1273734Y214891D02*
X1273740Y214889D01*
G01X1273727Y214893D02*
X1273734Y214891D01*
G01X1273720Y214893D02*
X1273727D01*
G01X1273750Y218030D02*
X1273754Y218025D01*
G01X1273746Y218034D02*
X1273750Y218030D01*
G01X1273740Y218038D02*
X1273746Y218034D01*
G01X1273734Y218041D02*
X1273740Y218038D01*
G01X1273727Y218043D02*
X1273734Y218041D01*
G01X1273720Y218043D02*
X1273727D01*
G01X1272776Y213719D02*
Y213727D01*
G01X1272779Y213713D02*
X1272776Y213719D01*
G01X1272782Y213706D02*
X1272779Y213713D01*
G01X1272787Y213700D02*
X1272782Y213706D01*
G01X1272793Y213696D02*
X1272787Y213700D01*
G01X1272800Y213693D02*
X1272793Y213696D01*
G01X1272807Y213691D02*
X1272800Y213693D01*
G01X1272815Y213690D02*
X1272807Y213691D01*
G01X1272776Y216869D02*
Y216876D01*
G01X1272779Y216862D02*
X1272776Y216869D01*
G01X1272782Y216856D02*
X1272779Y216862D01*
G01X1272787Y216850D02*
X1272782Y216856D01*
G01X1272793Y216845D02*
X1272787Y216850D01*
G01X1272800Y216842D02*
X1272793Y216845D01*
G01X1272807Y216840D02*
X1272800Y216842D01*
G01X1272815Y216839D02*
X1272807Y216840D01*
G01X1273730Y214881D02*
X1273739Y214876D01*
G01X1273719Y214882D02*
X1273730Y214881D01*
G01Y218030D02*
X1273739Y218026D01*
G01X1273719Y218031D02*
X1273730Y218030D01*
G01X1272776Y213731D02*
Y213727D01*
G01X1272777Y213724D02*
X1272776Y213731D01*
G01X1272789Y213709D02*
X1272777Y213724D01*
G01X1272813Y213701D02*
X1272789Y213709D01*
G01X1272776Y216880D02*
Y216876D01*
G01X1272777Y216874D02*
X1272776Y216880D01*
G01X1272789Y216859D02*
X1272777Y216874D01*
G01X1272813Y216850D02*
X1272789Y216859D01*
G01X1273728Y214881D02*
X1273719Y214882D01*
G01X1273737Y214878D02*
X1273728Y214881D01*
G01X1273745Y214872D02*
X1273737Y214878D01*
G01X1273728Y218030D02*
X1273719Y218031D01*
G01X1273737Y218027D02*
X1273728Y218030D01*
G01X1273745Y218022D02*
X1273737Y218027D01*
G01X1272815Y213696D02*
Y213690D01*
G01X1272814Y213700D02*
X1272815Y213696D01*
G01X1272813Y213701D02*
X1272814Y213700D01*
G01X1272815Y216846D02*
Y216839D01*
G01X1272814Y216849D02*
X1272815Y216846D01*
G01X1272813Y216850D02*
X1272814Y216849D01*
G01X1272798Y213704D02*
X1272813Y213701D01*
G01X1272786Y213711D02*
X1272798Y213704D01*
G01X1272774Y213731D02*
X1272786Y213711D01*
G01X1273760Y213734D02*
Y213727D01*
G01X1273759Y213739D02*
X1273760Y213734D01*
G01X1273758Y213740D02*
X1273759Y213739D01*
G01X1273760Y216884D02*
Y216876D01*
G01X1273759Y216889D02*
X1273760Y216884D01*
G01X1273758Y216890D02*
X1273759Y216889D01*
G01X1272798Y216853D02*
X1272813Y216850D01*
G01X1272785Y216861D02*
X1272798Y216853D01*
G01X1272774Y216881D02*
X1272785Y216861D01*
G01X1273759Y214863D02*
X1273760Y214856D01*
G01X1273757Y214869D02*
X1273759Y214863D01*
G01X1273754Y214875D02*
X1273757Y214869D01*
G01X1273759Y218013D02*
X1273760Y218006D01*
G01X1273757Y218019D02*
X1273759Y218013D01*
G01X1273754Y218025D02*
X1273757Y218019D01*
G01X1273721Y216845D02*
Y216839D01*
G01X1273720Y216849D02*
X1273721Y216845D01*
G01X1273719Y216850D02*
X1273720Y216849D01*
G01X1273752Y214864D02*
X1273745Y214872D01*
G01X1273757Y214854D02*
X1273752Y214864D01*
G01X1273759Y214843D02*
X1273757Y214854D01*
G01X1273752Y218013D02*
X1273745Y218022D01*
G01X1273757Y218003D02*
X1273752Y218013D01*
G01X1273759Y217992D02*
X1273757Y218003D01*
G01X1272816Y218216D02*
X1272815Y218228D01*
G01X1272813Y218203D02*
X1272816Y218216D01*
G01X1272813Y218189D02*
Y218203D01*
G01X1272816Y215067D02*
X1272815Y215079D01*
G01X1272813Y215054D02*
X1272816Y215067D01*
G01X1272813Y215040D02*
Y215054D01*
G01X1272775Y216884D02*
X1272776Y216876D01*
G01X1272774Y216889D02*
X1272775Y216884D01*
G01X1272774Y216881D02*
Y216889D01*
G01X1272813Y216679D02*
X1272811Y216693D01*
G01X1272816Y216666D02*
X1272813Y216679D01*
G01X1272815Y216654D02*
X1272816Y216666D01*
G01X1272813Y213530D02*
X1272811Y213543D01*
G01X1272816Y213517D02*
X1272813Y213530D01*
G01X1272815Y213504D02*
X1272816Y213517D01*
G01X1273723Y218203D02*
X1273724Y218189D01*
G01X1273720Y218216D02*
X1273723Y218203D01*
G01X1273720Y218228D02*
Y218216D01*
G01X1273723Y215053D02*
X1273724Y215040D01*
G01X1273720Y215066D02*
X1273723Y215053D01*
G01X1273720Y215079D02*
Y215066D01*
G01X1272775Y213734D02*
X1272776Y213727D01*
G01X1272774Y213739D02*
X1272775Y213734D01*
G01X1272774Y213732D02*
Y213739D01*
G01X1273720Y216666D02*
Y216654D01*
G01X1273722Y216679D02*
X1273720Y216666D01*
G01X1273724Y216693D02*
X1273722Y216679D01*
G01X1273720Y213517D02*
Y213504D01*
G01X1273722Y213530D02*
X1273720Y213517D01*
G01X1273724Y213543D02*
X1273722Y213530D01*
G01X1272789Y218023D02*
X1272813Y218031D01*
G01X1272777Y218009D02*
X1272789Y218023D01*
G01X1272776Y218002D02*
X1272777Y218009D01*
G01X1272789Y214874D02*
X1272813Y214882D01*
G01X1272777Y214859D02*
X1272789Y214874D01*
G01X1272776Y214852D02*
X1272777Y214859D01*
G01X1273760Y217998D02*
Y218006D01*
G01X1273759Y217994D02*
X1273760Y217998D01*
G01X1273759Y217992D02*
Y217994D01*
G01X1273760Y214849D02*
Y214856D01*
G01X1273759Y214844D02*
X1273760Y214849D01*
G01X1273759Y214843D02*
Y214844D01*
G01X1273720Y218037D02*
Y218043D01*
G01Y218033D02*
Y218037D01*
G01X1273719Y218031D02*
X1273720Y218033D01*
G01Y214887D02*
Y214893D01*
G01Y214883D02*
Y214887D01*
G01X1273719Y214882D02*
X1273720Y214883D01*
G01X1272775Y217998D02*
X1272776Y218006D01*
G01X1272774Y217994D02*
X1272775Y217998D01*
G01X1272773Y217992D02*
X1272774Y217994D01*
G01X1272775Y214849D02*
X1272776Y214856D01*
G01X1272774Y214844D02*
X1272775Y214849D01*
G01X1272773Y214843D02*
X1272774Y214844D01*
G01X1273757Y216864D02*
X1273760Y216876D01*
G01X1273751Y216853D02*
X1273757Y216864D01*
G01X1273741Y216844D02*
X1273751Y216853D01*
G01X1272814Y218037D02*
Y218043D01*
G01Y218033D02*
Y218037D01*
G01X1272812Y218031D02*
X1272814Y218033D01*
G01Y214887D02*
Y214893D01*
G01Y214883D02*
Y214887D01*
G01X1272812Y214882D02*
X1272814Y214883D01*
G01X1272776Y218012D02*
Y218006D01*
G01X1272778Y218019D02*
X1272776Y218012D01*
G01X1272781Y218024D02*
X1272778Y218019D01*
G01X1272785Y218030D02*
X1272781Y218024D01*
G01X1272789Y218034D02*
X1272785Y218030D01*
G01X1272795Y218038D02*
X1272789Y218034D01*
G01X1272776Y214863D02*
Y214856D01*
G01X1272778Y214869D02*
X1272776Y214863D01*
G01X1272781Y214874D02*
X1272778Y214869D01*
G01X1272785Y214880D02*
X1272781Y214874D01*
G01X1272789Y214884D02*
X1272785Y214880D01*
G01X1272795Y214888D02*
X1272789Y214884D01*
G01X1273731Y216852D02*
X1273719Y216850D01*
G01X1273741Y216857D02*
X1273731Y216852D01*
G01Y213703D02*
X1273719Y213701D01*
G01X1273741Y213708D02*
X1273731Y213703D01*
G01X1273759Y214845D02*
X1273760Y214856D01*
G01X1273759Y217994D02*
X1273760Y218006D01*
G01X1274213Y299232D02*
Y220197D01*
G01X1273760Y216693D02*
Y218189D01*
G01Y213543D02*
Y215039D01*
G01X1273720Y216839D02*
Y216693D01*
G01Y213690D02*
Y213543D01*
G01Y215040D02*
Y214893D01*
G01Y218189D02*
Y218043D01*
G01X1272815D02*
Y218190D01*
G01Y216692D02*
Y216839D01*
G01Y213543D02*
Y213690D01*
G01Y214893D02*
Y215040D01*
G01X1272776Y215039D02*
Y213543D01*
G01Y218189D02*
Y216693D01*
G01X1271594Y218031D02*
Y216850D01*
G01Y214882D02*
Y213701D01*
G01X1267835Y216850D02*
Y218031D01*
G01Y213701D02*
Y214882D01*
G01X1273760Y216876D02*
X1273759Y216887D01*
G01X1273760Y213727D02*
X1273759Y213738D01*
G01X1273719Y213701D02*
X1273722Y213690D01*
G01X1272662Y216890D02*
X1272774Y216881D01*
G01X1274213Y220197D02*
X1270866D01*
G01X1273720Y218228D02*
X1272815D01*
G01X1273760Y218189D02*
X1272776D01*
G01X1273719Y218031D02*
X1267835D01*
G01Y217992D02*
X1273759D01*
G01X1273758Y216890D02*
X1267835D01*
G01X1273719Y216850D02*
X1267835D01*
G01X1272776Y216693D02*
X1273760D01*
G01X1272815Y216654D02*
X1273720D01*
G01Y215079D02*
X1272815D01*
G01X1273760Y215039D02*
X1272776D01*
G01X1273719Y214882D02*
X1267835D01*
G01Y214843D02*
X1273759D01*
G01X1273758Y213740D02*
X1267835D01*
G01X1273719Y213701D02*
X1267835D01*
G01X1272776Y213543D02*
X1273760D01*
G01X1272815Y213504D02*
X1273720D01*
G01X1279134Y307579D02*
G03X1277953Y306398I0J-1181D01*
G01X1283583Y302303D02*
G03I-1890J0D01*
G01X1284055D02*
G03I-2362J0D01*
G01X1279208Y299232D02*
X1280512Y301201D01*
G01D02*
Y302894D01*
G01X1277953Y297854D02*
Y306398D01*
G01X1270866Y316083D02*
Y300335D01*
G01X1280512Y302894D02*
X1278202Y307123D01*
G01X1275984Y295492D02*
X1277165Y294311D01*
G01X1270866Y300335D02*
X1274213Y296988D01*
G01X1292520Y307618D02*
X1270866D01*
G01X1279134Y307579D02*
X1284252D01*
G01X1280512Y302894D02*
X1282874D01*
G01X1280512Y301201D02*
X1282874D01*
G01X1274213Y299232D02*
X1288583D01*
G01X1274213Y297854D02*
X1277953D01*
G01X1274213Y296988D02*
X1289173D01*
G01X1275984Y295492D02*
X1283858D01*
G01X1277165Y294311D02*
X1282677D01*
G01X1278346Y317264D02*
G03X1277756Y316673I1J-591D01*
G01X1280512Y315492D02*
G03Y313524I0J-984D01*
G01X1272835Y318051D02*
G03X1270866Y316083I-1J-1968D01*
G01X1277756Y310571D02*
Y316673D01*
G01X1290551Y318051D02*
X1272835D01*
G01X1285039Y317264D02*
X1278346D01*
G01X1282874Y315492D02*
X1280512D01*
G01Y313524D02*
X1282874D01*
G01X1285630Y312146D02*
X1277756D01*
G01Y310571D02*
X1285630D01*
G01X1284965Y378885D02*
G03X1318775I16905J-13531D01*
G01X1241732Y374803D02*
G03X1242913I591J0D01*
G01Y368504D02*
G03X1241732I-590J0D01*
G01X1239764D02*
G03X1238583I-590J0D01*
G01Y374803D02*
G03X1239764I591J0D01*
G01X1241732D02*
G03X1242913I591J0D01*
G01Y368504D02*
G03X1241732I-590J0D01*
G01X1239764D02*
G03X1238583I-590J0D01*
G01Y374803D02*
G03X1239764I591J0D01*
G01X1284965Y378885D02*
G03X1318776I16906J-13531D01*
G01X1243701Y368504D02*
Y374803D01*
G01Y368504D02*
Y374803D01*
G01X1237795Y368504D02*
Y374803D01*
G01D02*
Y368504D01*
G01X1238583Y374803D02*
X1237795D01*
G01X1238583D02*
X1237795D01*
G01X1241732D02*
X1239764D01*
G01X1241732D02*
X1239764D01*
G01X1243701D02*
X1242913D01*
G01X1243701D02*
X1242913D01*
G01X1243701Y373819D02*
X1237795D01*
G01Y373622D02*
X1243701D01*
G01X1237795Y369685D02*
X1243701D01*
G01Y369488D02*
X1237795D01*
G01X1242913Y368504D02*
X1243701D01*
G01X1242913D02*
X1243701D01*
G01X1239764D02*
X1241732D01*
G01X1239764D02*
X1241732D01*
G01X1237795D02*
X1238583D01*
G01X1237795D02*
X1238583D01*
G01X1277756Y592067D02*
G03X1278346Y591476I591J0D01*
G01X1280512Y595217D02*
G03Y593248I0J-985D01*
G01X1270866Y592657D02*
G03X1272835Y590689I1969J1D01*
G01X1277756Y598169D02*
Y592067D01*
G01X1270866Y608406D02*
Y592657D01*
G01X1285630Y598169D02*
X1277756D01*
G01Y596594D02*
X1285630D01*
G01X1282874Y595217D02*
X1280512D01*
G01Y593248D02*
X1282874D01*
G01X1285039Y591476D02*
X1278346D01*
G01X1290551Y590689D02*
X1272835D01*
G01X1282795Y606437D02*
G03I-1102J0D01*
G01X1277953Y602343D02*
G03X1279134Y601161I1181J-1D01*
G01X1283268Y606437D02*
G03I-1575J0D01*
G01X1277165Y614429D02*
X1275984Y613248D01*
G01X1274213Y611752D02*
X1270866Y608406D01*
G01X1278202Y601617D02*
X1280512Y605846D01*
G01D02*
Y607539D01*
G01X1277953Y602343D02*
Y610886D01*
G01X1277165Y614429D02*
Y747067D01*
G01X1275984Y613248D02*
Y748248D01*
G01X1274213Y648543D02*
Y609508D01*
G01X1280512Y607539D02*
X1279208Y609508D01*
G01X1282677Y614429D02*
X1277165D01*
G01X1283858Y613248D02*
X1275984D01*
G01X1289173Y611752D02*
X1274213D01*
G01X1277953Y610886D02*
X1274213D01*
G01Y609508D02*
X1288583D01*
G01X1282874Y607539D02*
X1280512D01*
G01X1282874Y605846D02*
X1280512D01*
G01X1284252Y601161D02*
X1279134D01*
G01X1292520Y601122D02*
X1270866D01*
G01X1272778Y651870D02*
X1272773Y651850D01*
G01X1272793Y651885D02*
X1272778Y651870D01*
G01X1272813Y651890D02*
X1272793Y651885D01*
G01X1272778Y655020D02*
X1272773Y655000D01*
G01X1272793Y655034D02*
X1272778Y655020D01*
G01X1272813Y655039D02*
X1272793Y655034D01*
G01X1272778Y658169D02*
X1272773Y658150D01*
G01X1272793Y658184D02*
X1272778Y658169D01*
G01X1272813Y658189D02*
X1272793Y658184D01*
G01X1272778Y661319D02*
X1272773Y661299D01*
G01X1272793Y661333D02*
X1272778Y661319D01*
G01X1272813Y661339D02*
X1272793Y661333D01*
G01X1272778Y664469D02*
X1272773Y664449D01*
G01X1272793Y664483D02*
X1272778Y664469D01*
G01X1272813Y664488D02*
X1272793Y664483D01*
G01X1272778Y667618D02*
X1272773Y667598D01*
G01X1272793Y667633D02*
X1272778Y667618D01*
G01X1272813Y667638D02*
X1272793Y667633D01*
G01X1272778Y670768D02*
X1272773Y670748D01*
G01X1272793Y670782D02*
X1272778Y670768D01*
G01X1272813Y670787D02*
X1272793Y670782D01*
G01X1273753Y650728D02*
X1273758Y650748D01*
G01X1273739Y650714D02*
X1273753Y650728D01*
G01X1273719Y650709D02*
X1273739Y650714D01*
G01X1273753Y653878D02*
X1273758Y653898D01*
G01X1273739Y653864D02*
X1273753Y653878D01*
G01X1273719Y653858D02*
X1273739Y653864D01*
G01X1273753Y657028D02*
X1273758Y657047D01*
G01X1273739Y657013D02*
X1273753Y657028D01*
G01X1273719Y657008D02*
X1273739Y657013D01*
G01X1273753Y660177D02*
X1273758Y660197D01*
G01X1273739Y660163D02*
X1273753Y660177D01*
G01X1273719Y660157D02*
X1273739Y660163D01*
G01X1273753Y663327D02*
X1273758Y663346D01*
G01X1273739Y663313D02*
X1273753Y663327D01*
G01X1273719Y663307D02*
X1273739Y663313D01*
G01X1273753Y666476D02*
X1273758Y666496D01*
G01X1273739Y666462D02*
X1273753Y666476D01*
G01X1273719Y666457D02*
X1273739Y666462D01*
G01X1273753Y669626D02*
X1273758Y669646D01*
G01X1273739Y669612D02*
X1273753Y669626D01*
G01X1273719Y669606D02*
X1273739Y669612D01*
G01X1273759Y666475D02*
X1273760Y666483D01*
G01X1273757Y666469D02*
X1273759Y666475D01*
G01X1273753Y666462D02*
X1273757Y666469D01*
G01X1273748Y666456D02*
X1273753Y666462D01*
G01X1273742Y666452D02*
X1273748Y666456D01*
G01X1273735Y666448D02*
X1273742Y666452D01*
G01X1273728Y666446D02*
X1273735Y666448D01*
G01X1273720Y666446D02*
X1273728D01*
G01X1273737Y650701D02*
X1273741Y650703D01*
G01X1273734Y650700D02*
X1273737Y650701D01*
G01X1273731Y650699D02*
X1273734Y650700D01*
G01X1273728Y650698D02*
X1273731Y650699D01*
G01X1273724Y650698D02*
X1273728D01*
G01X1273720D02*
X1273724D01*
G01X1272798Y651898D02*
X1272795Y651896D01*
G01X1272801Y651899D02*
X1272798Y651898D01*
G01X1272804Y651900D02*
X1272801Y651899D01*
G01X1272808Y651900D02*
X1272804D01*
G01X1272811Y651901D02*
X1272808Y651900D01*
G01X1272815Y651901D02*
X1272811D01*
G01X1273737Y653851D02*
X1273741Y653852D01*
G01X1273734Y653850D02*
X1273737Y653851D01*
G01X1273731Y653848D02*
X1273734Y653850D01*
G01X1273728Y653848D02*
X1273731D01*
G01X1273724Y653847D02*
X1273728Y653848D01*
G01X1273720Y653847D02*
X1273724D01*
G01X1272798Y655047D02*
X1272795Y655046D01*
G01X1272801Y655048D02*
X1272798Y655047D01*
G01X1272804Y655050D02*
X1272801Y655048D01*
G01X1272808Y655050D02*
X1272804D01*
G01X1272811Y655051D02*
X1272808Y655050D01*
G01X1272815Y655051D02*
X1272811D01*
G01X1273737Y657000D02*
X1273741Y657002D01*
G01X1273734Y656999D02*
X1273737Y657000D01*
G01X1273731Y656998D02*
X1273734Y656999D01*
G01X1273728Y656997D02*
X1273731Y656998D01*
G01X1273724Y656997D02*
X1273728D01*
G01X1273720D02*
X1273724D01*
G01X1272798Y658197D02*
X1272795Y658195D01*
G01X1272801Y658198D02*
X1272798Y658197D01*
G01X1272804Y658199D02*
X1272801Y658198D01*
G01X1272808Y658200D02*
X1272804Y658199D01*
G01X1272811Y658200D02*
X1272808D01*
G01X1272815D02*
X1272811D01*
G01X1273737Y660150D02*
X1273741Y660152D01*
G01X1273734Y660149D02*
X1273737Y660150D01*
G01X1273731Y660148D02*
X1273734Y660149D01*
G01X1273728Y660147D02*
X1273731Y660148D01*
G01X1273724Y660146D02*
X1273728Y660147D01*
G01X1273720Y660146D02*
X1273724D01*
G01X1272798Y661346D02*
X1272795Y661345D01*
G01X1272801Y661348D02*
X1272798Y661346D01*
G01X1272804Y661349D02*
X1272801Y661348D01*
G01X1272808Y661349D02*
X1272804D01*
G01X1272811Y661350D02*
X1272808Y661349D01*
G01X1272815Y661350D02*
X1272811D01*
G01X1273737Y663300D02*
X1273741Y663301D01*
G01X1273734Y663298D02*
X1273737Y663300D01*
G01X1273731Y663297D02*
X1273734Y663298D01*
G01X1273728Y663296D02*
X1273731Y663297D01*
G01X1273724Y663296D02*
X1273728D01*
G01X1273720D02*
X1273724D01*
G01X1272798Y664496D02*
X1272795Y664494D01*
G01X1272801Y664497D02*
X1272798Y664496D01*
G01X1272804Y664498D02*
X1272801Y664497D01*
G01X1272808Y664499D02*
X1272804Y664498D01*
G01X1272811Y664500D02*
X1272808Y664499D01*
G01X1272815Y664500D02*
X1272811D01*
G01X1272798Y667646D02*
X1272795Y667644D01*
G01X1272801Y667647D02*
X1272798Y667646D01*
G01X1272804Y667648D02*
X1272801Y667647D01*
G01X1272808Y667648D02*
X1272804D01*
G01X1272811Y667649D02*
X1272808Y667648D01*
G01X1272815Y667649D02*
X1272811D01*
G01X1273737Y669599D02*
X1273741Y669600D01*
G01X1273734Y669598D02*
X1273737Y669599D01*
G01X1273731Y669596D02*
X1273734Y669598D01*
G01X1273728Y669596D02*
X1273731D01*
G01X1273724Y669595D02*
X1273728Y669596D01*
G01X1273720Y669595D02*
X1273724D01*
G01X1272798Y670795D02*
X1272795Y670794D01*
G01X1272801Y670796D02*
X1272798Y670795D01*
G01X1272804Y670798D02*
X1272801Y670796D01*
G01X1272808Y670798D02*
X1272804D01*
G01X1272811Y670799D02*
X1272808Y670798D01*
G01X1272815Y670799D02*
X1272811D01*
G01X1273750Y651888D02*
X1273754Y651883D01*
G01X1273746Y651893D02*
X1273750Y651888D01*
G01X1273740Y651896D02*
X1273746Y651893D01*
G01X1273734Y651899D02*
X1273740Y651896D01*
G01X1273727Y651901D02*
X1273734Y651899D01*
G01X1273720Y651901D02*
X1273727D01*
G01X1273750Y655038D02*
X1273754Y655033D01*
G01X1273746Y655042D02*
X1273750Y655038D01*
G01X1273740Y655046D02*
X1273746Y655042D01*
G01X1273734Y655048D02*
X1273740Y655046D01*
G01X1273727Y655050D02*
X1273734Y655048D01*
G01X1273720Y655051D02*
X1273727Y655050D01*
G01X1273750Y658187D02*
X1273754Y658182D01*
G01X1273746Y658192D02*
X1273750Y658187D01*
G01X1273740Y658196D02*
X1273746Y658192D01*
G01X1273734Y658198D02*
X1273740Y658196D01*
G01X1273727Y658200D02*
X1273734Y658198D01*
G01X1273720Y658200D02*
X1273727D01*
G01X1273750Y661337D02*
X1273754Y661332D01*
G01X1273746Y661341D02*
X1273750Y661337D01*
G01X1273740Y661345D02*
X1273746Y661341D01*
G01X1273734Y661348D02*
X1273740Y661345D01*
G01X1273727Y661350D02*
X1273734Y661348D01*
G01X1273720Y661350D02*
X1273727D01*
G01X1273750Y664487D02*
X1273754Y664481D01*
G01X1273746Y664491D02*
X1273750Y664487D01*
G01X1273740Y664495D02*
X1273746Y664491D01*
G01X1273734Y664497D02*
X1273740Y664495D01*
G01X1273727Y664499D02*
X1273734Y664497D01*
G01X1273720Y664500D02*
X1273727Y664499D01*
G01X1273750Y667636D02*
X1273754Y667631D01*
G01X1273746Y667641D02*
X1273750Y667636D01*
G01X1273740Y667644D02*
X1273746Y667641D01*
G01X1273734Y667647D02*
X1273740Y667644D01*
G01X1273727Y667649D02*
X1273734Y667647D01*
G01X1273720Y667649D02*
X1273727D01*
G01X1273750Y670786D02*
X1273754Y670781D01*
G01X1273746Y670790D02*
X1273750Y670786D01*
G01X1273740Y670794D02*
X1273746Y670790D01*
G01X1273734Y670796D02*
X1273740Y670794D01*
G01X1273727Y670798D02*
X1273734Y670796D01*
G01X1273720Y670799D02*
X1273727Y670798D01*
G01X1272776Y650727D02*
Y650735D01*
G01X1272779Y650720D02*
X1272776Y650727D01*
G01X1272782Y650714D02*
X1272779Y650720D01*
G01X1272787Y650708D02*
X1272782Y650714D01*
G01X1272793Y650704D02*
X1272787Y650708D01*
G01X1272800Y650700D02*
X1272793Y650704D01*
G01X1272807Y650698D02*
X1272800Y650700D01*
G01X1272815Y650698D02*
X1272807D01*
G01X1272776Y653877D02*
Y653884D01*
G01X1272779Y653870D02*
X1272776Y653877D01*
G01X1272782Y653864D02*
X1272779Y653870D01*
G01X1272787Y653858D02*
X1272782Y653864D01*
G01X1272793Y653853D02*
X1272787Y653858D01*
G01X1272800Y653850D02*
X1272793Y653853D01*
G01X1272807Y653848D02*
X1272800Y653850D01*
G01X1272815Y653847D02*
X1272807Y653848D01*
G01X1272776Y657026D02*
Y657034D01*
G01X1272779Y657020D02*
X1272776Y657026D01*
G01X1272782Y657013D02*
X1272779Y657020D01*
G01X1272787Y657007D02*
X1272782Y657013D01*
G01X1272793Y657003D02*
X1272787Y657007D01*
G01X1272800Y657000D02*
X1272793Y657003D01*
G01X1272807Y656998D02*
X1272800Y657000D01*
G01X1272815Y656997D02*
X1272807Y656998D01*
G01X1272776Y660176D02*
Y660183D01*
G01X1272779Y660169D02*
X1272776Y660176D01*
G01X1272782Y660163D02*
X1272779Y660169D01*
G01X1272787Y660157D02*
X1272782Y660163D01*
G01X1272793Y660152D02*
X1272787Y660157D01*
G01X1272800Y660149D02*
X1272793Y660152D01*
G01X1272807Y660147D02*
X1272800Y660149D01*
G01X1272815Y660146D02*
X1272807Y660147D01*
G01X1272776Y663326D02*
Y663333D01*
G01X1272779Y663319D02*
X1272776Y663326D01*
G01X1272782Y663313D02*
X1272779Y663319D01*
G01X1272787Y663307D02*
X1272782Y663313D01*
G01X1272793Y663302D02*
X1272787Y663307D01*
G01X1272800Y663299D02*
X1272793Y663302D01*
G01X1272807Y663297D02*
X1272800Y663299D01*
G01X1272815Y663296D02*
X1272807Y663297D01*
G01X1272776Y666475D02*
Y666483D01*
G01X1272779Y666469D02*
X1272776Y666475D01*
G01X1272782Y666462D02*
X1272779Y666469D01*
G01X1272787Y666456D02*
X1272782Y666462D01*
G01X1272793Y666452D02*
X1272787Y666456D01*
G01X1272800Y666448D02*
X1272793Y666452D01*
G01X1272807Y666446D02*
X1272800Y666448D01*
G01X1272815Y666446D02*
X1272807D01*
G01X1272776Y669625D02*
Y669632D01*
G01X1272779Y669618D02*
X1272776Y669625D01*
G01X1272782Y669612D02*
X1272779Y669618D01*
G01X1272787Y669606D02*
X1272782Y669612D01*
G01X1272793Y669601D02*
X1272787Y669606D01*
G01X1272800Y669598D02*
X1272793Y669601D01*
G01X1272807Y669596D02*
X1272800Y669598D01*
G01X1272815Y669595D02*
X1272807Y669596D01*
G01X1273730Y651889D02*
X1273739Y651884D01*
G01X1273719Y651890D02*
X1273730Y651889D01*
G01Y655038D02*
X1273739Y655034D01*
G01X1273719Y655039D02*
X1273730Y655038D01*
G01Y658188D02*
X1273739Y658183D01*
G01X1273719Y658189D02*
X1273730Y658188D01*
G01Y661337D02*
X1273739Y661333D01*
G01X1273719Y661339D02*
X1273730Y661337D01*
G01Y664487D02*
X1273739Y664483D01*
G01X1273719Y664488D02*
X1273730Y664487D01*
G01Y667637D02*
X1273739Y667632D01*
G01X1273719Y667638D02*
X1273730Y667637D01*
G01Y670786D02*
X1273739Y670782D01*
G01X1273719Y670787D02*
X1273730Y670786D01*
G01X1272776Y653888D02*
Y653884D01*
G01X1272777Y653882D02*
X1272776Y653888D01*
G01X1272789Y653867D02*
X1272777Y653882D01*
G01X1272814Y653858D02*
X1272789Y653867D01*
G01X1272776Y657038D02*
Y657034D01*
G01X1272777Y657031D02*
X1272776Y657038D01*
G01X1272789Y657016D02*
X1272777Y657031D01*
G01X1272813Y657008D02*
X1272789Y657016D01*
G01X1272776Y663337D02*
Y663333D01*
G01X1272777Y663331D02*
X1272776Y663337D01*
G01X1272789Y663315D02*
X1272777Y663331D01*
G01X1272813Y663307D02*
X1272789Y663315D01*
G01X1272776Y666487D02*
Y666483D01*
G01X1272777Y666480D02*
X1272776Y666487D01*
G01X1272789Y666465D02*
X1272777Y666480D01*
G01X1272813Y666457D02*
X1272789Y666465D01*
G01X1272776Y650739D02*
Y650735D01*
G01X1272777Y650732D02*
X1272776Y650739D01*
G01X1272789Y650717D02*
X1272777Y650732D01*
G01X1272813Y650709D02*
X1272789Y650717D01*
G01X1272776Y669636D02*
Y669632D01*
G01X1272777Y669630D02*
X1272776Y669636D01*
G01X1272789Y669615D02*
X1272777Y669630D01*
G01X1272813Y669606D02*
X1272789Y669615D01*
G01X1272776Y660187D02*
Y660183D01*
G01X1272777Y660182D02*
X1272776Y660187D01*
G01X1272787Y660167D02*
X1272777Y660182D01*
G01X1272810Y660158D02*
X1272787Y660167D01*
G01X1273728Y658188D02*
X1273719Y658189D01*
G01X1273737Y658185D02*
X1273728Y658188D01*
G01X1273745Y658180D02*
X1273737Y658185D01*
G01X1273728Y651889D02*
X1273719Y651890D01*
G01X1273737Y651885D02*
X1273728Y651889D01*
G01X1273745Y651880D02*
X1273737Y651885D01*
G01X1273728Y655038D02*
X1273719Y655039D01*
G01X1273737Y655035D02*
X1273728Y655038D01*
G01X1273745Y655030D02*
X1273737Y655035D01*
G01X1273728Y661337D02*
X1273719Y661339D01*
G01X1273737Y661334D02*
X1273728Y661337D01*
G01X1273745Y661329D02*
X1273737Y661334D01*
G01X1273728Y664487D02*
X1273719Y664488D01*
G01X1273737Y664484D02*
X1273728Y664487D01*
G01X1273745Y664479D02*
X1273737Y664484D01*
G01X1273728Y667637D02*
X1273719Y667638D01*
G01X1273737Y667633D02*
X1273728Y667637D01*
G01X1273745Y667628D02*
X1273737Y667633D01*
G01X1273728Y670786D02*
X1273719Y670787D01*
G01X1273737Y670783D02*
X1273728Y670786D01*
G01X1273745Y670778D02*
X1273737Y670783D01*
G01X1272815Y650704D02*
Y650698D01*
G01X1272814Y650707D02*
X1272815Y650704D01*
G01X1272813Y650709D02*
X1272814Y650707D01*
G01X1272815Y653854D02*
Y653847D01*
G01X1272814Y653857D02*
X1272815Y653854D01*
G01X1272813Y653858D02*
X1272814Y653857D01*
G01X1272815Y657003D02*
Y656997D01*
G01X1272814Y657007D02*
X1272815Y657003D01*
G01X1272813Y657008D02*
X1272814Y657007D01*
G01X1272815Y660153D02*
Y660146D01*
G01X1272814Y660156D02*
X1272815Y660153D01*
G01X1272813Y660157D02*
X1272814Y660156D01*
G01X1272815Y663302D02*
Y663296D01*
G01X1272814Y663306D02*
X1272815Y663302D01*
G01X1272813Y663307D02*
X1272814Y663306D01*
G01X1272815Y666452D02*
Y666446D01*
G01X1272814Y666456D02*
X1272815Y666452D01*
G01X1272813Y666457D02*
X1272814Y666456D01*
G01X1272815Y669602D02*
Y669595D01*
G01X1272814Y669605D02*
X1272815Y669602D01*
G01X1272813Y669606D02*
X1272814Y669605D01*
G01X1272798Y653861D02*
X1272813Y653858D01*
G01X1272787Y653868D02*
X1272798Y653861D01*
G01X1272775Y653887D02*
X1272787Y653868D01*
G01X1273757Y669620D02*
X1273760Y669632D01*
G01X1273751Y669609D02*
X1273757Y669620D01*
G01X1273741Y669600D02*
X1273751Y669609D01*
G01X1272814Y670793D02*
Y670799D01*
G01Y670789D02*
Y670793D01*
G01X1272812Y670787D02*
X1272814Y670789D01*
G01Y667643D02*
Y667649D01*
G01Y667639D02*
Y667643D01*
G01X1272812Y667638D02*
X1272814Y667639D01*
G01Y664493D02*
Y664500D01*
G01Y664489D02*
Y664493D01*
G01X1272812Y664488D02*
X1272814Y664489D01*
G01Y661344D02*
Y661350D01*
G01Y661340D02*
Y661344D01*
G01X1272812Y661339D02*
X1272814Y661340D01*
G01Y658194D02*
Y658200D01*
G01Y658190D02*
Y658194D01*
G01X1272812Y658189D02*
X1272814Y658190D01*
G01Y655044D02*
Y655051D01*
G01Y655041D02*
Y655044D01*
G01X1272812Y655039D02*
X1272814Y655041D01*
G01X1272776Y670768D02*
Y670762D01*
G01X1272778Y670774D02*
X1272776Y670768D01*
G01X1272781Y670780D02*
X1272778Y670774D01*
G01X1272785Y670785D02*
X1272781Y670780D01*
G01X1272789Y670790D02*
X1272785Y670785D01*
G01X1272795Y670794D02*
X1272789Y670790D01*
G01X1272776Y667619D02*
Y667612D01*
G01X1272778Y667625D02*
X1272776Y667619D01*
G01X1272781Y667630D02*
X1272778Y667625D01*
G01X1272785Y667636D02*
X1272781Y667630D01*
G01X1272789Y667640D02*
X1272785Y667636D01*
G01X1272795Y667644D02*
X1272789Y667640D01*
G01X1272776Y664469D02*
Y664463D01*
G01X1272778Y664475D02*
X1272776Y664469D01*
G01X1272781Y664481D02*
X1272778Y664475D01*
G01X1272785Y664486D02*
X1272781Y664481D01*
G01X1272789Y664491D02*
X1272785Y664486D01*
G01X1272795Y664494D02*
X1272789Y664491D01*
G01X1272776Y661319D02*
Y661313D01*
G01X1272778Y661326D02*
X1272776Y661319D01*
G01X1272781Y661331D02*
X1272778Y661326D01*
G01X1272785Y661337D02*
X1272781Y661331D01*
G01X1272789Y661341D02*
X1272785Y661337D01*
G01X1272795Y661345D02*
X1272789Y661341D01*
G01X1272776Y658170D02*
Y658163D01*
G01X1272778Y658176D02*
X1272776Y658170D01*
G01X1272781Y658181D02*
X1272778Y658176D01*
G01X1272785Y658187D02*
X1272781Y658181D01*
G01X1272789Y658191D02*
X1272785Y658187D01*
G01X1272795Y658195D02*
X1272789Y658191D01*
G01X1272776Y655020D02*
Y655014D01*
G01X1272778Y655026D02*
X1272776Y655020D01*
G01X1272781Y655032D02*
X1272778Y655026D01*
G01X1272785Y655037D02*
X1272781Y655032D01*
G01X1272789Y655042D02*
X1272785Y655037D01*
G01X1272795Y655046D02*
X1272789Y655042D01*
G01X1272776Y651870D02*
Y651864D01*
G01X1272778Y651877D02*
X1272776Y651870D01*
G01X1272781Y651882D02*
X1272778Y651877D01*
G01X1272785Y651888D02*
X1272781Y651882D01*
G01X1272789Y651892D02*
X1272785Y651888D01*
G01X1272795Y651896D02*
X1272789Y651892D01*
G01X1273731Y669608D02*
X1273719Y669606D01*
G01X1273741Y669613D02*
X1273731Y669608D01*
G01Y666459D02*
X1273719Y666457D01*
G01X1273741Y666464D02*
X1273731Y666459D01*
G01Y663309D02*
X1273719Y663307D01*
G01X1273741Y663314D02*
X1273731Y663309D01*
G01Y660159D02*
X1273719Y660157D01*
G01X1273741Y660165D02*
X1273731Y660159D01*
G01Y657010D02*
X1273719Y657008D01*
G01X1273741Y657015D02*
X1273731Y657010D01*
G01Y653860D02*
X1273719Y653858D01*
G01X1273741Y653865D02*
X1273731Y653860D01*
G01Y650711D02*
X1273719Y650709D01*
G01X1273741Y650716D02*
X1273731Y650711D01*
G01X1272798Y663310D02*
X1272813Y663307D01*
G01X1272787Y663317D02*
X1272798Y663310D01*
G01X1272775Y663335D02*
X1272787Y663317D01*
G01X1272798Y657011D02*
X1272813Y657008D01*
G01X1272786Y657019D02*
X1272798Y657011D01*
G01X1272774Y657039D02*
X1272786Y657019D01*
G01X1272798Y666459D02*
X1272813Y666457D01*
G01X1272786Y666467D02*
X1272798Y666459D01*
G01X1272774Y666487D02*
X1272786Y666467D01*
G01X1273760Y650742D02*
Y650735D01*
G01X1273759Y650747D02*
X1273760Y650742D01*
G01X1273758Y650748D02*
X1273759Y650747D01*
G01X1273760Y653892D02*
Y653884D01*
G01X1273759Y653896D02*
X1273760Y653892D01*
G01X1273758Y653898D02*
X1273759Y653896D01*
G01X1273760Y657041D02*
Y657034D01*
G01X1273759Y657046D02*
X1273760Y657041D01*
G01X1273758Y657047D02*
X1273759Y657046D01*
G01X1273760Y660191D02*
Y660183D01*
G01X1273759Y660196D02*
X1273760Y660191D01*
G01X1273758Y660197D02*
X1273759Y660196D01*
G01X1273760Y663341D02*
Y663333D01*
G01X1273759Y663345D02*
X1273760Y663341D01*
G01X1273758Y663346D02*
X1273759Y663345D01*
G01X1273760Y666490D02*
Y666483D01*
G01X1273759Y666495D02*
X1273760Y666490D01*
G01X1273758Y666496D02*
X1273759Y666495D01*
G01X1273760Y669640D02*
Y669632D01*
G01X1273759Y669644D02*
X1273760Y669640D01*
G01X1273758Y669646D02*
X1273759Y669644D01*
G01X1272798Y669609D02*
X1272813Y669606D01*
G01X1272785Y669617D02*
X1272798Y669609D01*
G01X1272774Y669637D02*
X1272785Y669617D01*
G01X1272798Y650712D02*
X1272813Y650709D01*
G01X1272785Y650720D02*
X1272798Y650712D01*
G01X1272774Y650741D02*
X1272785Y650720D01*
G01X1273759Y651871D02*
X1273760Y651864D01*
G01X1273757Y651877D02*
X1273759Y651871D01*
G01X1273754Y651883D02*
X1273757Y651877D01*
G01X1273759Y655020D02*
X1273760Y655014D01*
G01X1273757Y655027D02*
X1273759Y655020D01*
G01X1273754Y655033D02*
X1273757Y655027D01*
G01X1273759Y658170D02*
X1273760Y658163D01*
G01X1273757Y658176D02*
X1273759Y658170D01*
G01X1273754Y658182D02*
X1273757Y658176D01*
G01X1273759Y661320D02*
X1273760Y661313D01*
G01X1273757Y661326D02*
X1273759Y661320D01*
G01X1273754Y661332D02*
X1273757Y661326D01*
G01X1273759Y664469D02*
X1273760Y664463D01*
G01X1273757Y664476D02*
X1273759Y664469D01*
G01X1273754Y664481D02*
X1273757Y664476D01*
G01X1273759Y667619D02*
X1273760Y667612D01*
G01X1273757Y667625D02*
X1273759Y667619D01*
G01X1273754Y667631D02*
X1273757Y667625D01*
G01X1273759Y670769D02*
X1273760Y670762D01*
G01X1273757Y670775D02*
X1273759Y670769D01*
G01X1273754Y670781D02*
X1273757Y670775D01*
G01X1273721Y650704D02*
Y650698D01*
G01X1273720Y650707D02*
X1273721Y650704D01*
G01X1273719Y650709D02*
X1273720Y650707D01*
G01X1273721Y653853D02*
Y653847D01*
G01X1273720Y653857D02*
X1273721Y653853D01*
G01X1273719Y653858D02*
X1273720Y653857D01*
G01X1273721Y657003D02*
Y656997D01*
G01X1273720Y657007D02*
X1273721Y657003D01*
G01X1273719Y657008D02*
X1273720Y657007D01*
G01X1273721Y660152D02*
Y660146D01*
G01X1273720Y660156D02*
X1273721Y660152D01*
G01X1273719Y660157D02*
X1273720Y660156D01*
G01X1273721Y663302D02*
Y663296D01*
G01X1273720Y663306D02*
X1273721Y663302D01*
G01X1273719Y663307D02*
X1273720Y663306D01*
G01X1273721Y669601D02*
Y669595D01*
G01X1273720Y669605D02*
X1273721Y669601D01*
G01X1273719Y669606D02*
X1273720Y669605D01*
G01X1272793Y660163D02*
X1272813Y660157D01*
G01X1272780Y660175D02*
X1272793Y660163D01*
G01X1272773Y660193D02*
X1272780Y660175D01*
G01X1272775Y663341D02*
X1272776Y663333D01*
G01X1272774Y663345D02*
X1272775Y663341D01*
G01Y663336D02*
X1272774Y663345D01*
G01X1272816Y670972D02*
X1272815Y670984D01*
G01X1272813Y670959D02*
X1272816Y670972D01*
G01X1272813Y670945D02*
Y670959D01*
G01X1272816Y667822D02*
X1272815Y667835D01*
G01X1272813Y667809D02*
X1272816Y667822D01*
G01X1272813Y667796D02*
Y667809D01*
G01X1272816Y664673D02*
X1272815Y664685D01*
G01X1272813Y664660D02*
X1272816Y664673D01*
G01X1272813Y664646D02*
Y664660D01*
G01X1272816Y661523D02*
X1272815Y661535D01*
G01X1272813Y661510D02*
X1272816Y661523D01*
G01X1272813Y661496D02*
Y661510D01*
G01X1272816Y658374D02*
X1272815Y658386D01*
G01X1272813Y658361D02*
X1272816Y658374D01*
G01X1272813Y658347D02*
Y658361D01*
G01X1272816Y655224D02*
X1272815Y655236D01*
G01X1272813Y655211D02*
X1272816Y655224D01*
G01X1272813Y655197D02*
Y655211D01*
G01X1272816Y652074D02*
X1272815Y652087D01*
G01X1272813Y652061D02*
X1272816Y652074D01*
G01X1272813Y652048D02*
Y652061D01*
G01X1272775Y669640D02*
X1272776Y669632D01*
G01X1272774Y669644D02*
X1272775Y669640D01*
G01X1272774Y669637D02*
Y669644D01*
G01X1272813Y669435D02*
X1272811Y669448D01*
G01X1272816Y669422D02*
X1272813Y669435D01*
G01X1272815Y669409D02*
X1272816Y669422D01*
G01X1272813Y666285D02*
X1272811Y666299D01*
G01X1272816Y666272D02*
X1272813Y666285D01*
G01X1272815Y666260D02*
X1272816Y666272D01*
G01X1272813Y663136D02*
X1272811Y663149D01*
G01X1272816Y663123D02*
X1272813Y663136D01*
G01X1272815Y663110D02*
X1272816Y663123D01*
G01X1272813Y659986D02*
X1272811Y660000D01*
G01X1272816Y659973D02*
X1272813Y659986D01*
G01X1272815Y659961D02*
X1272816Y659973D01*
G01X1272813Y656837D02*
X1272811Y656850D01*
G01X1272816Y656824D02*
X1272813Y656837D01*
G01X1272815Y656811D02*
X1272816Y656824D01*
G01X1272813Y653687D02*
X1272811Y653700D01*
G01X1272816Y653674D02*
X1272813Y653687D01*
G01X1272815Y653661D02*
X1272816Y653674D01*
G01X1272813Y650537D02*
X1272811Y650551D01*
G01X1272816Y650524D02*
X1272813Y650537D01*
G01X1272815Y650512D02*
X1272816Y650524D01*
G01X1273723Y670959D02*
X1273724Y670945D01*
G01X1273720Y670972D02*
X1273723Y670959D01*
G01X1273720Y670984D02*
Y670972D01*
G01X1273723Y667809D02*
X1273724Y667796D01*
G01X1273720Y667822D02*
X1273723Y667809D01*
G01X1273720Y667835D02*
Y667822D01*
G01X1273723Y664659D02*
X1273724Y664646D01*
G01X1273720Y664672D02*
X1273723Y664659D01*
G01X1273720Y664685D02*
Y664672D01*
G01X1273723Y661510D02*
X1273724Y661496D01*
G01X1273720Y661523D02*
X1273723Y661510D01*
G01X1273720Y661535D02*
Y661523D01*
G01X1273723Y658360D02*
X1273724Y658347D01*
G01X1273720Y658373D02*
X1273723Y658360D01*
G01X1273720Y658386D02*
Y658373D01*
G01X1273723Y655211D02*
X1273724Y655197D01*
G01X1273720Y655224D02*
X1273723Y655211D01*
G01X1273720Y655236D02*
Y655224D01*
G01X1273723Y652061D02*
X1273724Y652048D01*
G01X1273720Y652074D02*
X1273723Y652061D01*
G01X1273720Y652087D02*
Y652074D01*
G01X1272775Y657041D02*
X1272776Y657034D01*
G01X1272774Y657046D02*
X1272775Y657041D01*
G01X1272774Y657039D02*
Y657046D01*
G01X1272775Y666490D02*
X1272776Y666483D01*
G01X1272774Y666495D02*
X1272775Y666490D01*
G01X1272774Y666488D02*
Y666495D01*
G01X1273720Y669422D02*
Y669409D01*
G01X1273722Y669435D02*
X1273720Y669422D01*
G01X1273724Y669448D02*
X1273722Y669435D01*
G01X1273720Y666272D02*
Y666260D01*
G01X1273722Y666285D02*
X1273720Y666272D01*
G01X1273724Y666299D02*
X1273722Y666285D01*
G01X1273720Y663123D02*
Y663110D01*
G01X1273722Y663136D02*
X1273720Y663123D01*
G01X1273724Y663149D02*
X1273722Y663136D01*
G01X1273720Y659973D02*
Y659961D01*
G01X1273722Y659986D02*
X1273720Y659973D01*
G01X1273724Y660000D02*
X1273722Y659986D01*
G01X1273720Y656824D02*
Y656811D01*
G01X1273722Y656837D02*
X1273720Y656824D01*
G01X1273724Y656850D02*
X1273722Y656837D01*
G01X1273720Y653674D02*
Y653661D01*
G01X1273722Y653687D02*
X1273720Y653674D01*
G01X1273724Y653700D02*
X1273722Y653687D01*
G01X1273720Y650524D02*
Y650512D01*
G01X1273722Y650537D02*
X1273720Y650524D01*
G01X1273724Y650551D02*
X1273722Y650537D01*
G01X1272775Y650743D02*
X1272776Y650735D01*
G01X1272774Y650747D02*
X1272775Y650743D01*
G01X1272774Y650741D02*
Y650747D01*
G01X1272789Y670779D02*
X1272813Y670787D01*
G01X1272777Y670765D02*
X1272789Y670779D01*
G01X1272776Y670758D02*
X1272777Y670765D01*
G01X1272789Y667630D02*
X1272813Y667638D01*
G01X1272777Y667615D02*
X1272789Y667630D01*
G01X1272776Y667608D02*
X1272777Y667615D01*
G01X1272789Y664480D02*
X1272813Y664488D01*
G01X1272777Y664465D02*
X1272789Y664480D01*
G01X1272776Y664459D02*
X1272777Y664465D01*
G01X1272789Y661330D02*
X1272813Y661339D01*
G01X1272777Y661316D02*
X1272789Y661330D01*
G01X1272776Y661309D02*
X1272777Y661316D01*
G01X1272789Y658181D02*
X1272813Y658189D01*
G01X1272777Y658166D02*
X1272789Y658181D01*
G01X1272776Y658159D02*
X1272777Y658166D01*
G01X1272789Y655031D02*
X1272813Y655039D01*
G01X1272777Y655017D02*
X1272789Y655031D01*
G01X1272776Y655010D02*
X1272777Y655017D01*
G01X1272789Y651881D02*
X1272813Y651890D01*
G01X1272777Y651867D02*
X1272789Y651881D01*
G01X1272776Y651860D02*
X1272777Y651867D01*
G01X1273760Y670754D02*
Y670761D01*
G01X1273759Y670750D02*
X1273760Y670754D01*
G01X1273759Y670748D02*
Y670750D01*
G01X1273760Y667605D02*
Y667612D01*
G01X1273759Y667600D02*
X1273760Y667605D01*
G01X1273759Y667598D02*
Y667600D01*
G01X1273760Y664455D02*
Y664462D01*
G01X1273759Y664451D02*
X1273760Y664455D01*
G01X1273759Y664449D02*
Y664451D01*
G01X1273760Y661306D02*
Y661313D01*
G01X1273759Y661301D02*
X1273760Y661306D01*
G01X1273759Y661299D02*
Y661301D01*
G01X1273760Y658156D02*
Y658163D01*
G01X1273759Y658152D02*
X1273760Y658156D01*
G01X1273759Y658150D02*
Y658152D01*
G01X1273760Y655006D02*
Y655013D01*
G01X1273759Y655002D02*
X1273760Y655006D01*
G01X1273759Y655000D02*
Y655002D01*
G01X1273760Y651857D02*
Y651864D01*
G01X1273759Y651852D02*
X1273760Y651857D01*
G01X1273759Y651850D02*
Y651852D01*
G01X1272775Y660191D02*
X1272776Y660183D01*
G01X1272774Y660196D02*
X1272775Y660191D01*
G01X1272773Y660193D02*
X1272774Y660196D01*
G01X1272775Y653892D02*
X1272776Y653884D01*
G01X1272774Y653896D02*
X1272775Y653892D01*
G01X1272773Y653894D02*
X1272774Y653896D01*
G01X1273720Y670793D02*
Y670799D01*
G01Y670789D02*
Y670793D01*
G01X1273719Y670787D02*
X1273720Y670789D01*
G01Y667643D02*
Y667649D01*
G01Y667639D02*
Y667643D01*
G01X1273719Y667638D02*
X1273720Y667639D01*
G01Y664493D02*
Y664500D01*
G01Y664490D02*
Y664493D01*
G01X1273719Y664488D02*
X1273720Y664490D01*
G01Y661344D02*
Y661350D01*
G01Y661340D02*
Y661344D01*
G01X1273719Y661339D02*
X1273720Y661340D01*
G01Y658194D02*
Y658200D01*
G01Y658191D02*
Y658194D01*
G01X1273719Y658189D02*
X1273720Y658191D01*
G01Y655044D02*
Y655051D01*
G01Y655041D02*
Y655044D01*
G01X1273719Y655039D02*
X1273720Y655041D01*
G01Y651895D02*
Y651901D01*
G01Y651891D02*
Y651895D01*
G01X1273719Y651890D02*
X1273720Y651891D01*
G01X1272775Y670754D02*
X1272776Y670762D01*
G01X1272774Y670750D02*
X1272775Y670754D01*
G01X1272773Y670748D02*
X1272774Y670750D01*
G01X1272775Y667605D02*
X1272776Y667612D01*
G01X1272774Y667600D02*
X1272775Y667605D01*
G01X1272773Y667598D02*
X1272774Y667600D01*
G01X1272775Y664455D02*
X1272776Y664463D01*
G01X1272774Y664450D02*
X1272775Y664455D01*
G01X1272773Y664449D02*
X1272774Y664450D01*
G01X1272775Y661306D02*
X1272776Y661313D01*
G01X1272774Y661301D02*
X1272775Y661306D01*
G01X1272773Y661299D02*
X1272774Y661301D01*
G01X1272775Y658156D02*
X1272776Y658163D01*
G01X1272774Y658151D02*
X1272775Y658156D01*
G01X1272773Y658150D02*
X1272774Y658151D01*
G01X1272775Y655006D02*
X1272776Y655014D01*
G01X1272774Y655002D02*
X1272775Y655006D01*
G01X1272773Y655000D02*
X1272774Y655002D01*
G01X1272775Y651857D02*
X1272776Y651864D01*
G01X1272774Y651852D02*
X1272775Y651857D01*
G01X1272773Y651850D02*
X1272774Y651852D01*
G01X1273757Y663320D02*
X1273760Y663333D01*
G01X1273751Y663309D02*
X1273757Y663320D01*
G01X1273741Y663301D02*
X1273751Y663309D01*
G01X1273757Y660171D02*
X1273760Y660183D01*
G01X1273751Y660160D02*
X1273757Y660171D01*
G01X1273741Y660152D02*
X1273751Y660160D01*
G01X1273757Y657021D02*
X1273760Y657034D01*
G01X1273751Y657010D02*
X1273757Y657021D01*
G01X1273741Y657002D02*
X1273751Y657010D01*
G01X1273757Y653872D02*
X1273760Y653884D01*
G01X1273751Y653861D02*
X1273757Y653872D01*
G01X1273741Y653852D02*
X1273751Y653861D01*
G01X1273757Y650722D02*
X1273760Y650735D01*
G01X1273751Y650711D02*
X1273757Y650722D01*
G01X1273741Y650703D02*
X1273751Y650711D01*
G01X1272814Y651895D02*
Y651901D01*
G01Y651891D02*
Y651895D01*
G01X1272812Y651890D02*
X1272814Y651891D01*
G01X1273752Y658171D02*
X1273745Y658180D01*
G01X1273757Y658161D02*
X1273752Y658171D01*
G01X1273759Y658150D02*
X1273757Y658161D01*
G01X1273752Y651872D02*
X1273745Y651880D01*
G01X1273757Y651861D02*
X1273752Y651872D01*
G01X1273759Y651850D02*
X1273757Y651861D01*
G01X1273752Y655021D02*
X1273745Y655030D01*
G01X1273757Y655011D02*
X1273752Y655021D01*
G01X1273759Y655000D02*
X1273757Y655011D01*
G01X1273752Y661320D02*
X1273745Y661329D01*
G01X1273757Y661310D02*
X1273752Y661320D01*
G01X1273759Y661299D02*
X1273757Y661310D01*
G01X1273752Y664470D02*
X1273745Y664479D01*
G01X1273757Y664460D02*
X1273752Y664470D01*
G01X1273759Y664449D02*
X1273757Y664460D01*
G01X1273752Y667620D02*
X1273745Y667628D01*
G01X1273757Y667609D02*
X1273752Y667620D01*
G01X1273759Y667598D02*
X1273757Y667609D01*
G01X1273752Y670769D02*
X1273745Y670778D01*
G01X1273757Y670759D02*
X1273752Y670769D01*
G01X1273759Y670748D02*
X1273757Y670759D01*
G01X1273759Y651853D02*
X1273760Y651864D01*
G01X1273759Y655002D02*
X1273760Y655013D01*
G01X1273759Y658152D02*
X1273760Y658163D01*
G01X1273759Y661302D02*
X1273760Y661313D01*
G01X1273759Y664451D02*
X1273760Y664462D01*
G01X1273759Y667601D02*
X1273760Y667612D01*
G01X1273759Y670750D02*
X1273760Y670761D01*
G01X1274213Y751988D02*
Y672953D01*
G01X1273760Y669449D02*
Y670945D01*
G01Y666299D02*
Y667795D01*
G01Y663150D02*
Y664646D01*
G01Y660000D02*
Y661496D01*
G01Y656850D02*
Y658346D01*
G01Y653701D02*
Y655197D01*
G01Y650551D02*
Y652047D01*
G01X1273720Y650698D02*
Y650551D01*
G01Y652048D02*
Y651901D01*
G01Y656997D02*
Y656850D01*
G01Y653847D02*
Y653700D01*
G01Y655197D02*
Y655051D01*
G01Y660146D02*
Y660000D01*
G01Y661496D02*
Y661350D01*
G01Y658347D02*
Y658200D01*
G01Y666446D02*
Y666299D01*
G01Y663296D02*
Y663149D01*
G01Y664646D02*
Y664500D01*
G01Y669595D02*
Y669448D01*
G01Y670945D02*
Y670799D01*
G01Y667796D02*
Y667649D01*
G01X1272815Y669448D02*
Y669595D01*
G01Y670799D02*
Y670946D01*
G01Y667649D02*
Y667796D01*
G01Y666298D02*
Y666446D01*
G01Y663149D02*
Y663296D01*
G01Y664500D02*
Y664646D01*
G01Y659999D02*
Y660146D01*
G01Y661350D02*
Y661497D01*
G01Y658200D02*
Y658347D01*
G01Y656850D02*
Y656997D01*
G01Y653700D02*
Y653847D01*
G01Y655051D02*
Y655198D01*
G01Y650550D02*
Y650698D01*
G01Y651901D02*
Y652048D01*
G01X1272776Y652047D02*
Y650551D01*
G01Y655197D02*
Y653701D01*
G01Y661496D02*
Y660000D01*
G01Y658346D02*
Y656850D01*
G01Y664646D02*
Y663150D01*
G01Y670945D02*
Y669449D01*
G01Y667795D02*
Y666299D01*
G01X1271594Y651890D02*
Y650709D01*
G01Y658189D02*
Y657008D01*
G01Y655039D02*
Y653858D01*
G01Y661339D02*
Y660157D01*
G01Y667638D02*
Y666457D01*
G01Y664488D02*
Y663307D01*
G01Y670787D02*
Y669606D01*
G01X1271260Y672953D02*
Y648543D01*
G01X1270866D02*
Y672953D01*
G01X1267835Y669606D02*
Y670787D01*
G01Y666457D02*
Y667638D01*
G01Y663307D02*
Y664488D01*
G01Y660157D02*
Y661339D01*
G01Y657008D02*
Y658189D01*
G01Y653858D02*
Y655039D01*
G01Y650709D02*
Y651890D01*
G01X1273760Y669632D02*
X1273759Y669643D01*
G01X1273760Y666483D02*
X1273759Y666494D01*
G01X1273760Y663333D02*
X1273759Y663344D01*
G01X1273760Y660183D02*
X1273759Y660194D01*
G01X1273760Y657034D02*
X1273759Y657045D01*
G01X1273760Y653884D02*
X1273759Y653895D01*
G01X1273760Y650735D02*
X1273759Y650746D01*
G01X1273719Y666457D02*
X1273722Y666446D01*
G01X1272662Y669646D02*
X1272774Y669637D01*
G01X1272773Y660193D02*
X1272662Y660197D01*
G01X1272773Y653894D02*
X1272662Y653898D01*
G01X1272773Y663343D02*
X1272662Y663346D01*
G01X1274213Y672953D02*
X1270866D01*
G01X1273720Y670984D02*
X1272815D01*
G01X1273760Y670945D02*
X1272776D01*
G01X1273719Y670787D02*
X1267835D01*
G01Y670748D02*
X1273759D01*
G01X1273758Y669646D02*
X1267835D01*
G01X1273719Y669606D02*
X1267835D01*
G01X1272776Y669449D02*
X1273760D01*
G01X1272815Y669409D02*
X1273720D01*
G01Y667835D02*
X1272815D01*
G01X1273760Y667795D02*
X1272776D01*
G01X1273719Y667638D02*
X1267835D01*
G01Y667598D02*
X1273759D01*
G01X1273758Y666496D02*
X1267835D01*
G01X1273719Y666457D02*
X1267835D01*
G01X1272776Y666299D02*
X1273760D01*
G01X1272815Y666260D02*
X1273720D01*
G01Y664685D02*
X1272815D01*
G01X1273760Y664646D02*
X1272776D01*
G01X1273719Y664488D02*
X1267835D01*
G01Y664449D02*
X1273759D01*
G01X1272028Y663346D02*
X1271594D01*
G01X1273758D02*
X1267835D01*
G01X1273719Y663307D02*
X1267835D01*
G01X1272776Y663150D02*
X1273760D01*
G01X1272815Y663110D02*
X1273720D01*
G01Y661535D02*
X1272815D01*
G01X1273760Y661496D02*
X1272776D01*
G01X1273719Y661339D02*
X1267835D01*
G01Y661299D02*
X1273759D01*
G01X1272028Y660197D02*
X1271594D01*
G01X1273758D02*
X1267835D01*
G01X1273719Y660157D02*
X1267835D01*
G01X1272776Y660000D02*
X1273760D01*
G01X1272815Y659961D02*
X1273720D01*
G01Y658386D02*
X1272815D01*
G01X1273760Y658346D02*
X1272776D01*
G01X1273719Y658189D02*
X1267835D01*
G01Y658150D02*
X1273759D01*
G01X1273758Y657047D02*
X1267835D01*
G01X1273719Y657008D02*
X1267835D01*
G01X1272776Y656850D02*
X1273760D01*
G01X1272815Y656811D02*
X1273720D01*
G01Y655236D02*
X1272815D01*
G01X1273760Y655197D02*
X1272776D01*
G01X1273719Y655039D02*
X1267835D01*
G01Y655000D02*
X1273759D01*
G01X1272028Y653898D02*
X1271594D01*
G01X1273758D02*
X1267835D01*
G01X1273719Y653858D02*
X1267835D01*
G01X1272776Y653701D02*
X1273760D01*
G01X1272815Y653661D02*
X1273720D01*
G01Y652087D02*
X1272815D01*
G01X1273760Y652047D02*
X1272776D01*
G01X1273719Y651890D02*
X1267835D01*
G01Y651850D02*
X1273759D01*
G01X1273758Y650748D02*
X1267835D01*
G01X1273719Y650709D02*
X1267835D01*
G01X1272776Y650551D02*
X1273760D01*
G01X1272815Y650512D02*
X1273720D01*
G01X1274213Y648543D02*
X1270866D01*
G01X1278346Y770020D02*
G03X1277756Y769429I1J-591D01*
G01X1280512Y768248D02*
G03Y766280I0J-984D01*
G01X1272835Y770807D02*
G03X1270866Y768839I-1J-1968D01*
G01X1279134Y760335D02*
G03X1277953Y759154I0J-1181D01*
G01X1283583Y755059D02*
G03I-1890J0D01*
G01X1284055D02*
G03I-2362J0D01*
G01X1280512Y753957D02*
Y755650D01*
G01X1277953Y750610D02*
Y759154D01*
G01X1277756Y763327D02*
Y769429D01*
G01X1270866Y768839D02*
Y753091D01*
G01X1280512Y755650D02*
X1278202Y759879D01*
G01X1275984Y748248D02*
X1277165Y747067D01*
G01X1270866Y753091D02*
X1274213Y749744D01*
G01X1279208Y751988D02*
X1280512Y753957D01*
G01X1290551Y770807D02*
X1272835D01*
G01X1285039Y770020D02*
X1278346D01*
G01X1282874Y768248D02*
X1280512D01*
G01Y766280D02*
X1282874D01*
G01X1285630Y764902D02*
X1277756D01*
G01Y763327D02*
X1285630D01*
G01X1292520Y760374D02*
X1270866D01*
G01X1279134Y760335D02*
X1284252D01*
G01X1280512Y755650D02*
X1282874D01*
G01X1280512Y753957D02*
X1282874D01*
G01X1274213Y751988D02*
X1288583D01*
G01X1274213Y750610D02*
X1277953D01*
G01X1274213Y749744D02*
X1289173D01*
G01X1275984Y748248D02*
X1283858D01*
G01X1277165Y747067D02*
X1282677D01*
G01X1284965Y831641D02*
G03X1318775I16905J-13531D01*
G01X1241732Y827559D02*
G03X1242913I591J0D01*
G01Y821260D02*
G03X1241732I-590J0D01*
G01X1239764D02*
G03X1238583I-590J0D01*
G01Y827559D02*
G03X1239764I591J0D01*
G01X1241732D02*
G03X1242913I591J0D01*
G01Y821260D02*
G03X1241732I-590J0D01*
G01X1239764D02*
G03X1238583I-590J0D01*
G01Y827559D02*
G03X1239764I591J0D01*
G01X1284965Y831641D02*
G03X1318776I16906J-13531D01*
G01X1243701Y821260D02*
Y827559D01*
G01Y821260D02*
Y827559D01*
G01X1237795Y821260D02*
Y827559D01*
G01D02*
Y821260D01*
G01X1238583Y827559D02*
X1237795D01*
G01X1238583D02*
X1237795D01*
G01X1241732D02*
X1239764D01*
G01X1241732D02*
X1239764D01*
G01X1243701D02*
X1242913D01*
G01X1243701D02*
X1242913D01*
G01X1243701Y826575D02*
X1237795D01*
G01Y826378D02*
X1243701D01*
G01X1237795Y822441D02*
X1243701D01*
G01Y822244D02*
X1237795D01*
G01X1242913Y821260D02*
X1243701D01*
G01X1242913D02*
X1243701D01*
G01X1239764D02*
X1241732D01*
G01X1239764D02*
X1241732D01*
G01X1237795D02*
X1238583D01*
G01X1237795D02*
X1238583D01*
G01X1277756Y1044823D02*
G03X1278346Y1044232I591J0D01*
G01X1280512Y1047972D02*
G03Y1046004I0J-984D01*
G01X1282795Y1059193D02*
G03I-1102J0D01*
G01X1277953Y1055098D02*
G03X1279134Y1053917I1181J0D01*
G01X1283268Y1059193D02*
G03I-1575J0D01*
G01X1270866Y1045413D02*
G03X1272835Y1043445I1969J1D01*
G01X1280512Y1060295D02*
X1279208Y1062264D01*
G01X1282677Y1067185D02*
X1277165D01*
G01X1283858Y1066004D02*
X1275984D01*
G01X1289173Y1064508D02*
X1274213D01*
G01X1280512Y1058602D02*
Y1060295D01*
G01X1277953Y1055098D02*
Y1063642D01*
G01X1277756Y1050925D02*
Y1044823D01*
G01X1277165Y1067185D02*
Y1199823D01*
G01X1275984Y1066004D02*
Y1201004D01*
G01X1274213Y1101299D02*
Y1062264D01*
G01X1270866Y1061161D02*
Y1045413D01*
G01X1277953Y1063642D02*
X1274213D01*
G01Y1062264D02*
X1288583D01*
G01X1282874Y1060295D02*
X1280512D01*
G01X1282874Y1058602D02*
X1280512D01*
G01X1284252Y1053917D02*
X1279134D01*
G01X1292520Y1053878D02*
X1270866D01*
G01X1285630Y1050925D02*
X1277756D01*
G01Y1049350D02*
X1285630D01*
G01X1282874Y1047972D02*
X1280512D01*
G01Y1046004D02*
X1282874D01*
G01X1285039Y1044232D02*
X1278346D01*
G01X1290551Y1043445D02*
X1272835D01*
G01X1278202Y1054373D02*
X1280512Y1058602D01*
G01X1277165Y1067185D02*
X1275984Y1066004D01*
G01X1274213Y1064508D02*
X1270866Y1061161D01*
G01X1273731Y1122364D02*
X1273719Y1122362D01*
G01X1273741Y1122369D02*
X1273731Y1122364D01*
G01X1272814Y1123548D02*
Y1123555D01*
G01Y1123544D02*
Y1123548D01*
G01X1272812Y1123543D02*
X1272814Y1123544D01*
G01Y1120399D02*
Y1120405D01*
G01Y1120395D02*
Y1120399D01*
G01X1272812Y1120394D02*
X1272814Y1120395D01*
G01Y1117249D02*
Y1117256D01*
G01Y1117245D02*
Y1117249D01*
G01X1272812Y1117244D02*
X1272814Y1117245D01*
G01Y1114100D02*
Y1114106D01*
G01Y1114096D02*
Y1114100D01*
G01X1272812Y1114094D02*
X1272814Y1114096D01*
G01Y1110950D02*
Y1110956D01*
G01Y1110946D02*
Y1110950D01*
G01X1272812Y1110945D02*
X1272814Y1110946D01*
G01Y1107800D02*
Y1107807D01*
G01Y1107796D02*
Y1107800D01*
G01X1272812Y1107795D02*
X1272814Y1107796D01*
G01Y1104651D02*
Y1104657D01*
G01Y1104647D02*
Y1104651D01*
G01X1272812Y1104646D02*
X1272814Y1104647D01*
G01X1272776Y1123524D02*
Y1123518D01*
G01X1272778Y1123530D02*
X1272776Y1123524D01*
G01X1272781Y1123536D02*
X1272778Y1123530D01*
G01X1272785Y1123541D02*
X1272781Y1123536D01*
G01X1272789Y1123546D02*
X1272785Y1123541D01*
G01X1272795Y1123550D02*
X1272789Y1123546D01*
G01X1272776Y1120374D02*
Y1120368D01*
G01X1272778Y1120381D02*
X1272776Y1120374D01*
G01X1272781Y1120386D02*
X1272778Y1120381D01*
G01X1272785Y1120392D02*
X1272781Y1120386D01*
G01X1272789Y1120396D02*
X1272785Y1120392D01*
G01X1272795Y1120400D02*
X1272789Y1120396D01*
G01X1272776Y1117225D02*
Y1117219D01*
G01X1272778Y1117231D02*
X1272776Y1117225D01*
G01X1272781Y1117237D02*
X1272778Y1117231D01*
G01X1272785Y1117242D02*
X1272781Y1117237D01*
G01X1272789Y1117246D02*
X1272785Y1117242D01*
G01X1272795Y1117250D02*
X1272789Y1117246D01*
G01X1272776Y1114075D02*
Y1114069D01*
G01X1272778Y1114081D02*
X1272776Y1114075D01*
G01X1272781Y1114087D02*
X1272778Y1114081D01*
G01X1272785Y1114093D02*
X1272781Y1114087D01*
G01X1272789Y1114097D02*
X1272785Y1114093D01*
G01X1272795Y1114101D02*
X1272789Y1114097D01*
G01X1272776Y1110926D02*
Y1110919D01*
G01X1272778Y1110932D02*
X1272776Y1110926D01*
G01X1272781Y1110937D02*
X1272778Y1110932D01*
G01X1272785Y1110943D02*
X1272781Y1110937D01*
G01X1272789Y1110947D02*
X1272785Y1110943D01*
G01X1272795Y1110951D02*
X1272789Y1110947D01*
G01X1272776Y1107776D02*
Y1107770D01*
G01X1272778Y1107782D02*
X1272776Y1107776D01*
G01X1272781Y1107788D02*
X1272778Y1107782D01*
G01X1272785Y1107793D02*
X1272781Y1107788D01*
G01X1272789Y1107798D02*
X1272785Y1107793D01*
G01X1272795Y1107802D02*
X1272789Y1107798D01*
G01X1272776Y1104626D02*
Y1104620D01*
G01X1272778Y1104633D02*
X1272776Y1104626D01*
G01X1272781Y1104638D02*
X1272778Y1104633D01*
G01X1272785Y1104644D02*
X1272781Y1104638D01*
G01X1272789Y1104648D02*
X1272785Y1104644D01*
G01X1272795Y1104652D02*
X1272789Y1104648D01*
G01X1273731Y1119215D02*
X1273719Y1119213D01*
G01X1273741Y1119220D02*
X1273731Y1119215D01*
G01Y1116065D02*
X1273719Y1116063D01*
G01X1273741Y1116070D02*
X1273731Y1116065D01*
G01Y1112915D02*
X1273719Y1112913D01*
G01X1273741Y1112920D02*
X1273731Y1112915D01*
G01Y1109766D02*
X1273719Y1109764D01*
G01X1273741Y1109771D02*
X1273731Y1109766D01*
G01Y1106616D02*
X1273719Y1106614D01*
G01X1273741Y1106621D02*
X1273731Y1106616D01*
G01Y1103467D02*
X1273719Y1103465D01*
G01X1273741Y1103472D02*
X1273731Y1103467D01*
G01X1272775Y1123510D02*
X1272776Y1123518D01*
G01X1272774Y1123506D02*
X1272775Y1123510D01*
G01X1272773Y1123504D02*
X1272774Y1123506D01*
G01X1272775Y1120361D02*
X1272776Y1120368D01*
G01X1272774Y1120356D02*
X1272775Y1120361D01*
G01X1272773Y1120354D02*
X1272774Y1120356D01*
G01X1272775Y1117211D02*
X1272776Y1117219D01*
G01X1272774Y1117206D02*
X1272775Y1117211D01*
G01X1272773Y1117205D02*
X1272774Y1117206D01*
G01X1272775Y1114061D02*
X1272776Y1114069D01*
G01X1272774Y1114057D02*
X1272775Y1114061D01*
G01X1272773Y1114055D02*
X1272774Y1114057D01*
G01X1272775Y1110912D02*
X1272776Y1110919D01*
G01X1272774Y1110907D02*
X1272775Y1110912D01*
G01X1272773Y1110906D02*
X1272774Y1110907D01*
G01X1272775Y1107762D02*
X1272776Y1107770D01*
G01X1272774Y1107757D02*
X1272775Y1107762D01*
G01X1272773Y1107756D02*
X1272774Y1107757D01*
G01X1272775Y1104613D02*
X1272776Y1104620D01*
G01X1272774Y1104608D02*
X1272775Y1104613D01*
G01X1272773Y1104606D02*
X1272774Y1104608D01*
G01X1273757Y1122376D02*
X1273760Y1122388D01*
G01X1273751Y1122365D02*
X1273757Y1122376D01*
G01X1273741Y1122356D02*
X1273751Y1122365D01*
G01X1273757Y1116076D02*
X1273760Y1116089D01*
G01X1273751Y1116065D02*
X1273757Y1116076D01*
G01X1273741Y1116057D02*
X1273751Y1116065D01*
G01X1273757Y1112927D02*
X1273760Y1112939D01*
G01X1273751Y1112916D02*
X1273757Y1112927D01*
G01X1273741Y1112907D02*
X1273751Y1112916D01*
G01X1273757Y1109777D02*
X1273760Y1109790D01*
G01X1273751Y1109766D02*
X1273757Y1109777D01*
G01X1273741Y1109758D02*
X1273751Y1109766D01*
G01X1273757Y1106628D02*
X1273760Y1106640D01*
G01X1273751Y1106617D02*
X1273757Y1106628D01*
G01X1273741Y1106608D02*
X1273751Y1106617D01*
G01X1273757Y1103478D02*
X1273760Y1103491D01*
G01X1273751Y1103467D02*
X1273757Y1103478D01*
G01X1273741Y1103459D02*
X1273751Y1103467D01*
G01X1273720Y1123548D02*
Y1123555D01*
G01Y1123545D02*
Y1123548D01*
G01X1273719Y1123543D02*
X1273720Y1123545D01*
G01Y1120399D02*
Y1120405D01*
G01Y1120395D02*
Y1120399D01*
G01X1273719Y1120394D02*
X1273720Y1120395D01*
G01Y1117249D02*
Y1117256D01*
G01Y1117246D02*
Y1117249D01*
G01X1273719Y1117244D02*
X1273720Y1117246D01*
G01Y1114100D02*
Y1114106D01*
G01Y1114096D02*
Y1114100D01*
G01X1273719Y1114094D02*
X1273720Y1114096D01*
G01Y1110950D02*
Y1110956D01*
G01Y1110946D02*
Y1110950D01*
G01X1273719Y1110945D02*
X1273720Y1110946D01*
G01Y1107800D02*
Y1107807D01*
G01Y1107797D02*
Y1107800D01*
G01X1273719Y1107795D02*
X1273720Y1107797D01*
G01Y1104651D02*
Y1104657D01*
G01Y1104647D02*
Y1104651D01*
G01X1273719Y1104646D02*
X1273720Y1104647D01*
G01X1273760Y1123510D02*
Y1123517D01*
G01X1273759Y1123506D02*
X1273760Y1123510D01*
G01X1273759Y1123504D02*
Y1123506D01*
G01X1273760Y1120361D02*
Y1120368D01*
G01X1273759Y1120356D02*
X1273760Y1120361D01*
G01X1273759Y1120354D02*
Y1120356D01*
G01X1273760Y1117211D02*
Y1117218D01*
G01X1273759Y1117207D02*
X1273760Y1117211D01*
G01X1273759Y1117205D02*
Y1117207D01*
G01X1273760Y1114061D02*
Y1114069D01*
G01X1273759Y1114057D02*
X1273760Y1114061D01*
G01X1273759Y1114055D02*
Y1114057D01*
G01X1273760Y1110912D02*
Y1110919D01*
G01X1273759Y1110907D02*
X1273760Y1110912D01*
G01X1273759Y1110906D02*
Y1110907D01*
G01X1273760Y1107762D02*
Y1107769D01*
G01X1273759Y1107758D02*
X1273760Y1107762D01*
G01X1273759Y1107756D02*
Y1107758D01*
G01X1273760Y1104613D02*
Y1104620D01*
G01X1273759Y1104608D02*
X1273760Y1104613D01*
G01X1273759Y1104606D02*
Y1104608D01*
G01X1272775Y1112947D02*
X1272776Y1112939D01*
G01X1272774Y1112952D02*
X1272775Y1112947D01*
G01X1272773Y1112949D02*
X1272774Y1112952D01*
G01X1272775Y1106648D02*
X1272776Y1106640D01*
G01X1272774Y1106652D02*
X1272775Y1106648D01*
G01X1272773Y1106650D02*
X1272774Y1106652D01*
G01X1272775Y1119246D02*
X1272776Y1119239D01*
G01X1272774Y1119251D02*
X1272775Y1119246D01*
G01X1272774Y1119244D02*
Y1119251D01*
G01X1273720Y1122178D02*
Y1122165D01*
G01X1273722Y1122191D02*
X1273720Y1122178D01*
G01X1273724Y1122204D02*
X1273722Y1122191D01*
G01X1273720Y1119028D02*
Y1119016D01*
G01X1273722Y1119041D02*
X1273720Y1119028D01*
G01X1273724Y1119055D02*
X1273722Y1119041D01*
G01X1273720Y1115879D02*
Y1115866D01*
G01X1273722Y1115892D02*
X1273720Y1115879D01*
G01X1273724Y1115905D02*
X1273722Y1115892D01*
G01X1273720Y1112729D02*
Y1112717D01*
G01X1273722Y1112742D02*
X1273720Y1112729D01*
G01X1273724Y1112756D02*
X1273722Y1112742D01*
G01X1273720Y1109580D02*
Y1109567D01*
G01X1273722Y1109593D02*
X1273720Y1109580D01*
G01X1273724Y1109606D02*
X1273722Y1109593D01*
G01X1273720Y1106430D02*
Y1106417D01*
G01X1273722Y1106443D02*
X1273720Y1106430D01*
G01X1273724Y1106456D02*
X1273722Y1106443D01*
G01X1273720Y1103280D02*
Y1103268D01*
G01X1273722Y1103293D02*
X1273720Y1103280D01*
G01X1273724Y1103307D02*
X1273722Y1103293D01*
G01X1272775Y1103498D02*
X1272776Y1103491D01*
G01X1272774Y1103503D02*
X1272775Y1103498D01*
G01X1272774Y1103496D02*
Y1103503D01*
G01X1272789Y1123535D02*
X1272813Y1123543D01*
G01X1272777Y1123520D02*
X1272789Y1123535D01*
G01X1272776Y1123514D02*
X1272777Y1123520D01*
G01X1272789Y1120385D02*
X1272813Y1120394D01*
G01X1272777Y1120371D02*
X1272789Y1120385D01*
G01X1272776Y1120364D02*
X1272777Y1120371D01*
G01X1272789Y1117236D02*
X1272813Y1117244D01*
G01X1272777Y1117221D02*
X1272789Y1117236D01*
G01X1272776Y1117215D02*
X1272777Y1117221D01*
G01X1272789Y1114086D02*
X1272813Y1114094D01*
G01X1272777Y1114072D02*
X1272789Y1114086D01*
G01X1272776Y1114065D02*
X1272777Y1114072D01*
G01X1272789Y1110937D02*
X1272813Y1110945D01*
G01X1272777Y1110922D02*
X1272789Y1110937D01*
G01X1272776Y1110915D02*
X1272777Y1110922D01*
G01X1272789Y1107787D02*
X1272813Y1107795D01*
G01X1272777Y1107772D02*
X1272789Y1107787D01*
G01X1272776Y1107766D02*
X1272777Y1107772D01*
G01X1272789Y1104637D02*
X1272813Y1104646D01*
G01X1272777Y1104623D02*
X1272789Y1104637D01*
G01X1272776Y1104616D02*
X1272777Y1104623D01*
G01X1272778Y1104626D02*
X1272773Y1104606D01*
G01X1272793Y1104641D02*
X1272778Y1104626D01*
G01X1272813Y1104646D02*
X1272793Y1104641D01*
G01X1272778Y1107776D02*
X1272773Y1107756D01*
G01X1272793Y1107790D02*
X1272778Y1107776D01*
G01X1272813Y1107795D02*
X1272793Y1107790D01*
G01X1272778Y1110925D02*
X1272773Y1110906D01*
G01X1272793Y1110940D02*
X1272778Y1110925D01*
G01X1272813Y1110945D02*
X1272793Y1110940D01*
G01X1272778Y1114075D02*
X1272773Y1114055D01*
G01X1272793Y1114089D02*
X1272778Y1114075D01*
G01X1272813Y1114094D02*
X1272793Y1114089D01*
G01X1272778Y1117224D02*
X1272773Y1117205D01*
G01X1272793Y1117239D02*
X1272778Y1117224D01*
G01X1272813Y1117244D02*
X1272793Y1117239D01*
G01X1272778Y1120374D02*
X1272773Y1120354D01*
G01X1272793Y1120389D02*
X1272778Y1120374D01*
G01X1272813Y1120394D02*
X1272793Y1120389D01*
G01X1272778Y1123524D02*
X1272773Y1123504D01*
G01X1272793Y1123538D02*
X1272778Y1123524D01*
G01X1272813Y1123543D02*
X1272793Y1123538D01*
G01X1273753Y1103484D02*
X1273758Y1103504D01*
G01X1273739Y1103470D02*
X1273753Y1103484D01*
G01X1273719Y1103465D02*
X1273739Y1103470D01*
G01X1273753Y1106634D02*
X1273758Y1106654D01*
G01X1273739Y1106620D02*
X1273753Y1106634D01*
G01X1273719Y1106614D02*
X1273739Y1106620D01*
G01X1273753Y1109783D02*
X1273758Y1109803D01*
G01X1273739Y1109769D02*
X1273753Y1109783D01*
G01X1273719Y1109764D02*
X1273739Y1109769D01*
G01X1273753Y1112933D02*
X1273758Y1112953D01*
G01X1273739Y1112919D02*
X1273753Y1112933D01*
G01X1273719Y1112913D02*
X1273739Y1112919D01*
G01X1273753Y1116083D02*
X1273758Y1116102D01*
G01X1273739Y1116069D02*
X1273753Y1116083D01*
G01X1273719Y1116063D02*
X1273739Y1116069D01*
G01X1273753Y1119232D02*
X1273758Y1119252D01*
G01X1273739Y1119218D02*
X1273753Y1119232D01*
G01X1273719Y1119213D02*
X1273739Y1119218D01*
G01X1273753Y1122382D02*
X1273758Y1122402D01*
G01X1273739Y1122368D02*
X1273753Y1122382D01*
G01X1273719Y1122362D02*
X1273739Y1122368D01*
G01X1272775Y1116096D02*
X1272776Y1116089D01*
G01X1272774Y1116101D02*
X1272775Y1116096D01*
G01Y1116092D02*
X1272774Y1116101D01*
G01X1272816Y1123728D02*
X1272815Y1123740D01*
G01X1272813Y1123715D02*
X1272816Y1123728D01*
G01X1272813Y1123701D02*
Y1123715D01*
G01X1272816Y1120578D02*
X1272815Y1120591D01*
G01X1272813Y1120565D02*
X1272816Y1120578D01*
G01X1272813Y1120552D02*
Y1120565D01*
G01X1272816Y1117429D02*
X1272815Y1117441D01*
G01X1272813Y1117416D02*
X1272816Y1117429D01*
G01X1272813Y1117402D02*
Y1117416D01*
G01X1272816Y1114279D02*
X1272815Y1114291D01*
G01X1272813Y1114266D02*
X1272816Y1114279D01*
G01X1272813Y1114252D02*
Y1114266D01*
G01X1272816Y1111130D02*
X1272815Y1111142D01*
G01X1272813Y1111117D02*
X1272816Y1111130D01*
G01X1272813Y1111103D02*
Y1111117D01*
G01X1272816Y1107980D02*
X1272815Y1107992D01*
G01X1272813Y1107967D02*
X1272816Y1107980D01*
G01X1272813Y1107953D02*
Y1107967D01*
G01X1272816Y1104830D02*
X1272815Y1104843D01*
G01X1272813Y1104817D02*
X1272816Y1104830D01*
G01X1272813Y1104804D02*
Y1104817D01*
G01X1272775Y1122396D02*
X1272776Y1122388D01*
G01X1272774Y1122400D02*
X1272775Y1122396D01*
G01X1272774Y1122393D02*
Y1122400D01*
G01X1272813Y1122191D02*
X1272811Y1122204D01*
G01X1272816Y1122178D02*
X1272813Y1122191D01*
G01X1272815Y1122165D02*
X1272816Y1122178D01*
G01X1272813Y1119041D02*
X1272811Y1119055D01*
G01X1272816Y1119028D02*
X1272813Y1119041D01*
G01X1272815Y1119016D02*
X1272816Y1119028D01*
G01X1272813Y1115892D02*
X1272811Y1115905D01*
G01X1272816Y1115879D02*
X1272813Y1115892D01*
G01X1272815Y1115866D02*
X1272816Y1115879D01*
G01X1272813Y1112742D02*
X1272811Y1112756D01*
G01X1272816Y1112729D02*
X1272813Y1112742D01*
G01X1272815Y1112717D02*
X1272816Y1112729D01*
G01X1272813Y1109593D02*
X1272811Y1109606D01*
G01X1272816Y1109580D02*
X1272813Y1109593D01*
G01X1272815Y1109567D02*
X1272816Y1109580D01*
G01X1272813Y1106443D02*
X1272811Y1106456D01*
G01X1272816Y1106430D02*
X1272813Y1106443D01*
G01X1272815Y1106417D02*
X1272816Y1106430D01*
G01X1272813Y1103293D02*
X1272811Y1103307D01*
G01X1272816Y1103280D02*
X1272813Y1103293D01*
G01X1272815Y1103268D02*
X1272816Y1103280D01*
G01X1273723Y1123715D02*
X1273724Y1123701D01*
G01X1273720Y1123728D02*
X1273723Y1123715D01*
G01X1273720Y1123740D02*
Y1123728D01*
G01X1273723Y1120565D02*
X1273724Y1120552D01*
G01X1273720Y1120578D02*
X1273723Y1120565D01*
G01X1273720Y1120591D02*
Y1120578D01*
G01X1273723Y1117415D02*
X1273724Y1117402D01*
G01X1273720Y1117428D02*
X1273723Y1117415D01*
G01X1273720Y1117441D02*
Y1117428D01*
G01X1273723Y1114266D02*
X1273724Y1114252D01*
G01X1273720Y1114279D02*
X1273723Y1114266D01*
G01X1273720Y1114291D02*
Y1114279D01*
G01X1273723Y1111116D02*
X1273724Y1111103D01*
G01X1273720Y1111129D02*
X1273723Y1111116D01*
G01X1273720Y1111142D02*
Y1111129D01*
G01X1273723Y1107967D02*
X1273724Y1107953D01*
G01X1273720Y1107980D02*
X1273723Y1107967D01*
G01X1273720Y1107992D02*
Y1107980D01*
G01X1273723Y1104817D02*
X1273724Y1104804D01*
G01X1273720Y1104830D02*
X1273723Y1104817D01*
G01X1273720Y1104843D02*
Y1104830D01*
G01X1272775Y1109797D02*
X1272776Y1109790D01*
G01X1272774Y1109802D02*
X1272775Y1109797D01*
G01X1272774Y1109795D02*
Y1109802D01*
G01X1273759Y1119231D02*
X1273760Y1119239D01*
G01X1273757Y1119224D02*
X1273759Y1119231D01*
G01X1273753Y1119218D02*
X1273757Y1119224D01*
G01X1273748Y1119212D02*
X1273753Y1119218D01*
G01X1273742Y1119207D02*
X1273748Y1119212D01*
G01X1273735Y1119204D02*
X1273742Y1119207D01*
G01X1273728Y1119202D02*
X1273735Y1119204D01*
G01X1273720Y1119202D02*
X1273728D01*
G01X1273737Y1103457D02*
X1273741Y1103459D01*
G01X1273734Y1103456D02*
X1273737Y1103457D01*
G01X1273731Y1103455D02*
X1273734Y1103456D01*
G01X1273728Y1103454D02*
X1273731Y1103455D01*
G01X1273724Y1103454D02*
X1273728D01*
G01X1273720D02*
X1273724D01*
G01X1272798Y1104654D02*
X1272795Y1104652D01*
G01X1272801Y1104655D02*
X1272798Y1104654D01*
G01X1272804Y1104656D02*
X1272801Y1104655D01*
G01X1272808Y1104656D02*
X1272804D01*
G01X1272811Y1104657D02*
X1272808Y1104656D01*
G01X1272815Y1104657D02*
X1272811D01*
G01X1273737Y1106607D02*
X1273741Y1106608D01*
G01X1273734Y1106606D02*
X1273737Y1106607D01*
G01X1273731Y1106604D02*
X1273734Y1106606D01*
G01X1273728Y1106604D02*
X1273731D01*
G01X1273724Y1106603D02*
X1273728Y1106604D01*
G01X1273720Y1106603D02*
X1273724D01*
G01X1272798Y1107803D02*
X1272795Y1107802D01*
G01X1272801Y1107804D02*
X1272798Y1107803D01*
G01X1272804Y1107806D02*
X1272801Y1107804D01*
G01X1272808Y1107806D02*
X1272804D01*
G01X1272811Y1107807D02*
X1272808Y1107806D01*
G01X1272815Y1107807D02*
X1272811D01*
G01X1273737Y1109756D02*
X1273741Y1109758D01*
G01X1273734Y1109755D02*
X1273737Y1109756D01*
G01X1273731Y1109754D02*
X1273734Y1109755D01*
G01X1273728Y1109753D02*
X1273731Y1109754D01*
G01X1273724Y1109753D02*
X1273728D01*
G01X1273720D02*
X1273724D01*
G01X1272798Y1110953D02*
X1272795Y1110951D01*
G01X1272801Y1110954D02*
X1272798Y1110953D01*
G01X1272804Y1110955D02*
X1272801Y1110954D01*
G01X1272808Y1110956D02*
X1272804Y1110955D01*
G01X1272811Y1110956D02*
X1272808D01*
G01X1272815D02*
X1272811D01*
G01X1273737Y1112906D02*
X1273741Y1112907D01*
G01X1273734Y1112905D02*
X1273737Y1112906D01*
G01X1273731Y1112904D02*
X1273734Y1112905D01*
G01X1273728Y1112903D02*
X1273731Y1112904D01*
G01X1273724Y1112902D02*
X1273728Y1112903D01*
G01X1273720Y1112902D02*
X1273724D01*
G01X1272798Y1114102D02*
X1272795Y1114101D01*
G01X1272801Y1114104D02*
X1272798Y1114102D01*
G01X1272804Y1114105D02*
X1272801Y1114104D01*
G01X1272808Y1114105D02*
X1272804D01*
G01X1272811Y1114106D02*
X1272808Y1114105D01*
G01X1272815Y1114106D02*
X1272811D01*
G01X1273737Y1116056D02*
X1273741Y1116057D01*
G01X1273734Y1116054D02*
X1273737Y1116056D01*
G01X1273731Y1116053D02*
X1273734Y1116054D01*
G01X1273728Y1116052D02*
X1273731Y1116053D01*
G01X1273724Y1116052D02*
X1273728D01*
G01X1273720D02*
X1273724D01*
G01X1272798Y1117252D02*
X1272795Y1117250D01*
G01X1272801Y1117253D02*
X1272798Y1117252D01*
G01X1272804Y1117254D02*
X1272801Y1117253D01*
G01X1272808Y1117255D02*
X1272804Y1117254D01*
G01X1272811Y1117256D02*
X1272808Y1117255D01*
G01X1272815Y1117256D02*
X1272811D01*
G01X1272798Y1120402D02*
X1272795Y1120400D01*
G01X1272801Y1120403D02*
X1272798Y1120402D01*
G01X1272804Y1120404D02*
X1272801Y1120403D01*
G01X1272808Y1120404D02*
X1272804D01*
G01X1272811Y1120405D02*
X1272808Y1120404D01*
G01X1272815Y1120405D02*
X1272811D01*
G01X1273737Y1122355D02*
X1273741Y1122356D01*
G01X1273734Y1122354D02*
X1273737Y1122355D01*
G01X1273731Y1122352D02*
X1273734Y1122354D01*
G01X1273728Y1122352D02*
X1273731D01*
G01X1273724Y1122351D02*
X1273728Y1122352D01*
G01X1273720Y1122351D02*
X1273724D01*
G01X1272798Y1123551D02*
X1272795Y1123550D01*
G01X1272801Y1123552D02*
X1272798Y1123551D01*
G01X1272804Y1123554D02*
X1272801Y1123552D01*
G01X1272808Y1123554D02*
X1272804D01*
G01X1272811Y1123555D02*
X1272808Y1123554D01*
G01X1272815Y1123555D02*
X1272811D01*
G01X1273750Y1104644D02*
X1273754Y1104639D01*
G01X1273746Y1104648D02*
X1273750Y1104644D01*
G01X1273740Y1104652D02*
X1273746Y1104648D01*
G01X1273734Y1104655D02*
X1273740Y1104652D01*
G01X1273727Y1104657D02*
X1273734Y1104655D01*
G01X1273720Y1104657D02*
X1273727D01*
G01X1273750Y1107794D02*
X1273754Y1107789D01*
G01X1273746Y1107798D02*
X1273750Y1107794D01*
G01X1273740Y1107802D02*
X1273746Y1107798D01*
G01X1273734Y1107804D02*
X1273740Y1107802D01*
G01X1273727Y1107806D02*
X1273734Y1107804D01*
G01X1273720Y1107807D02*
X1273727Y1107806D01*
G01X1273750Y1110943D02*
X1273754Y1110938D01*
G01X1273746Y1110948D02*
X1273750Y1110943D01*
G01X1273740Y1110952D02*
X1273746Y1110948D01*
G01X1273734Y1110954D02*
X1273740Y1110952D01*
G01X1273727Y1110956D02*
X1273734Y1110954D01*
G01X1273720Y1110956D02*
X1273727D01*
G01X1273750Y1114093D02*
X1273754Y1114088D01*
G01X1273746Y1114097D02*
X1273750Y1114093D01*
G01X1273740Y1114101D02*
X1273746Y1114097D01*
G01X1273734Y1114104D02*
X1273740Y1114101D01*
G01X1273727Y1114106D02*
X1273734Y1114104D01*
G01X1273720Y1114106D02*
X1273727D01*
G01X1273750Y1117243D02*
X1273754Y1117237D01*
G01X1273746Y1117247D02*
X1273750Y1117243D01*
G01X1273740Y1117251D02*
X1273746Y1117247D01*
G01X1273734Y1117253D02*
X1273740Y1117251D01*
G01X1273727Y1117255D02*
X1273734Y1117253D01*
G01X1273720Y1117256D02*
X1273727Y1117255D01*
G01X1273750Y1120392D02*
X1273754Y1120387D01*
G01X1273746Y1120396D02*
X1273750Y1120392D01*
G01X1273740Y1120400D02*
X1273746Y1120396D01*
G01X1273734Y1120403D02*
X1273740Y1120400D01*
G01X1273727Y1120405D02*
X1273734Y1120403D01*
G01X1273720Y1120405D02*
X1273727D01*
G01X1273750Y1123542D02*
X1273754Y1123537D01*
G01X1273746Y1123546D02*
X1273750Y1123542D01*
G01X1273740Y1123550D02*
X1273746Y1123546D01*
G01X1273734Y1123552D02*
X1273740Y1123550D01*
G01X1273727Y1123554D02*
X1273734Y1123552D01*
G01X1273720Y1123555D02*
X1273727Y1123554D01*
G01X1272776Y1103483D02*
Y1103491D01*
G01X1272779Y1103476D02*
X1272776Y1103483D01*
G01X1272782Y1103470D02*
X1272779Y1103476D01*
G01X1272787Y1103464D02*
X1272782Y1103470D01*
G01X1272793Y1103459D02*
X1272787Y1103464D01*
G01X1272800Y1103456D02*
X1272793Y1103459D01*
G01X1272807Y1103454D02*
X1272800Y1103456D01*
G01X1272815Y1103454D02*
X1272807D01*
G01X1272776Y1106633D02*
Y1106640D01*
G01X1272779Y1106626D02*
X1272776Y1106633D01*
G01X1272782Y1106620D02*
X1272779Y1106626D01*
G01X1272787Y1106614D02*
X1272782Y1106620D01*
G01X1272793Y1106609D02*
X1272787Y1106614D01*
G01X1272800Y1106606D02*
X1272793Y1106609D01*
G01X1272807Y1106604D02*
X1272800Y1106606D01*
G01X1272815Y1106603D02*
X1272807Y1106604D01*
G01X1272776Y1109782D02*
Y1109790D01*
G01X1272779Y1109776D02*
X1272776Y1109782D01*
G01X1272782Y1109769D02*
X1272779Y1109776D01*
G01X1272787Y1109763D02*
X1272782Y1109769D01*
G01X1272793Y1109759D02*
X1272787Y1109763D01*
G01X1272800Y1109756D02*
X1272793Y1109759D01*
G01X1272807Y1109754D02*
X1272800Y1109756D01*
G01X1272815Y1109753D02*
X1272807Y1109754D01*
G01X1272776Y1112932D02*
Y1112939D01*
G01X1272779Y1112925D02*
X1272776Y1112932D01*
G01X1272782Y1112919D02*
X1272779Y1112925D01*
G01X1272787Y1112913D02*
X1272782Y1112919D01*
G01X1272793Y1112908D02*
X1272787Y1112913D01*
G01X1272800Y1112905D02*
X1272793Y1112908D01*
G01X1272807Y1112903D02*
X1272800Y1112905D01*
G01X1272815Y1112902D02*
X1272807Y1112903D01*
G01X1272776Y1116081D02*
Y1116089D01*
G01X1272779Y1116075D02*
X1272776Y1116081D01*
G01X1272782Y1116069D02*
X1272779Y1116075D01*
G01X1272787Y1116063D02*
X1272782Y1116069D01*
G01X1272793Y1116058D02*
X1272787Y1116063D01*
G01X1272800Y1116055D02*
X1272793Y1116058D01*
G01X1272807Y1116053D02*
X1272800Y1116055D01*
G01X1272815Y1116052D02*
X1272807Y1116053D01*
G01X1272776Y1119231D02*
Y1119239D01*
G01X1272779Y1119224D02*
X1272776Y1119231D01*
G01X1272782Y1119218D02*
X1272779Y1119224D01*
G01X1272787Y1119212D02*
X1272782Y1119218D01*
G01X1272793Y1119207D02*
X1272787Y1119212D01*
G01X1272800Y1119204D02*
X1272793Y1119207D01*
G01X1272807Y1119202D02*
X1272800Y1119204D01*
G01X1272815Y1119202D02*
X1272807D01*
G01X1272776Y1122381D02*
Y1122388D01*
G01X1272779Y1122374D02*
X1272776Y1122381D01*
G01X1272782Y1122368D02*
X1272779Y1122374D01*
G01X1272787Y1122362D02*
X1272782Y1122368D01*
G01X1272793Y1122357D02*
X1272787Y1122362D01*
G01X1272800Y1122354D02*
X1272793Y1122357D01*
G01X1272807Y1122352D02*
X1272800Y1122354D01*
G01X1272815Y1122351D02*
X1272807Y1122352D01*
G01X1273730Y1104644D02*
X1273739Y1104640D01*
G01X1273719Y1104646D02*
X1273730Y1104644D01*
G01Y1107794D02*
X1273739Y1107790D01*
G01X1273719Y1107795D02*
X1273730Y1107794D01*
G01Y1110944D02*
X1273739Y1110939D01*
G01X1273719Y1110945D02*
X1273730Y1110944D01*
G01Y1114093D02*
X1273739Y1114089D01*
G01X1273719Y1114094D02*
X1273730Y1114093D01*
G01X1273752Y1110927D02*
X1273745Y1110935D01*
G01X1273757Y1110917D02*
X1273752Y1110927D01*
G01X1273759Y1110906D02*
X1273757Y1110917D01*
G01X1273752Y1104628D02*
X1273745Y1104636D01*
G01X1273757Y1104617D02*
X1273752Y1104628D01*
G01X1273759Y1104606D02*
X1273757Y1104617D01*
G01X1273752Y1107777D02*
X1273745Y1107786D01*
G01X1273757Y1107767D02*
X1273752Y1107777D01*
G01X1273759Y1107756D02*
X1273757Y1107767D01*
G01X1273752Y1114076D02*
X1273745Y1114085D01*
G01X1273757Y1114066D02*
X1273752Y1114076D01*
G01X1273759Y1114055D02*
X1273757Y1114066D01*
G01X1273752Y1117226D02*
X1273745Y1117235D01*
G01X1273757Y1117216D02*
X1273752Y1117226D01*
G01X1273759Y1117205D02*
X1273757Y1117216D01*
G01X1273752Y1120376D02*
X1273745Y1120384D01*
G01X1273757Y1120365D02*
X1273752Y1120376D01*
G01X1273759Y1120354D02*
X1273757Y1120365D01*
G01X1273752Y1123525D02*
X1273745Y1123534D01*
G01X1273757Y1123515D02*
X1273752Y1123525D01*
G01X1273759Y1123504D02*
X1273757Y1123515D01*
G01X1273730Y1117243D02*
X1273739Y1117239D01*
G01X1273719Y1117244D02*
X1273730Y1117243D01*
G01Y1120393D02*
X1273739Y1120388D01*
G01X1273719Y1120394D02*
X1273730Y1120393D01*
G01Y1123542D02*
X1273739Y1123538D01*
G01X1273719Y1123543D02*
X1273730Y1123542D01*
G01X1272776Y1106644D02*
Y1106640D01*
G01X1272777Y1106638D02*
X1272776Y1106644D01*
G01X1272789Y1106622D02*
X1272777Y1106638D01*
G01X1272814Y1106614D02*
X1272789Y1106622D01*
G01X1272776Y1109794D02*
Y1109790D01*
G01X1272777Y1109787D02*
X1272776Y1109794D01*
G01X1272789Y1109772D02*
X1272777Y1109787D01*
G01X1272813Y1109764D02*
X1272789Y1109772D01*
G01X1272776Y1116093D02*
Y1116089D01*
G01X1272777Y1116087D02*
X1272776Y1116093D01*
G01X1272789Y1116071D02*
X1272777Y1116087D01*
G01X1272813Y1116063D02*
X1272789Y1116071D01*
G01X1272776Y1119243D02*
Y1119239D01*
G01X1272777Y1119236D02*
X1272776Y1119243D01*
G01X1272789Y1119221D02*
X1272777Y1119236D01*
G01X1272813Y1119213D02*
X1272789Y1119221D01*
G01X1272776Y1103494D02*
Y1103491D01*
G01X1272777Y1103488D02*
X1272776Y1103494D01*
G01X1272789Y1103473D02*
X1272777Y1103488D01*
G01X1272813Y1103465D02*
X1272789Y1103473D01*
G01X1272776Y1122392D02*
Y1122388D01*
G01X1272777Y1122386D02*
X1272776Y1122392D01*
G01X1272789Y1122370D02*
X1272777Y1122386D01*
G01X1272813Y1122362D02*
X1272789Y1122370D01*
G01X1272776Y1112943D02*
Y1112939D01*
G01X1272777Y1112938D02*
X1272776Y1112943D01*
G01X1272787Y1112923D02*
X1272777Y1112938D01*
G01X1272810Y1112914D02*
X1272787Y1112923D01*
G01X1273728Y1110944D02*
X1273719Y1110945D01*
G01X1273737Y1110941D02*
X1273728Y1110944D01*
G01X1273745Y1110935D02*
X1273737Y1110941D01*
G01X1273728Y1104644D02*
X1273719Y1104646D01*
G01X1273737Y1104641D02*
X1273728Y1104644D01*
G01X1273745Y1104636D02*
X1273737Y1104641D01*
G01X1273728Y1107794D02*
X1273719Y1107795D01*
G01X1273737Y1107791D02*
X1273728Y1107794D01*
G01X1273745Y1107786D02*
X1273737Y1107791D01*
G01X1273728Y1114093D02*
X1273719Y1114094D01*
G01X1273737Y1114090D02*
X1273728Y1114093D01*
G01X1273745Y1114085D02*
X1273737Y1114090D01*
G01X1273728Y1117243D02*
X1273719Y1117244D01*
G01X1273737Y1117240D02*
X1273728Y1117243D01*
G01X1273745Y1117235D02*
X1273737Y1117240D01*
G01X1273728Y1120393D02*
X1273719Y1120394D01*
G01X1273737Y1120389D02*
X1273728Y1120393D01*
G01X1273745Y1120384D02*
X1273737Y1120389D01*
G01X1273728Y1123542D02*
X1273719Y1123543D01*
G01X1273737Y1123539D02*
X1273728Y1123542D01*
G01X1273745Y1123534D02*
X1273737Y1123539D01*
G01X1272815Y1103460D02*
Y1103454D01*
G01X1272814Y1103463D02*
X1272815Y1103460D01*
G01X1272813Y1103465D02*
X1272814Y1103463D01*
G01X1272815Y1106609D02*
Y1106603D01*
G01X1272814Y1106613D02*
X1272815Y1106609D01*
G01X1272813Y1106614D02*
X1272814Y1106613D01*
G01X1272815Y1109759D02*
Y1109753D01*
G01X1272814Y1109763D02*
X1272815Y1109759D01*
G01X1272813Y1109764D02*
X1272814Y1109763D01*
G01X1272815Y1112909D02*
Y1112902D01*
G01X1272814Y1112912D02*
X1272815Y1112909D01*
G01X1272813Y1112913D02*
X1272814Y1112912D01*
G01X1272815Y1116058D02*
Y1116052D01*
G01X1272814Y1116062D02*
X1272815Y1116058D01*
G01X1272813Y1116063D02*
X1272814Y1116062D01*
G01X1272815Y1119208D02*
Y1119202D01*
G01X1272814Y1119211D02*
X1272815Y1119208D01*
G01X1272813Y1119213D02*
X1272814Y1119211D01*
G01X1272815Y1122357D02*
Y1122351D01*
G01X1272814Y1122361D02*
X1272815Y1122357D01*
G01X1272813Y1122362D02*
X1272814Y1122361D01*
G01X1272798Y1106617D02*
X1272813Y1106614D01*
G01X1272787Y1106624D02*
X1272798Y1106617D01*
G01X1272775Y1106643D02*
X1272787Y1106624D01*
G01X1272798Y1116066D02*
X1272813Y1116063D01*
G01X1272787Y1116073D02*
X1272798Y1116066D01*
G01X1272775Y1116091D02*
X1272787Y1116073D01*
G01X1272798Y1109767D02*
X1272813Y1109764D01*
G01X1272786Y1109774D02*
X1272798Y1109767D01*
G01X1272774Y1109794D02*
X1272786Y1109774D01*
G01X1272798Y1119215D02*
X1272813Y1119213D01*
G01X1272786Y1119223D02*
X1272798Y1119215D01*
G01X1272774Y1119243D02*
X1272786Y1119223D01*
G01X1273760Y1103498D02*
Y1103491D01*
G01X1273759Y1103503D02*
X1273760Y1103498D01*
G01X1273758Y1103504D02*
X1273759Y1103503D01*
G01X1273760Y1106648D02*
Y1106640D01*
G01X1273759Y1106652D02*
X1273760Y1106648D01*
G01X1273758Y1106654D02*
X1273759Y1106652D01*
G01X1273760Y1109797D02*
Y1109790D01*
G01X1273759Y1109802D02*
X1273760Y1109797D01*
G01X1273758Y1109803D02*
X1273759Y1109802D01*
G01X1273760Y1112947D02*
Y1112939D01*
G01X1273759Y1112952D02*
X1273760Y1112947D01*
G01X1273758Y1112953D02*
X1273759Y1112952D01*
G01X1273760Y1116096D02*
Y1116089D01*
G01X1273759Y1116101D02*
X1273760Y1116096D01*
G01X1273758Y1116102D02*
X1273759Y1116101D01*
G01X1273760Y1119246D02*
Y1119239D01*
G01X1273759Y1119251D02*
X1273760Y1119246D01*
G01X1273758Y1119252D02*
X1273759Y1119251D01*
G01X1273760Y1122396D02*
Y1122388D01*
G01X1273759Y1122400D02*
X1273760Y1122396D01*
G01X1273758Y1122402D02*
X1273759Y1122400D01*
G01X1272798Y1122365D02*
X1272813Y1122362D01*
G01X1272785Y1122373D02*
X1272798Y1122365D01*
G01X1272774Y1122393D02*
X1272785Y1122373D01*
G01X1272798Y1103468D02*
X1272813Y1103465D01*
G01X1272785Y1103476D02*
X1272798Y1103468D01*
G01X1272774Y1103496D02*
X1272785Y1103476D01*
G01X1273759Y1104627D02*
X1273760Y1104620D01*
G01X1273757Y1104633D02*
X1273759Y1104627D01*
G01X1273754Y1104639D02*
X1273757Y1104633D01*
G01X1273759Y1107776D02*
X1273760Y1107770D01*
G01X1273757Y1107783D02*
X1273759Y1107776D01*
G01X1273754Y1107789D02*
X1273757Y1107783D01*
G01X1273759Y1110926D02*
X1273760Y1110919D01*
G01X1273757Y1110932D02*
X1273759Y1110926D01*
G01X1273754Y1110938D02*
X1273757Y1110932D01*
G01X1273759Y1114076D02*
X1273760Y1114069D01*
G01X1273757Y1114082D02*
X1273759Y1114076D01*
G01X1273754Y1114088D02*
X1273757Y1114082D01*
G01X1273759Y1117225D02*
X1273760Y1117219D01*
G01X1273757Y1117231D02*
X1273759Y1117225D01*
G01X1273754Y1117237D02*
X1273757Y1117231D01*
G01X1273759Y1120375D02*
X1273760Y1120368D01*
G01X1273757Y1120381D02*
X1273759Y1120375D01*
G01X1273754Y1120387D02*
X1273757Y1120381D01*
G01X1273759Y1123524D02*
X1273760Y1123518D01*
G01X1273757Y1123531D02*
X1273759Y1123524D01*
G01X1273754Y1123537D02*
X1273757Y1123531D01*
G01X1273721Y1103459D02*
Y1103454D01*
G01X1273720Y1103463D02*
X1273721Y1103459D01*
G01X1273719Y1103465D02*
X1273720Y1103463D01*
G01X1273721Y1106609D02*
Y1106603D01*
G01X1273720Y1106613D02*
X1273721Y1106609D01*
G01X1273719Y1106614D02*
X1273720Y1106613D01*
G01X1273721Y1109759D02*
Y1109753D01*
G01X1273720Y1109763D02*
X1273721Y1109759D01*
G01X1273719Y1109764D02*
X1273720Y1109763D01*
G01X1273721Y1112908D02*
Y1112902D01*
G01X1273720Y1112912D02*
X1273721Y1112908D01*
G01X1273719Y1112913D02*
X1273720Y1112912D01*
G01X1273721Y1116058D02*
Y1116052D01*
G01X1273720Y1116062D02*
X1273721Y1116058D01*
G01X1273719Y1116063D02*
X1273720Y1116062D01*
G01X1273721Y1122357D02*
Y1122351D01*
G01X1273720Y1122361D02*
X1273721Y1122357D01*
G01X1273719Y1122362D02*
X1273720Y1122361D01*
G01X1272793Y1112919D02*
X1272813Y1112913D01*
G01X1272780Y1112931D02*
X1272793Y1112919D01*
G01X1272773Y1112949D02*
X1272780Y1112931D01*
G01X1273719Y1119213D02*
X1273722Y1119202D01*
G01X1272662Y1122402D02*
X1272774Y1122393D01*
G01X1272773Y1112949D02*
X1272662Y1112953D01*
G01X1272773Y1106650D02*
X1272662Y1106654D01*
G01X1272773Y1116099D02*
X1272662Y1116102D01*
G01X1274213Y1125709D02*
X1270866D01*
G01X1273720Y1123740D02*
X1272815D01*
G01X1273760Y1123701D02*
X1272776D01*
G01X1273719Y1123543D02*
X1267835D01*
G01Y1123504D02*
X1273759D01*
G01X1273758Y1122402D02*
X1267835D01*
G01X1273719Y1122362D02*
X1267835D01*
G01X1272776Y1122205D02*
X1273760D01*
G01X1272815Y1122165D02*
X1273720D01*
G01Y1120591D02*
X1272815D01*
G01X1273760Y1120551D02*
X1272776D01*
G01X1273719Y1120394D02*
X1267835D01*
G01Y1120354D02*
X1273759D01*
G01X1273758Y1119252D02*
X1267835D01*
G01X1273719Y1119213D02*
X1267835D01*
G01X1272776Y1119055D02*
X1273760D01*
G01X1272815Y1119016D02*
X1273720D01*
G01Y1117441D02*
X1272815D01*
G01X1273760Y1117402D02*
X1272776D01*
G01X1273719Y1117244D02*
X1267835D01*
G01Y1117205D02*
X1273759D01*
G01X1272028Y1116102D02*
X1271594D01*
G01X1273758D02*
X1267835D01*
G01X1273719Y1116063D02*
X1267835D01*
G01X1272776Y1115906D02*
X1273760D01*
G01X1272815Y1115866D02*
X1273720D01*
G01Y1114291D02*
X1272815D01*
G01X1273760Y1114252D02*
X1272776D01*
G01X1273719Y1114094D02*
X1267835D01*
G01Y1114055D02*
X1273759D01*
G01X1272028Y1112953D02*
X1271594D01*
G01X1273758D02*
X1267835D01*
G01X1273719Y1112913D02*
X1267835D01*
G01X1272776Y1112756D02*
X1273760D01*
G01X1272815Y1112717D02*
X1273720D01*
G01Y1111142D02*
X1272815D01*
G01X1273760Y1111102D02*
X1272776D01*
G01X1273719Y1110945D02*
X1267835D01*
G01Y1110906D02*
X1273759D01*
G01X1273758Y1109803D02*
X1267835D01*
G01X1273719Y1109764D02*
X1267835D01*
G01X1272776Y1109606D02*
X1273760D01*
G01X1272815Y1109567D02*
X1273720D01*
G01Y1107992D02*
X1272815D01*
G01X1273760Y1107953D02*
X1272776D01*
G01X1273719Y1107795D02*
X1267835D01*
G01Y1107756D02*
X1273759D01*
G01X1272028Y1106654D02*
X1271594D01*
G01X1273758D02*
X1267835D01*
G01X1273719Y1106614D02*
X1267835D01*
G01X1272776Y1106457D02*
X1273760D01*
G01X1272815Y1106417D02*
X1273720D01*
G01Y1104843D02*
X1272815D01*
G01X1273760Y1104803D02*
X1272776D01*
G01X1273719Y1104646D02*
X1267835D01*
G01Y1104606D02*
X1273759D01*
G01X1273758Y1103504D02*
X1267835D01*
G01X1273719Y1103465D02*
X1267835D01*
G01X1272776Y1103307D02*
X1273760D01*
G01X1272815Y1103268D02*
X1273720D01*
G01X1274213Y1101299D02*
X1270866D01*
G01X1273759Y1104609D02*
X1273760Y1104620D01*
G01X1273759Y1107758D02*
X1273760Y1107769D01*
G01X1273759Y1110908D02*
X1273760Y1110919D01*
G01X1273759Y1114057D02*
X1273760Y1114069D01*
G01X1273759Y1117207D02*
X1273760Y1117218D01*
G01X1273759Y1120357D02*
X1273760Y1120368D01*
G01X1273759Y1123506D02*
X1273760Y1123517D01*
G01X1274213Y1204744D02*
Y1125709D01*
G01X1273760Y1122205D02*
Y1123701D01*
G01Y1119055D02*
Y1120551D01*
G01Y1115906D02*
Y1117402D01*
G01Y1112756D02*
Y1114252D01*
G01Y1109606D02*
Y1111102D01*
G01Y1106457D02*
Y1107953D01*
G01Y1103307D02*
Y1104803D01*
G01X1273720Y1106603D02*
Y1106456D01*
G01Y1103454D02*
Y1103307D01*
G01Y1104804D02*
Y1104657D01*
G01Y1109753D02*
Y1109606D01*
G01Y1111103D02*
Y1110956D01*
G01Y1107953D02*
Y1107807D01*
G01Y1116052D02*
Y1115905D01*
G01Y1112902D02*
Y1112756D01*
G01Y1114252D02*
Y1114106D01*
G01Y1119202D02*
Y1119055D01*
G01Y1120552D02*
Y1120405D01*
G01Y1117402D02*
Y1117256D01*
G01Y1122351D02*
Y1122204D01*
G01Y1123701D02*
Y1123555D01*
G01X1272815Y1122204D02*
Y1122351D01*
G01Y1123555D02*
Y1123702D01*
G01Y1119054D02*
Y1119202D01*
G01Y1120405D02*
Y1120552D01*
G01Y1117256D02*
Y1117402D01*
G01Y1115905D02*
Y1116052D01*
G01Y1112755D02*
Y1112902D01*
G01Y1114106D02*
Y1114253D01*
G01Y1109606D02*
Y1109753D01*
G01Y1110956D02*
Y1111103D01*
G01Y1107807D02*
Y1107954D01*
G01Y1106456D02*
Y1106603D01*
G01Y1103306D02*
Y1103454D01*
G01Y1104657D02*
Y1104804D01*
G01X1272776Y1104803D02*
Y1103307D01*
G01Y1111102D02*
Y1109606D01*
G01Y1107953D02*
Y1106457D01*
G01Y1114252D02*
Y1112756D01*
G01Y1120551D02*
Y1119055D01*
G01Y1117402D02*
Y1115906D01*
G01Y1123701D02*
Y1122205D01*
G01X1271594Y1107795D02*
Y1106614D01*
G01Y1104646D02*
Y1103465D01*
G01Y1110945D02*
Y1109764D01*
G01Y1117244D02*
Y1116063D01*
G01Y1114094D02*
Y1112913D01*
G01Y1120394D02*
Y1119213D01*
G01Y1123543D02*
Y1122362D01*
G01X1271260Y1125709D02*
Y1101299D01*
G01X1270866D02*
Y1125709D01*
G01X1267835Y1122362D02*
Y1123543D01*
G01Y1119213D02*
Y1120394D01*
G01Y1116063D02*
Y1117244D01*
G01Y1112913D02*
Y1114094D01*
G01Y1109764D02*
Y1110945D01*
G01Y1106614D02*
Y1107795D01*
G01Y1103465D02*
Y1104646D01*
G01X1273760Y1122388D02*
X1273759Y1122399D01*
G01X1273760Y1119239D02*
X1273759Y1119250D01*
G01X1273760Y1116089D02*
X1273759Y1116100D01*
G01X1273760Y1112939D02*
X1273759Y1112950D01*
G01X1273760Y1109790D02*
X1273759Y1109801D01*
G01X1273760Y1106640D02*
X1273759Y1106651D01*
G01X1273760Y1103491D02*
X1273759Y1103502D01*
G01X1278346Y1222776D02*
G03X1277756Y1222185I1J-591D01*
G01X1280512Y1221004D02*
G03Y1219035I0J-985D01*
G01X1272835Y1223563D02*
G03X1270866Y1221594I0J-1969D01*
G01X1279134Y1213091D02*
G03X1277953Y1211909I0J-1181D01*
G01X1283583Y1207815D02*
G03I-1890J0D01*
G01X1284055D02*
G03I-2362J0D01*
G01X1280512Y1208406D02*
X1278202Y1212635D01*
G01X1275984Y1201004D02*
X1277165Y1199823D01*
G01X1270866Y1205846D02*
X1274213Y1202500D01*
G01X1290551Y1223563D02*
X1272835D01*
G01X1285039Y1222776D02*
X1278346D01*
G01X1282874Y1221004D02*
X1280512D01*
G01Y1219035D02*
X1282874D01*
G01X1285630Y1217657D02*
X1277756D01*
G01Y1216083D02*
X1285630D01*
G01X1292520Y1213130D02*
X1270866D01*
G01X1279134Y1213091D02*
X1284252D01*
G01X1280512Y1208406D02*
X1282874D01*
G01X1280512Y1206713D02*
X1282874D01*
G01X1274213Y1204744D02*
X1288583D01*
G01X1274213Y1203366D02*
X1277953D01*
G01X1274213Y1202500D02*
X1289173D01*
G01X1275984Y1201004D02*
X1283858D01*
G01X1277165Y1199823D02*
X1282677D01*
G01X1280512Y1206713D02*
Y1208406D01*
G01X1277953Y1203366D02*
Y1211909D01*
G01X1277756Y1216083D02*
Y1222185D01*
G01X1270866Y1221594D02*
Y1205846D01*
G01X1279208Y1204744D02*
X1280512Y1206713D01*
G01X1284965Y1284397D02*
G03X1318775I16905J-13531D01*
G01X1242913Y1274016D02*
G03X1241732I-590J0D01*
G01X1239764D02*
G03X1238583I-590J0D01*
G01X1242913D02*
G03X1241732I-590J0D01*
G01X1239764D02*
G03X1238583I-590J0D01*
G01X1284965Y1284397D02*
G03X1318776I16906J-13531D01*
G01X1237795Y1275197D02*
X1243701D01*
G01Y1275000D02*
X1237795D01*
G01X1242913Y1274016D02*
X1243701D01*
G01X1242913D02*
X1243701D01*
G01X1239764D02*
X1241732D01*
G01X1239764D02*
X1241732D01*
G01X1237795D02*
X1238583D01*
G01X1237795D02*
X1238583D01*
G01X1243701D02*
Y1280315D01*
G01Y1274016D02*
Y1280315D01*
G01X1237795Y1274016D02*
Y1280315D01*
G01D02*
Y1274016D01*
G01X1241732Y1280315D02*
G03X1242913I591J0D01*
G01X1238583D02*
G03X1239764I591J0D01*
G01X1241732D02*
G03X1242913I591J0D01*
G01X1238583D02*
G03X1239764I591J0D01*
G01X1238583D02*
X1237795D01*
G01X1238583D02*
X1237795D01*
G01X1241732D02*
X1239764D01*
G01X1241732D02*
X1239764D01*
G01X1243701D02*
X1242913D01*
G01X1243701D02*
X1242913D01*
G01X1243701Y1279331D02*
X1237795D01*
G01Y1279134D02*
X1243701D01*
G01X1315748Y-7874D02*
G03Y0I0J3937D01*
G01X1293602Y20472D02*
G03X1302264I4331J0D01*
G01X1315748Y-7874D02*
G03Y0I0J3937D01*
G01X1302264Y20473D02*
G03I-4331J0D01*
G01Y20472D02*
G03X1293602I-4331J0D01*
G01X1285039Y138720D02*
G03X1285630Y139311I0J591D01*
G01X1282874Y140492D02*
G03Y142461I0J984D01*
G01X1284252Y148406D02*
G03X1285433Y149587I0J1181D01*
G01X1290551Y137933D02*
G03X1292520Y139902I0J1969D01*
G01X1284178Y156752D02*
X1282874Y154783D01*
G01X1292520Y139902D02*
Y155650D01*
G01X1289173Y296988D02*
Y158996D01*
G01X1288583Y299232D02*
Y156752D01*
G01X1285630Y145413D02*
Y139311D01*
G01X1285433Y158130D02*
Y149587D01*
G01X1283858Y196949D02*
Y160492D01*
G01X1282874Y154783D02*
Y153091D01*
G01X1282677Y198130D02*
Y161673D01*
G01X1282874Y153091D02*
X1285184Y148861D01*
G01X1289173Y158996D02*
X1292520Y155650D01*
G01X1282677Y161673D02*
X1283858Y160492D01*
G01X1285433Y158130D02*
X1288583D01*
G01X1287172Y166173D02*
X1287183Y166157D01*
G01X1287148Y166181D02*
X1287172Y166173D01*
G01Y171173D02*
X1287183Y171157D01*
G01X1287148Y171181D02*
X1287172Y171173D01*
G01Y176173D02*
X1287183Y176157D01*
G01X1287148Y176181D02*
X1287172Y176173D01*
G01Y181173D02*
X1287183Y181157D01*
G01X1287148Y181181D02*
X1287172Y181173D01*
G01Y186173D02*
X1287183Y186157D01*
G01X1287148Y186181D02*
X1287172Y186173D01*
G01Y191173D02*
X1287183Y191157D01*
G01X1287148Y191181D02*
X1287172Y191173D01*
G01Y196173D02*
X1287183Y196157D01*
G01X1287148Y196181D02*
X1287172Y196173D01*
G01X1287185Y166148D02*
Y166156D01*
G01X1287186Y166144D02*
X1287185Y166148D01*
G01X1287187Y166142D02*
X1287186Y166144D01*
G01X1287185Y171148D02*
Y171156D01*
G01X1287186Y171144D02*
X1287185Y171148D01*
G01X1287187Y171142D02*
X1287186Y171144D01*
G01X1287185Y176148D02*
Y176156D01*
G01X1287186Y176144D02*
X1287185Y176148D01*
G01X1287187Y176142D02*
X1287186Y176144D01*
G01X1287185Y181148D02*
Y181156D01*
G01X1287186Y181144D02*
X1287185Y181148D01*
G01X1287187Y181142D02*
X1287186Y181144D01*
G01X1287185Y186148D02*
Y186156D01*
G01X1287186Y186144D02*
X1287185Y186148D01*
G01X1287187Y186142D02*
X1287186Y186144D01*
G01X1287185Y191148D02*
Y191156D01*
G01X1287186Y191144D02*
X1287185Y191148D01*
G01X1287187Y191142D02*
X1287186Y191144D01*
G01X1287185Y196148D02*
Y196156D01*
G01X1287186Y196144D02*
X1287185Y196148D01*
G01X1287187Y196142D02*
X1287186Y196144D01*
G01X1286201Y166189D02*
Y166198D01*
G01X1286202Y166183D02*
X1286201Y166189D01*
G01X1286202Y166181D02*
Y166183D01*
G01X1286201Y171189D02*
Y171198D01*
G01X1286202Y171183D02*
X1286201Y171189D01*
G01X1286202Y171181D02*
Y171183D01*
G01X1286201Y176189D02*
Y176198D01*
G01X1286202Y176183D02*
X1286201Y176189D01*
G01X1286202Y176181D02*
Y176183D01*
G01X1286201Y181189D02*
Y181198D01*
G01X1286202Y181183D02*
X1286201Y181189D01*
G01X1286202Y181181D02*
Y181183D01*
G01X1286201Y186189D02*
Y186198D01*
G01X1286202Y186183D02*
X1286201Y186189D01*
G01X1286202Y186181D02*
Y186183D01*
G01X1286201Y191189D02*
Y191198D01*
G01X1286202Y191183D02*
X1286201Y191189D01*
G01X1286202Y191181D02*
Y191183D01*
G01X1286201Y196189D02*
Y196198D01*
G01X1286202Y196183D02*
X1286201Y196189D01*
G01X1286202Y196181D02*
Y196183D01*
G01X1287177Y166325D02*
X1287185Y166299D01*
G01X1287167Y166352D02*
X1287177Y166325D01*
G01X1287156Y166378D02*
X1287167Y166352D01*
G01X1287177Y171325D02*
X1287185Y171299D01*
G01X1287167Y171352D02*
X1287177Y171325D01*
G01X1287156Y171378D02*
X1287167Y171352D01*
G01X1287177Y176325D02*
X1287185Y176299D01*
G01X1287167Y176352D02*
X1287177Y176325D01*
G01X1287156Y176378D02*
X1287167Y176352D01*
G01X1287177Y181325D02*
X1287185Y181299D01*
G01X1287167Y181352D02*
X1287177Y181325D01*
G01X1287156Y181378D02*
X1287167Y181352D01*
G01X1287177Y186325D02*
X1287185Y186299D01*
G01X1287167Y186352D02*
X1287177Y186325D01*
G01X1287156Y186378D02*
X1287167Y186352D01*
G01X1287177Y191325D02*
X1287185Y191299D01*
G01X1287167Y191352D02*
X1287177Y191325D01*
G01X1287156Y191378D02*
X1287167Y191352D01*
G01X1287177Y196325D02*
X1287185Y196299D01*
G01X1287167Y196352D02*
X1287177Y196325D01*
G01X1287156Y196378D02*
X1287167Y196352D01*
G01X1287168Y166176D02*
X1287148Y166181D01*
G01X1287182Y166162D02*
X1287168Y166176D01*
G01X1287187Y166142D02*
X1287182Y166162D01*
G01X1287168Y171176D02*
X1287148Y171181D01*
G01X1287182Y171162D02*
X1287168Y171176D01*
G01X1287187Y171142D02*
X1287182Y171162D01*
G01X1287168Y176176D02*
X1287148Y176181D01*
G01X1287182Y176162D02*
X1287168Y176176D01*
G01X1287187Y176142D02*
X1287182Y176162D01*
G01X1287168Y181176D02*
X1287148Y181181D01*
G01X1287182Y181162D02*
X1287168Y181176D01*
G01X1287187Y181142D02*
X1287182Y181162D01*
G01X1287168Y186176D02*
X1287148Y186181D01*
G01X1287182Y186162D02*
X1287168Y186176D01*
G01X1287187Y186142D02*
X1287182Y186162D01*
G01X1287168Y191176D02*
X1287148Y191181D01*
G01X1287182Y191162D02*
X1287168Y191176D01*
G01X1287187Y191142D02*
X1287182Y191162D01*
G01X1287168Y196176D02*
X1287148Y196181D01*
G01X1287182Y196162D02*
X1287168Y196176D01*
G01X1287187Y196142D02*
X1287182Y196162D01*
G01X1287152Y166279D02*
X1287156Y166378D01*
G01X1287146Y166207D02*
X1287152Y166279D01*
G01X1287148Y166181D02*
X1287146Y166207D01*
G01X1287152Y171279D02*
X1287156Y171378D01*
G01X1287146Y171207D02*
X1287152Y171279D01*
G01X1287148Y171181D02*
X1287146Y171207D01*
G01X1287152Y176279D02*
X1287156Y176378D01*
G01X1287146Y176207D02*
X1287152Y176279D01*
G01X1287148Y176181D02*
X1287146Y176207D01*
G01X1287152Y181279D02*
X1287156Y181378D01*
G01X1287146Y181207D02*
X1287152Y181279D01*
G01X1287148Y181181D02*
X1287146Y181207D01*
G01X1287152Y186279D02*
X1287156Y186378D01*
G01X1287146Y186207D02*
X1287152Y186279D01*
G01X1287148Y186181D02*
X1287146Y186207D01*
G01X1287152Y191279D02*
X1287156Y191378D01*
G01X1287146Y191207D02*
X1287152Y191279D01*
G01X1287148Y191181D02*
X1287146Y191207D01*
G01X1287152Y196279D02*
X1287156Y196378D01*
G01X1287146Y196207D02*
X1287152Y196279D01*
G01X1287148Y196181D02*
X1287146Y196207D01*
G01X1286202Y194802D02*
Y194803D01*
G01X1286201Y194796D02*
X1286202Y194802D01*
G01X1286201Y194787D02*
Y194796D01*
G01X1286202Y189802D02*
Y189803D01*
G01X1286201Y189796D02*
X1286202Y189802D01*
G01X1286201Y189787D02*
Y189796D01*
G01X1286202Y184802D02*
Y184803D01*
G01X1286201Y184796D02*
X1286202Y184802D01*
G01X1286201Y184787D02*
Y184796D01*
G01X1286202Y179802D02*
Y179803D01*
G01X1286201Y179796D02*
X1286202Y179802D01*
G01X1286201Y179787D02*
Y179796D01*
G01X1286202Y174802D02*
Y174803D01*
G01X1286201Y174796D02*
X1286202Y174802D01*
G01X1286201Y174787D02*
Y174796D01*
G01X1286202Y169802D02*
Y169803D01*
G01X1286201Y169796D02*
X1286202Y169802D01*
G01X1286201Y169787D02*
Y169796D01*
G01X1286202Y164802D02*
Y164803D01*
G01X1286201Y164796D02*
X1286202Y164802D01*
G01X1286201Y164787D02*
Y164796D01*
G01X1287185Y194796D02*
Y194787D01*
G01X1287186Y194802D02*
X1287185Y194796D01*
G01X1287188Y194803D02*
X1287186Y194802D01*
G01X1287185Y189796D02*
Y189787D01*
G01X1287186Y189802D02*
X1287185Y189796D01*
G01X1287188Y189803D02*
X1287186Y189802D01*
G01X1287185Y184796D02*
Y184787D01*
G01X1287186Y184802D02*
X1287185Y184796D01*
G01X1287188Y184803D02*
X1287186Y184802D01*
G01X1287185Y179796D02*
Y179787D01*
G01X1287186Y179802D02*
X1287185Y179796D01*
G01X1287188Y179803D02*
X1287186Y179802D01*
G01X1287185Y174796D02*
Y174787D01*
G01X1287186Y174802D02*
X1287185Y174796D01*
G01X1287188Y174803D02*
X1287186Y174802D01*
G01X1287185Y169796D02*
Y169787D01*
G01X1287186Y169802D02*
X1287185Y169796D01*
G01X1287188Y169803D02*
X1287186Y169802D01*
G01X1287185Y164796D02*
Y164787D01*
G01X1287186Y164802D02*
X1287185Y164796D01*
G01X1287188Y164803D02*
X1287186Y164802D01*
G01X1287185Y166155D02*
Y166164D01*
G01Y171155D02*
Y171164D01*
G01Y176155D02*
Y176164D01*
G01Y181155D02*
Y181164D01*
G01Y186155D02*
Y186164D01*
G01Y191155D02*
Y191164D01*
G01Y196155D02*
Y196164D01*
G01X1291535Y194803D02*
Y196181D01*
G01Y189803D02*
Y191181D01*
G01Y184803D02*
Y186181D01*
G01Y179803D02*
Y181181D01*
G01Y174803D02*
Y176181D01*
G01Y169803D02*
Y171181D01*
G01Y164803D02*
Y166181D01*
G01X1288366D02*
Y164803D01*
G01Y171181D02*
Y169803D01*
G01Y176181D02*
Y174803D01*
G01Y181181D02*
Y179803D01*
G01Y186181D02*
Y184803D01*
G01Y191181D02*
Y189803D01*
G01Y196181D02*
Y194803D01*
G01X1287795Y219035D02*
Y196949D01*
G01X1287185Y166156D02*
Y166299D01*
G01Y171156D02*
Y171299D01*
G01Y176156D02*
Y176299D01*
G01Y181156D02*
Y181299D01*
G01Y186156D02*
Y186299D01*
G01Y191156D02*
Y191299D01*
G01Y196156D02*
Y196299D01*
G01Y194311D02*
Y196673D01*
G01Y189311D02*
Y191673D01*
G01Y184311D02*
Y186673D01*
G01Y179311D02*
Y181673D01*
G01Y174311D02*
Y176673D01*
G01Y169311D02*
Y171673D01*
G01Y164311D02*
Y166673D01*
G01X1286614Y217854D02*
Y198130D01*
G01X1286201Y166673D02*
Y164311D01*
G01Y171673D02*
Y169311D01*
G01Y176673D02*
Y174311D01*
G01Y181673D02*
Y179311D01*
G01Y186673D02*
Y184311D01*
G01Y191673D02*
Y189311D01*
G01Y196673D02*
Y194311D01*
G01X1286614Y198130D02*
X1287795Y196949D01*
G01X1282677Y198130D02*
X1283858Y196949D01*
G01X1286614Y198130D02*
X1282677D01*
G01X1287795Y196949D02*
X1283858D01*
G01X1287185Y196673D02*
X1286201D01*
G01X1286202Y196181D02*
X1291535D01*
G01Y196142D02*
X1287187D01*
G01X1291535Y194803D02*
X1286202D01*
G01X1286201Y194311D02*
X1287185D01*
G01Y191673D02*
X1286201D01*
G01X1286202Y191181D02*
X1291535D01*
G01Y191142D02*
X1287187D01*
G01X1291535Y189803D02*
X1286202D01*
G01X1286201Y189311D02*
X1287185D01*
G01Y186673D02*
X1286201D01*
G01X1286202Y186181D02*
X1291535D01*
G01Y186142D02*
X1287187D01*
G01X1291535Y184803D02*
X1286202D01*
G01X1286201Y184311D02*
X1287185D01*
G01Y181673D02*
X1286201D01*
G01X1286202Y181181D02*
X1291535D01*
G01Y181142D02*
X1287187D01*
G01X1291535Y179803D02*
X1286202D01*
G01X1286201Y179311D02*
X1287185D01*
G01Y176673D02*
X1286201D01*
G01X1286202Y176181D02*
X1291535D01*
G01Y176142D02*
X1287187D01*
G01X1291535Y174803D02*
X1286202D01*
G01X1286201Y174311D02*
X1287185D01*
G01Y171673D02*
X1286201D01*
G01X1286202Y171181D02*
X1291535D01*
G01Y171142D02*
X1287187D01*
G01X1291535Y169803D02*
X1286202D01*
G01X1286201Y169311D02*
X1287185D01*
G01X1286201Y196377D02*
X1287156Y196378D01*
G01X1287185Y194607D02*
X1286201Y194606D01*
G01Y191377D02*
X1287156Y191378D01*
G01X1287185Y189607D02*
X1286201Y189606D01*
G01Y186377D02*
X1287156Y186378D01*
G01X1287185Y184607D02*
X1286201Y184606D01*
G01Y181377D02*
X1287156Y181378D01*
G01X1287185Y179607D02*
X1286201Y179606D01*
G01Y176377D02*
X1287156Y176378D01*
G01X1287185Y174607D02*
X1286201Y174606D01*
G01Y171377D02*
X1287156Y171378D01*
G01X1287185Y169607D02*
X1286201Y169606D01*
G01X1287185Y166673D02*
X1286201D01*
G01X1286202Y166181D02*
X1291535D01*
G01Y166142D02*
X1287187D01*
G01X1291535Y164803D02*
X1286202D01*
G01X1286201Y164311D02*
X1287185D01*
G01X1286201Y166377D02*
X1287156Y166378D01*
G01X1287185Y164607D02*
X1286201Y164606D01*
G01X1287172Y221173D02*
X1287183Y221157D01*
G01X1287148Y221181D02*
X1287172Y221173D01*
G01Y226173D02*
X1287183Y226157D01*
G01X1287148Y226181D02*
X1287172Y226173D01*
G01Y231173D02*
X1287183Y231157D01*
G01X1287148Y231181D02*
X1287172Y231173D01*
G01Y236173D02*
X1287183Y236157D01*
G01X1287148Y236181D02*
X1287172Y236173D01*
G01Y241173D02*
X1287183Y241157D01*
G01X1287148Y241181D02*
X1287172Y241173D01*
G01Y246173D02*
X1287183Y246157D01*
G01X1287148Y246181D02*
X1287172Y246173D01*
G01Y251173D02*
X1287183Y251157D01*
G01X1287148Y251181D02*
X1287172Y251173D01*
G01Y256173D02*
X1287183Y256157D01*
G01X1287148Y256181D02*
X1287172Y256173D01*
G01X1287185Y221148D02*
Y221156D01*
G01X1287186Y221144D02*
X1287185Y221148D01*
G01X1287187Y221142D02*
X1287186Y221144D01*
G01X1287185Y226148D02*
Y226156D01*
G01X1287186Y226144D02*
X1287185Y226148D01*
G01X1287187Y226142D02*
X1287186Y226144D01*
G01X1287185Y231148D02*
Y231156D01*
G01X1287186Y231144D02*
X1287185Y231148D01*
G01X1287187Y231142D02*
X1287186Y231144D01*
G01X1287185Y236148D02*
Y236156D01*
G01X1287186Y236144D02*
X1287185Y236148D01*
G01X1287187Y236142D02*
X1287186Y236144D01*
G01X1287185Y241148D02*
Y241156D01*
G01X1287186Y241144D02*
X1287185Y241148D01*
G01X1287187Y241142D02*
X1287186Y241144D01*
G01X1287185Y246148D02*
Y246156D01*
G01X1287186Y246144D02*
X1287185Y246148D01*
G01X1287187Y246142D02*
X1287186Y246144D01*
G01X1287185Y251148D02*
Y251156D01*
G01X1287186Y251144D02*
X1287185Y251148D01*
G01X1287187Y251142D02*
X1287186Y251144D01*
G01X1287185Y256148D02*
Y256156D01*
G01X1287186Y256144D02*
X1287185Y256148D01*
G01X1287187Y256142D02*
X1287186Y256144D01*
G01X1286201Y221189D02*
Y221198D01*
G01X1286202Y221183D02*
X1286201Y221189D01*
G01X1286202Y221181D02*
Y221183D01*
G01X1286201Y226189D02*
Y226198D01*
G01X1286202Y226183D02*
X1286201Y226189D01*
G01X1286202Y226181D02*
Y226183D01*
G01X1286201Y231189D02*
Y231198D01*
G01X1286202Y231183D02*
X1286201Y231189D01*
G01X1286202Y231181D02*
Y231183D01*
G01X1286201Y236189D02*
Y236198D01*
G01X1286202Y236183D02*
X1286201Y236189D01*
G01X1286202Y236181D02*
Y236183D01*
G01X1286201Y241189D02*
Y241198D01*
G01X1286202Y241183D02*
X1286201Y241189D01*
G01X1286202Y241181D02*
Y241183D01*
G01X1286201Y246189D02*
Y246198D01*
G01X1286202Y246183D02*
X1286201Y246189D01*
G01X1286202Y246181D02*
Y246183D01*
G01X1286201Y251189D02*
Y251198D01*
G01X1286202Y251183D02*
X1286201Y251189D01*
G01X1286202Y251181D02*
Y251183D01*
G01X1286201Y256189D02*
Y256198D01*
G01X1286202Y256183D02*
X1286201Y256189D01*
G01X1286202Y256181D02*
Y256183D01*
G01X1287177Y221325D02*
X1287185Y221299D01*
G01X1287167Y221352D02*
X1287177Y221325D01*
G01X1287156Y221378D02*
X1287167Y221352D01*
G01X1287177Y226325D02*
X1287185Y226299D01*
G01X1287167Y226352D02*
X1287177Y226325D01*
G01X1287156Y226378D02*
X1287167Y226352D01*
G01X1287177Y231325D02*
X1287185Y231299D01*
G01X1287167Y231352D02*
X1287177Y231325D01*
G01X1287156Y231378D02*
X1287167Y231352D01*
G01X1287177Y236325D02*
X1287185Y236299D01*
G01X1287167Y236352D02*
X1287177Y236325D01*
G01X1287156Y236378D02*
X1287167Y236352D01*
G01X1287177Y241325D02*
X1287185Y241299D01*
G01X1287167Y241352D02*
X1287177Y241325D01*
G01X1287156Y241378D02*
X1287167Y241352D01*
G01X1287177Y246325D02*
X1287185Y246299D01*
G01X1287167Y246352D02*
X1287177Y246325D01*
G01X1287156Y246378D02*
X1287167Y246352D01*
G01X1287177Y251325D02*
X1287185Y251299D01*
G01X1287167Y251352D02*
X1287177Y251325D01*
G01X1287156Y251378D02*
X1287167Y251352D01*
G01X1287177Y256325D02*
X1287185Y256299D01*
G01X1287167Y256352D02*
X1287177Y256325D01*
G01X1287156Y256378D02*
X1287167Y256352D01*
G01X1287168Y221176D02*
X1287148Y221181D01*
G01X1287182Y221162D02*
X1287168Y221176D01*
G01X1287187Y221142D02*
X1287182Y221162D01*
G01X1287168Y226176D02*
X1287148Y226181D01*
G01X1287182Y226162D02*
X1287168Y226176D01*
G01X1287187Y226142D02*
X1287182Y226162D01*
G01X1287168Y231176D02*
X1287148Y231181D01*
G01X1287182Y231162D02*
X1287168Y231176D01*
G01X1287187Y231142D02*
X1287182Y231162D01*
G01X1287168Y236176D02*
X1287148Y236181D01*
G01X1287182Y236162D02*
X1287168Y236176D01*
G01X1287187Y236142D02*
X1287182Y236162D01*
G01X1287168Y241176D02*
X1287148Y241181D01*
G01X1287182Y241162D02*
X1287168Y241176D01*
G01X1287187Y241142D02*
X1287182Y241162D01*
G01X1287168Y246176D02*
X1287148Y246181D01*
G01X1287182Y246162D02*
X1287168Y246176D01*
G01X1287187Y246142D02*
X1287182Y246162D01*
G01X1287168Y251176D02*
X1287148Y251181D01*
G01X1287182Y251162D02*
X1287168Y251176D01*
G01X1287187Y251142D02*
X1287182Y251162D01*
G01X1287168Y256176D02*
X1287148Y256181D01*
G01X1287182Y256162D02*
X1287168Y256176D01*
G01X1287187Y256142D02*
X1287182Y256162D01*
G01X1287152Y221279D02*
X1287156Y221378D01*
G01X1287146Y221207D02*
X1287152Y221279D01*
G01X1287148Y221181D02*
X1287146Y221207D01*
G01X1287152Y226279D02*
X1287156Y226378D01*
G01X1287146Y226207D02*
X1287152Y226279D01*
G01X1287148Y226181D02*
X1287146Y226207D01*
G01X1287152Y231279D02*
X1287156Y231378D01*
G01X1287146Y231207D02*
X1287152Y231279D01*
G01X1287148Y231181D02*
X1287146Y231207D01*
G01X1287152Y236279D02*
X1287156Y236378D01*
G01X1287146Y236207D02*
X1287152Y236279D01*
G01X1287148Y236181D02*
X1287146Y236207D01*
G01X1287152Y241279D02*
X1287156Y241378D01*
G01X1287146Y241207D02*
X1287152Y241279D01*
G01X1287148Y241181D02*
X1287146Y241207D01*
G01X1287152Y246279D02*
X1287156Y246378D01*
G01X1287146Y246207D02*
X1287152Y246279D01*
G01X1287148Y246181D02*
X1287146Y246207D01*
G01X1287152Y251279D02*
X1287156Y251378D01*
G01X1287146Y251207D02*
X1287152Y251279D01*
G01X1287148Y251181D02*
X1287146Y251207D01*
G01X1287152Y256279D02*
X1287156Y256378D01*
G01X1287146Y256207D02*
X1287152Y256279D01*
G01X1287148Y256181D02*
X1287146Y256207D01*
G01X1286202Y259802D02*
Y259803D01*
G01X1286201Y259796D02*
X1286202Y259802D01*
G01X1286201Y259787D02*
Y259796D01*
G01X1286202Y254802D02*
Y254803D01*
G01X1286201Y254796D02*
X1286202Y254802D01*
G01X1286201Y254787D02*
Y254796D01*
G01X1286202Y249802D02*
Y249803D01*
G01X1286201Y249796D02*
X1286202Y249802D01*
G01X1286201Y249787D02*
Y249796D01*
G01X1286202Y244802D02*
Y244803D01*
G01X1286201Y244796D02*
X1286202Y244802D01*
G01X1286201Y244787D02*
Y244796D01*
G01X1286202Y239802D02*
Y239803D01*
G01X1286201Y239796D02*
X1286202Y239802D01*
G01X1286201Y239787D02*
Y239796D01*
G01X1286202Y234802D02*
Y234803D01*
G01X1286201Y234796D02*
X1286202Y234802D01*
G01X1286201Y234787D02*
Y234796D01*
G01X1286202Y229802D02*
Y229803D01*
G01X1286201Y229796D02*
X1286202Y229802D01*
G01X1286201Y229787D02*
Y229796D01*
G01X1286202Y224802D02*
Y224803D01*
G01X1286201Y224796D02*
X1286202Y224802D01*
G01X1286201Y224787D02*
Y224796D01*
G01X1286202Y219802D02*
Y219803D01*
G01X1286201Y219796D02*
X1286202Y219802D01*
G01X1286201Y219787D02*
Y219796D01*
G01X1287185Y259796D02*
Y259787D01*
G01X1287186Y259802D02*
X1287185Y259796D01*
G01X1287188Y259803D02*
X1287186Y259802D01*
G01X1287185Y254796D02*
Y254787D01*
G01X1287186Y254802D02*
X1287185Y254796D01*
G01X1287188Y254803D02*
X1287186Y254802D01*
G01X1287185Y249796D02*
Y249787D01*
G01X1287186Y249802D02*
X1287185Y249796D01*
G01X1287188Y249803D02*
X1287186Y249802D01*
G01X1287185Y244796D02*
Y244787D01*
G01X1287186Y244802D02*
X1287185Y244796D01*
G01X1287188Y244803D02*
X1287186Y244802D01*
G01X1287185Y239796D02*
Y239787D01*
G01X1287186Y239802D02*
X1287185Y239796D01*
G01X1287188Y239803D02*
X1287186Y239802D01*
G01X1287185Y234796D02*
Y234787D01*
G01X1287186Y234802D02*
X1287185Y234796D01*
G01X1287188Y234803D02*
X1287186Y234802D01*
G01X1287185Y229796D02*
Y229787D01*
G01X1287186Y229802D02*
X1287185Y229796D01*
G01X1287188Y229803D02*
X1287186Y229802D01*
G01X1287185Y224796D02*
Y224787D01*
G01X1287186Y224802D02*
X1287185Y224796D01*
G01X1287188Y224803D02*
X1287186Y224802D01*
G01X1287185Y219796D02*
Y219787D01*
G01X1287186Y219802D02*
X1287185Y219796D01*
G01X1287188Y219803D02*
X1287186Y219802D01*
G01X1286614Y217854D02*
X1287795Y219035D01*
G01X1282677Y217854D02*
X1283858Y219035D01*
G01X1287185Y221155D02*
Y221164D01*
G01Y226155D02*
Y226164D01*
G01Y231155D02*
Y231164D01*
G01Y236155D02*
Y236164D01*
G01Y241155D02*
Y241164D01*
G01Y246155D02*
Y246164D01*
G01Y251155D02*
Y251164D01*
G01Y256155D02*
Y256164D01*
G01X1291535Y259803D02*
Y261181D01*
G01Y254803D02*
Y256181D01*
G01Y249803D02*
Y251181D01*
G01Y244803D02*
Y246181D01*
G01Y239803D02*
Y241181D01*
G01Y234803D02*
Y236181D01*
G01Y229803D02*
Y231181D01*
G01Y224803D02*
Y226181D01*
G01Y219803D02*
Y221181D01*
G01X1288366D02*
Y219803D01*
G01Y226181D02*
Y224803D01*
G01Y231181D02*
Y229803D01*
G01Y236181D02*
Y234803D01*
G01Y241181D02*
Y239803D01*
G01Y246181D02*
Y244803D01*
G01Y251181D02*
Y249803D01*
G01Y256181D02*
Y254803D01*
G01Y261181D02*
Y259803D01*
G01X1287185Y221156D02*
Y221299D01*
G01Y226156D02*
Y226299D01*
G01Y231156D02*
Y231299D01*
G01Y236156D02*
Y236299D01*
G01Y241156D02*
Y241299D01*
G01Y246156D02*
Y246299D01*
G01Y251156D02*
Y251299D01*
G01Y256156D02*
Y256299D01*
G01Y259311D02*
Y261673D01*
G01Y254311D02*
Y256673D01*
G01Y249311D02*
Y251673D01*
G01Y244311D02*
Y246673D01*
G01Y239311D02*
Y241673D01*
G01Y234311D02*
Y236673D01*
G01Y229311D02*
Y231673D01*
G01Y224311D02*
Y226673D01*
G01Y219311D02*
Y221673D01*
G01X1286201D02*
Y219311D01*
G01Y226673D02*
Y224311D01*
G01Y231673D02*
Y229311D01*
G01Y236673D02*
Y234311D01*
G01Y241673D02*
Y239311D01*
G01Y246673D02*
Y244311D01*
G01Y251673D02*
Y249311D01*
G01Y256673D02*
Y254311D01*
G01Y261673D02*
Y259311D01*
G01X1283858Y295492D02*
Y219035D01*
G01X1282677Y294311D02*
Y217854D01*
G01X1291535Y259803D02*
X1286202D01*
G01X1286201Y259311D02*
X1287185D01*
G01Y256673D02*
X1286201D01*
G01X1287185Y259607D02*
X1286201Y259606D01*
G01X1286202Y256181D02*
X1291535D01*
G01Y256142D02*
X1287187D01*
G01X1291535Y254803D02*
X1286202D01*
G01X1286201Y254311D02*
X1287185D01*
G01Y251673D02*
X1286201D01*
G01X1286202Y251181D02*
X1291535D01*
G01Y251142D02*
X1287187D01*
G01X1291535Y249803D02*
X1286202D01*
G01X1286201Y249311D02*
X1287185D01*
G01Y246673D02*
X1286201D01*
G01X1286202Y246181D02*
X1291535D01*
G01Y246142D02*
X1287187D01*
G01X1291535Y244803D02*
X1286202D01*
G01X1286201Y244311D02*
X1287185D01*
G01Y241673D02*
X1286201D01*
G01X1286202Y241181D02*
X1291535D01*
G01Y241142D02*
X1287187D01*
G01X1291535Y239803D02*
X1286202D01*
G01X1286201Y239311D02*
X1287185D01*
G01Y236673D02*
X1286201D01*
G01X1286202Y236181D02*
X1291535D01*
G01Y236142D02*
X1287187D01*
G01X1291535Y234803D02*
X1286202D01*
G01X1286201Y234311D02*
X1287185D01*
G01Y231673D02*
X1286201D01*
G01X1286202Y231181D02*
X1291535D01*
G01Y231142D02*
X1287187D01*
G01X1291535Y229803D02*
X1286202D01*
G01X1286201Y229311D02*
X1287185D01*
G01Y226673D02*
X1286201D01*
G01X1286202Y226181D02*
X1291535D01*
G01Y226142D02*
X1287187D01*
G01X1291535Y224803D02*
X1286202D01*
G01X1286201Y224311D02*
X1287185D01*
G01Y221673D02*
X1286201D01*
G01X1286202Y221181D02*
X1291535D01*
G01Y221142D02*
X1287187D01*
G01X1291535Y219803D02*
X1286202D01*
G01X1286201Y219311D02*
X1287185D01*
G01X1283858Y219035D02*
X1287795D01*
G01X1282677Y217854D02*
X1286614D01*
G01X1286201Y256377D02*
X1287156Y256378D01*
G01X1287185Y254607D02*
X1286201Y254606D01*
G01Y251377D02*
X1287156Y251378D01*
G01X1287185Y249607D02*
X1286201Y249606D01*
G01Y246377D02*
X1287156Y246378D01*
G01X1287185Y244607D02*
X1286201Y244606D01*
G01Y241377D02*
X1287156Y241378D01*
G01X1287185Y239607D02*
X1286201Y239606D01*
G01Y236377D02*
X1287156Y236378D01*
G01X1287185Y234607D02*
X1286201Y234606D01*
G01Y231377D02*
X1287156Y231378D01*
G01X1287185Y229607D02*
X1286201Y229606D01*
G01Y226377D02*
X1287156Y226378D01*
G01X1287185Y224607D02*
X1286201Y224606D01*
G01Y221377D02*
X1287156Y221378D01*
G01X1287185Y219607D02*
X1286201Y219606D01*
G01X1287172Y261173D02*
X1287183Y261157D01*
G01X1287148Y261181D02*
X1287172Y261173D01*
G01Y266173D02*
X1287183Y266157D01*
G01X1287148Y266181D02*
X1287172Y266173D01*
G01Y271173D02*
X1287183Y271157D01*
G01X1287148Y271181D02*
X1287172Y271173D01*
G01Y276173D02*
X1287183Y276157D01*
G01X1287148Y276181D02*
X1287172Y276173D01*
G01Y281173D02*
X1287183Y281157D01*
G01X1287148Y281181D02*
X1287172Y281173D01*
G01Y286173D02*
X1287183Y286157D01*
G01X1287148Y286181D02*
X1287172Y286173D01*
G01Y291173D02*
X1287183Y291157D01*
G01X1287148Y291181D02*
X1287172Y291173D01*
G01X1287185Y261148D02*
Y261156D01*
G01X1287186Y261144D02*
X1287185Y261148D01*
G01X1287187Y261142D02*
X1287186Y261144D01*
G01X1287185Y266148D02*
Y266156D01*
G01X1287186Y266144D02*
X1287185Y266148D01*
G01X1287187Y266142D02*
X1287186Y266144D01*
G01X1287185Y271148D02*
Y271156D01*
G01X1287186Y271144D02*
X1287185Y271148D01*
G01X1287187Y271142D02*
X1287186Y271144D01*
G01X1287185Y276148D02*
Y276156D01*
G01X1287186Y276144D02*
X1287185Y276148D01*
G01X1287187Y276142D02*
X1287186Y276144D01*
G01X1287185Y281148D02*
Y281156D01*
G01X1287186Y281144D02*
X1287185Y281148D01*
G01X1287187Y281142D02*
X1287186Y281144D01*
G01X1287185Y286148D02*
Y286156D01*
G01X1287186Y286144D02*
X1287185Y286148D01*
G01X1287187Y286142D02*
X1287186Y286144D01*
G01X1287185Y291148D02*
Y291156D01*
G01X1287186Y291144D02*
X1287185Y291148D01*
G01X1287187Y291142D02*
X1287186Y291144D01*
G01X1286201Y261189D02*
Y261198D01*
G01X1286202Y261183D02*
X1286201Y261189D01*
G01X1286202Y261181D02*
Y261183D01*
G01X1286201Y266189D02*
Y266198D01*
G01X1286202Y266183D02*
X1286201Y266189D01*
G01X1286202Y266181D02*
Y266183D01*
G01X1286201Y271189D02*
Y271198D01*
G01X1286202Y271183D02*
X1286201Y271189D01*
G01X1286202Y271181D02*
Y271183D01*
G01X1286201Y276189D02*
Y276198D01*
G01X1286202Y276183D02*
X1286201Y276189D01*
G01X1286202Y276181D02*
Y276183D01*
G01X1286201Y281189D02*
Y281198D01*
G01X1286202Y281183D02*
X1286201Y281189D01*
G01X1286202Y281181D02*
Y281183D01*
G01X1286201Y286189D02*
Y286198D01*
G01X1286202Y286183D02*
X1286201Y286189D01*
G01X1286202Y286181D02*
Y286183D01*
G01X1286201Y291189D02*
Y291198D01*
G01X1286202Y291183D02*
X1286201Y291189D01*
G01X1286202Y291181D02*
Y291183D01*
G01X1287177Y261325D02*
X1287185Y261299D01*
G01X1287167Y261352D02*
X1287177Y261325D01*
G01X1287156Y261378D02*
X1287167Y261352D01*
G01X1287177Y266325D02*
X1287185Y266299D01*
G01X1287167Y266352D02*
X1287177Y266325D01*
G01X1287156Y266378D02*
X1287167Y266352D01*
G01X1287177Y271325D02*
X1287185Y271299D01*
G01X1287167Y271352D02*
X1287177Y271325D01*
G01X1287156Y271378D02*
X1287167Y271352D01*
G01X1287177Y276325D02*
X1287185Y276299D01*
G01X1287167Y276352D02*
X1287177Y276325D01*
G01X1287156Y276378D02*
X1287167Y276352D01*
G01X1287177Y281325D02*
X1287185Y281299D01*
G01X1287167Y281352D02*
X1287177Y281325D01*
G01X1287156Y281378D02*
X1287167Y281352D01*
G01X1287177Y286325D02*
X1287185Y286299D01*
G01X1287167Y286352D02*
X1287177Y286325D01*
G01X1287156Y286378D02*
X1287167Y286352D01*
G01X1287177Y291325D02*
X1287185Y291299D01*
G01X1287167Y291352D02*
X1287177Y291325D01*
G01X1287156Y291378D02*
X1287167Y291352D01*
G01X1287168Y261176D02*
X1287148Y261181D01*
G01X1287182Y261162D02*
X1287168Y261176D01*
G01X1287187Y261142D02*
X1287182Y261162D01*
G01X1287168Y266176D02*
X1287148Y266181D01*
G01X1287182Y266162D02*
X1287168Y266176D01*
G01X1287187Y266142D02*
X1287182Y266162D01*
G01X1287168Y271176D02*
X1287148Y271181D01*
G01X1287182Y271162D02*
X1287168Y271176D01*
G01X1287187Y271142D02*
X1287182Y271162D01*
G01X1287168Y276176D02*
X1287148Y276181D01*
G01X1287182Y276162D02*
X1287168Y276176D01*
G01X1287187Y276142D02*
X1287182Y276162D01*
G01X1287168Y281176D02*
X1287148Y281181D01*
G01X1287182Y281162D02*
X1287168Y281176D01*
G01X1287187Y281142D02*
X1287182Y281162D01*
G01X1287168Y286176D02*
X1287148Y286181D01*
G01X1287182Y286162D02*
X1287168Y286176D01*
G01X1287187Y286142D02*
X1287182Y286162D01*
G01X1287168Y291176D02*
X1287148Y291181D01*
G01X1287182Y291162D02*
X1287168Y291176D01*
G01X1287187Y291142D02*
X1287182Y291162D01*
G01X1287152Y261279D02*
X1287156Y261378D01*
G01X1287146Y261207D02*
X1287152Y261279D01*
G01X1287148Y261181D02*
X1287146Y261207D01*
G01X1287152Y266279D02*
X1287156Y266378D01*
G01X1287146Y266207D02*
X1287152Y266279D01*
G01X1287148Y266181D02*
X1287146Y266207D01*
G01X1287152Y271279D02*
X1287156Y271378D01*
G01X1287146Y271207D02*
X1287152Y271279D01*
G01X1287148Y271181D02*
X1287146Y271207D01*
G01X1287152Y276279D02*
X1287156Y276378D01*
G01X1287146Y276207D02*
X1287152Y276279D01*
G01X1287148Y276181D02*
X1287146Y276207D01*
G01X1287152Y281279D02*
X1287156Y281378D01*
G01X1287146Y281207D02*
X1287152Y281279D01*
G01X1287148Y281181D02*
X1287146Y281207D01*
G01X1287152Y286279D02*
X1287156Y286378D01*
G01X1287146Y286207D02*
X1287152Y286279D01*
G01X1287148Y286181D02*
X1287146Y286207D01*
G01X1287152Y291279D02*
X1287156Y291378D01*
G01X1287146Y291207D02*
X1287152Y291279D01*
G01X1287148Y291181D02*
X1287146Y291207D01*
G01X1286202Y289802D02*
Y289803D01*
G01X1286201Y289796D02*
X1286202Y289802D01*
G01X1286201Y289787D02*
Y289796D01*
G01X1286202Y284802D02*
Y284803D01*
G01X1286201Y284796D02*
X1286202Y284802D01*
G01X1286201Y284787D02*
Y284796D01*
G01X1286202Y279802D02*
Y279803D01*
G01X1286201Y279796D02*
X1286202Y279802D01*
G01X1286201Y279787D02*
Y279796D01*
G01X1286202Y274802D02*
Y274803D01*
G01X1286201Y274796D02*
X1286202Y274802D01*
G01X1286201Y274787D02*
Y274796D01*
G01X1286202Y269802D02*
Y269803D01*
G01X1286201Y269796D02*
X1286202Y269802D01*
G01X1286201Y269787D02*
Y269796D01*
G01X1286202Y264802D02*
Y264803D01*
G01X1286201Y264796D02*
X1286202Y264802D01*
G01X1286201Y264787D02*
Y264796D01*
G01X1287185Y289796D02*
Y289787D01*
G01X1287186Y289802D02*
X1287185Y289796D01*
G01X1287188Y289803D02*
X1287186Y289802D01*
G01X1287185Y284796D02*
Y284787D01*
G01X1287186Y284802D02*
X1287185Y284796D01*
G01X1287188Y284803D02*
X1287186Y284802D01*
G01X1287185Y279796D02*
Y279787D01*
G01X1287186Y279802D02*
X1287185Y279796D01*
G01X1287188Y279803D02*
X1287186Y279802D01*
G01X1287185Y274796D02*
Y274787D01*
G01X1287186Y274802D02*
X1287185Y274796D01*
G01X1287188Y274803D02*
X1287186Y274802D01*
G01X1287185Y269796D02*
Y269787D01*
G01X1287186Y269802D02*
X1287185Y269796D01*
G01X1287188Y269803D02*
X1287186Y269802D01*
G01X1287185Y264796D02*
Y264787D01*
G01X1287186Y264802D02*
X1287185Y264796D01*
G01X1287188Y264803D02*
X1287186Y264802D01*
G01X1285433Y306398D02*
G03X1284252Y307579I-1181J0D01*
G01X1292520Y300335D02*
X1289173Y296988D01*
G01X1282677Y294311D02*
X1283858Y295492D01*
G01X1285184Y307123D02*
X1282874Y302894D01*
G01X1287185Y261155D02*
Y261164D01*
G01Y266155D02*
Y266164D01*
G01Y271155D02*
Y271164D01*
G01Y276155D02*
Y276164D01*
G01Y281155D02*
Y281164D01*
G01Y286155D02*
Y286164D01*
G01Y291155D02*
Y291164D01*
G01X1292520Y300335D02*
Y316083D01*
G01X1291535Y289803D02*
Y291181D01*
G01Y284803D02*
Y286181D01*
G01Y279803D02*
Y281181D01*
G01Y274803D02*
Y276181D01*
G01Y269803D02*
Y271181D01*
G01Y264803D02*
Y266181D01*
G01X1288366D02*
Y264803D01*
G01Y271181D02*
Y269803D01*
G01Y276181D02*
Y274803D01*
G01Y281181D02*
Y279803D01*
G01Y286181D02*
Y284803D01*
G01Y291181D02*
Y289803D01*
G01X1287185Y261156D02*
Y261299D01*
G01Y266156D02*
Y266299D01*
G01Y271156D02*
Y271299D01*
G01Y276156D02*
Y276299D01*
G01Y281156D02*
Y281299D01*
G01Y286156D02*
Y286299D01*
G01Y291156D02*
Y291299D01*
G01Y289311D02*
Y291673D01*
G01Y284311D02*
Y286673D01*
G01Y279311D02*
Y281673D01*
G01Y274311D02*
Y276673D01*
G01Y269311D02*
Y271673D01*
G01Y264311D02*
Y266673D01*
G01X1286201D02*
Y264311D01*
G01Y271673D02*
Y269311D01*
G01Y276673D02*
Y274311D01*
G01Y281673D02*
Y279311D01*
G01Y286673D02*
Y284311D01*
G01Y291673D02*
Y289311D01*
G01X1285433Y306398D02*
Y297854D01*
G01X1282874Y302894D02*
Y301201D01*
G01D02*
X1284178Y299232D01*
G01X1288583Y297854D02*
X1285433D01*
G01X1287185Y291673D02*
X1286201D01*
G01X1286202Y291181D02*
X1291535D01*
G01Y291142D02*
X1287187D01*
G01X1291535Y289803D02*
X1286202D01*
G01X1286201Y289311D02*
X1287185D01*
G01Y286673D02*
X1286201D01*
G01X1286202Y286181D02*
X1291535D01*
G01Y286142D02*
X1287187D01*
G01X1291535Y284803D02*
X1286202D01*
G01X1286201Y284311D02*
X1287185D01*
G01Y281673D02*
X1286201D01*
G01X1286202Y281181D02*
X1291535D01*
G01Y281142D02*
X1287187D01*
G01X1291535Y279803D02*
X1286202D01*
G01X1286201Y279311D02*
X1287185D01*
G01Y276673D02*
X1286201D01*
G01X1286202Y276181D02*
X1291535D01*
G01Y276142D02*
X1287187D01*
G01X1291535Y274803D02*
X1286202D01*
G01X1286201Y274311D02*
X1287185D01*
G01Y271673D02*
X1286201D01*
G01X1286202Y271181D02*
X1291535D01*
G01Y271142D02*
X1287187D01*
G01X1291535Y269803D02*
X1286202D01*
G01X1286201Y269311D02*
X1287185D01*
G01Y266673D02*
X1286201D01*
G01X1286202Y266181D02*
X1291535D01*
G01Y266142D02*
X1287187D01*
G01X1291535Y264803D02*
X1286202D01*
G01X1286201Y264311D02*
X1287185D01*
G01Y261673D02*
X1286201D01*
G01X1286202Y261181D02*
X1291535D01*
G01Y261142D02*
X1287187D01*
G01X1286201Y291377D02*
X1287156Y291378D01*
G01X1287185Y289607D02*
X1286201Y289606D01*
G01Y286377D02*
X1287156Y286378D01*
G01X1287185Y284607D02*
X1286201Y284606D01*
G01Y281377D02*
X1287156Y281378D01*
G01X1287185Y279607D02*
X1286201Y279606D01*
G01Y276377D02*
X1287156Y276378D01*
G01X1287185Y274607D02*
X1286201Y274606D01*
G01Y271377D02*
X1287156Y271378D01*
G01X1287185Y269607D02*
X1286201Y269606D01*
G01Y266377D02*
X1287156Y266378D01*
G01X1287185Y264607D02*
X1286201Y264606D01*
G01Y261377D02*
X1287156Y261378D01*
G01X1285630Y316673D02*
G03X1285039Y317264I-591J0D01*
G01X1282874Y313524D02*
G03Y315492I0J984D01*
G01X1292520Y316083D02*
G03X1290551Y318051I-1968J0D01*
G01X1285630Y310571D02*
Y316673D01*
G01X1311851Y392016D02*
G03X1318775Y378885I37663J11469D01*
G01X1311851Y392016D02*
G03X1291890I-9980J-3039D01*
G01X1284965Y378885D02*
G03X1291890Y392016I-30737J24602D01*
G01X1311850D02*
G03X1318776Y378885I37662J11473D01*
G01X1311850Y392016D02*
G03X1291890I-9980J-3040D01*
G01X1284965Y378885D02*
G03X1291890Y392016I-30737J24602D01*
G01X1285039Y591476D02*
G03X1285630Y592067I0J591D01*
G01X1282874Y593248D02*
G03Y595217I0J985D01*
G01X1290551Y590689D02*
G03X1292520Y592657I0J1969D01*
G01D02*
Y608406D01*
G01X1285630Y598169D02*
Y592067D01*
G01X1287172Y618929D02*
X1287183Y618913D01*
G01X1287148Y618937D02*
X1287172Y618929D01*
G01Y623929D02*
X1287183Y623913D01*
G01X1287148Y623937D02*
X1287172Y623929D01*
G01Y628929D02*
X1287183Y628913D01*
G01X1287148Y628937D02*
X1287172Y628929D01*
G01Y633929D02*
X1287183Y633913D01*
G01X1287148Y633937D02*
X1287172Y633929D01*
G01Y638929D02*
X1287183Y638913D01*
G01X1287148Y638937D02*
X1287172Y638929D01*
G01Y643929D02*
X1287183Y643913D01*
G01X1287148Y643937D02*
X1287172Y643929D01*
G01X1287185Y618904D02*
Y618911D01*
G01X1287186Y618900D02*
X1287185Y618904D01*
G01X1287187Y618898D02*
X1287186Y618900D01*
G01X1287185Y623904D02*
Y623911D01*
G01X1287186Y623900D02*
X1287185Y623904D01*
G01X1287187Y623898D02*
X1287186Y623900D01*
G01X1287185Y628904D02*
Y628911D01*
G01X1287186Y628900D02*
X1287185Y628904D01*
G01X1287187Y628898D02*
X1287186Y628900D01*
G01X1287185Y633904D02*
Y633911D01*
G01X1287186Y633900D02*
X1287185Y633904D01*
G01X1287187Y633898D02*
X1287186Y633900D01*
G01X1287185Y638904D02*
Y638911D01*
G01X1287186Y638900D02*
X1287185Y638904D01*
G01X1287187Y638898D02*
X1287186Y638900D01*
G01X1287185Y643904D02*
Y643911D01*
G01X1287186Y643900D02*
X1287185Y643904D01*
G01X1287187Y643898D02*
X1287186Y643900D01*
G01X1286201Y618944D02*
Y618954D01*
G01X1286202Y618939D02*
X1286201Y618944D01*
G01X1286202Y618937D02*
Y618939D01*
G01X1286201Y623944D02*
Y623954D01*
G01X1286202Y623939D02*
X1286201Y623944D01*
G01X1286202Y623937D02*
Y623939D01*
G01X1286201Y628944D02*
Y628954D01*
G01X1286202Y628939D02*
X1286201Y628944D01*
G01X1286202Y628937D02*
Y628939D01*
G01X1286201Y633944D02*
Y633954D01*
G01X1286202Y633939D02*
X1286201Y633944D01*
G01X1286202Y633937D02*
Y633939D01*
G01X1286201Y638944D02*
Y638954D01*
G01X1286202Y638939D02*
X1286201Y638944D01*
G01X1286202Y638937D02*
Y638939D01*
G01X1286201Y643944D02*
Y643954D01*
G01X1286202Y643939D02*
X1286201Y643944D01*
G01X1286202Y643937D02*
Y643939D01*
G01X1287177Y619081D02*
X1287185Y619055D01*
G01X1287167Y619107D02*
X1287177Y619081D01*
G01X1287156Y619134D02*
X1287167Y619107D01*
G01X1287177Y624081D02*
X1287185Y624055D01*
G01X1287167Y624107D02*
X1287177Y624081D01*
G01X1287156Y624134D02*
X1287167Y624107D01*
G01X1287177Y629081D02*
X1287185Y629055D01*
G01X1287167Y629107D02*
X1287177Y629081D01*
G01X1287156Y629134D02*
X1287167Y629107D01*
G01X1287177Y634081D02*
X1287185Y634055D01*
G01X1287167Y634107D02*
X1287177Y634081D01*
G01X1287156Y634134D02*
X1287167Y634107D01*
G01X1287177Y639081D02*
X1287185Y639055D01*
G01X1287167Y639107D02*
X1287177Y639081D01*
G01X1287156Y639134D02*
X1287167Y639107D01*
G01X1287177Y644081D02*
X1287185Y644055D01*
G01X1287167Y644107D02*
X1287177Y644081D01*
G01X1287156Y644134D02*
X1287167Y644107D01*
G01X1287168Y618932D02*
X1287148Y618937D01*
G01X1287182Y618918D02*
X1287168Y618932D01*
G01X1287187Y618898D02*
X1287182Y618918D01*
G01X1287168Y623932D02*
X1287148Y623937D01*
G01X1287182Y623918D02*
X1287168Y623932D01*
G01X1287187Y623898D02*
X1287182Y623918D01*
G01X1287168Y628932D02*
X1287148Y628937D01*
G01X1287182Y628918D02*
X1287168Y628932D01*
G01X1287187Y628898D02*
X1287182Y628918D01*
G01X1287168Y633932D02*
X1287148Y633937D01*
G01X1287182Y633918D02*
X1287168Y633932D01*
G01X1287187Y633898D02*
X1287182Y633918D01*
G01X1287168Y638932D02*
X1287148Y638937D01*
G01X1287182Y638918D02*
X1287168Y638932D01*
G01X1287187Y638898D02*
X1287182Y638918D01*
G01X1287168Y643932D02*
X1287148Y643937D01*
G01X1287182Y643918D02*
X1287168Y643932D01*
G01X1287187Y643898D02*
X1287182Y643918D01*
G01X1287152Y619035D02*
X1287156Y619134D01*
G01X1287146Y618963D02*
X1287152Y619035D01*
G01X1287148Y618937D02*
X1287146Y618963D01*
G01X1287152Y624035D02*
X1287156Y624134D01*
G01X1287146Y623963D02*
X1287152Y624035D01*
G01X1287148Y623937D02*
X1287146Y623963D01*
G01X1287152Y629035D02*
X1287156Y629134D01*
G01X1287146Y628963D02*
X1287152Y629035D01*
G01X1287148Y628937D02*
X1287146Y628963D01*
G01X1287152Y634035D02*
X1287156Y634134D01*
G01X1287146Y633963D02*
X1287152Y634035D01*
G01X1287148Y633937D02*
X1287146Y633963D01*
G01X1287152Y639035D02*
X1287156Y639134D01*
G01X1287146Y638963D02*
X1287152Y639035D01*
G01X1287148Y638937D02*
X1287146Y638963D01*
G01X1287152Y644035D02*
X1287156Y644134D01*
G01X1287146Y643963D02*
X1287152Y644035D01*
G01X1287148Y643937D02*
X1287146Y643963D01*
G01X1286202Y647557D02*
Y647559D01*
G01X1286201Y647552D02*
X1286202Y647557D01*
G01X1286201Y647543D02*
Y647552D01*
G01X1286202Y642557D02*
Y642559D01*
G01X1286201Y642552D02*
X1286202Y642557D01*
G01X1286201Y642543D02*
Y642552D01*
G01X1286202Y637557D02*
Y637559D01*
G01X1286201Y637552D02*
X1286202Y637557D01*
G01X1286201Y637543D02*
Y637552D01*
G01X1286202Y632557D02*
Y632559D01*
G01X1286201Y632552D02*
X1286202Y632557D01*
G01X1286201Y632543D02*
Y632552D01*
G01X1286202Y627557D02*
Y627559D01*
G01X1286201Y627552D02*
X1286202Y627557D01*
G01X1286201Y627543D02*
Y627552D01*
G01X1286202Y622557D02*
Y622559D01*
G01X1286201Y622552D02*
X1286202Y622557D01*
G01X1286201Y622543D02*
Y622552D01*
G01X1286202Y617557D02*
Y617559D01*
G01X1286201Y617552D02*
X1286202Y617557D01*
G01X1286201Y617543D02*
Y617552D01*
G01X1287185Y647552D02*
Y647543D01*
G01X1287186Y647557D02*
X1287185Y647552D01*
G01X1287188Y647559D02*
X1287186Y647557D01*
G01X1287185Y642552D02*
Y642543D01*
G01X1287186Y642557D02*
X1287185Y642552D01*
G01X1287188Y642559D02*
X1287186Y642557D01*
G01X1287185Y637552D02*
Y637543D01*
G01X1287186Y637557D02*
X1287185Y637552D01*
G01X1287188Y637559D02*
X1287186Y637557D01*
G01X1287185Y632552D02*
Y632543D01*
G01X1287186Y632557D02*
X1287185Y632552D01*
G01X1287188Y632559D02*
X1287186Y632557D01*
G01X1287185Y627552D02*
Y627543D01*
G01X1287186Y627557D02*
X1287185Y627552D01*
G01X1287188Y627559D02*
X1287186Y627557D01*
G01X1287185Y622552D02*
Y622543D01*
G01X1287186Y622557D02*
X1287185Y622552D01*
G01X1287188Y622559D02*
X1287186Y622557D01*
G01X1287185Y617552D02*
Y617543D01*
G01X1287186Y617557D02*
X1287185Y617552D01*
G01X1287188Y617559D02*
X1287186Y617557D01*
G01X1284252Y601161D02*
G03X1285433Y602343I0J1181D01*
G01X1284178Y609508D02*
X1282874Y607539D01*
G01X1287185Y618911D02*
Y618920D01*
G01Y623911D02*
Y623920D01*
G01Y628911D02*
Y628920D01*
G01Y633911D02*
Y633920D01*
G01Y638911D02*
Y638920D01*
G01Y643911D02*
Y643920D01*
G01X1291535Y647559D02*
Y648937D01*
G01Y642559D02*
Y643937D01*
G01Y637559D02*
Y638937D01*
G01Y632559D02*
Y633937D01*
G01Y627559D02*
Y628937D01*
G01Y622559D02*
Y623937D01*
G01Y617559D02*
Y618937D01*
G01X1289173Y749744D02*
Y611752D01*
G01X1288583Y751988D02*
Y609508D01*
G01X1288366Y618937D02*
Y617559D01*
G01Y623937D02*
Y622559D01*
G01Y628937D02*
Y627559D01*
G01Y633937D02*
Y632559D01*
G01Y638937D02*
Y637559D01*
G01Y643937D02*
Y642559D01*
G01Y648937D02*
Y647559D01*
G01X1287185Y647067D02*
Y649429D01*
G01Y642067D02*
Y644429D01*
G01Y637067D02*
Y639429D01*
G01Y632067D02*
Y634429D01*
G01Y627067D02*
Y629429D01*
G01Y622067D02*
Y624429D01*
G01Y617067D02*
Y619429D01*
G01X1286201D02*
Y617067D01*
G01Y624429D02*
Y622067D01*
G01Y629429D02*
Y627067D01*
G01Y634429D02*
Y632067D01*
G01Y639429D02*
Y637067D01*
G01Y644429D02*
Y642067D01*
G01Y649429D02*
Y647067D01*
G01X1285433Y610886D02*
Y602343D01*
G01X1283858Y649705D02*
Y613248D01*
G01X1282874Y607539D02*
Y605846D01*
G01X1282677Y650886D02*
Y614429D01*
G01X1282874Y605846D02*
X1285184Y601617D01*
G01X1289173Y611752D02*
X1292520Y608406D01*
G01X1282677Y614429D02*
X1283858Y613248D01*
G01X1291535Y647559D02*
X1286202D01*
G01X1286201Y647067D02*
X1287185D01*
G01Y644429D02*
X1286201D01*
G01X1286202Y643937D02*
X1291535D01*
G01Y643898D02*
X1287187D01*
G01X1291535Y642559D02*
X1286202D01*
G01X1286201Y642067D02*
X1287185D01*
G01Y639429D02*
X1286201D01*
G01X1286202Y638937D02*
X1291535D01*
G01Y638898D02*
X1287187D01*
G01X1291535Y637559D02*
X1286202D01*
G01X1286201Y637067D02*
X1287185D01*
G01Y634429D02*
X1286201D01*
G01X1286202Y633937D02*
X1291535D01*
G01Y633898D02*
X1287187D01*
G01X1291535Y632559D02*
X1286202D01*
G01X1286201Y632067D02*
X1287185D01*
G01Y629429D02*
X1286201D01*
G01X1286202Y628937D02*
X1291535D01*
G01Y628898D02*
X1287187D01*
G01X1291535Y627559D02*
X1286202D01*
G01X1286201Y627067D02*
X1287185D01*
G01Y624429D02*
X1286201D01*
G01X1286202Y623937D02*
X1291535D01*
G01Y623898D02*
X1287187D01*
G01X1291535Y622559D02*
X1286202D01*
G01X1286201Y622067D02*
X1287185D01*
G01Y619429D02*
X1286201D01*
G01X1286202Y618937D02*
X1291535D01*
G01Y618898D02*
X1287187D01*
G01X1291535Y617559D02*
X1286202D01*
G01X1286201Y617067D02*
X1287185D01*
G01Y647363D02*
X1286201Y647362D01*
G01Y644133D02*
X1287156Y644134D01*
G01X1287185Y642363D02*
X1286201Y642362D01*
G01Y639133D02*
X1287156Y639134D01*
G01X1287185Y637363D02*
X1286201Y637362D01*
G01Y634133D02*
X1287156Y634134D01*
G01X1287185Y632363D02*
X1286201Y632362D01*
G01Y629133D02*
X1287156Y629134D01*
G01X1287185Y627363D02*
X1286201Y627362D01*
G01Y624133D02*
X1287156Y624134D01*
G01X1287185Y622363D02*
X1286201Y622362D01*
G01Y619133D02*
X1287156Y619134D01*
G01X1287185Y617363D02*
X1286201Y617362D01*
G01X1285433Y610886D02*
X1288583D01*
G01X1287172Y648929D02*
X1287183Y648913D01*
G01X1287148Y648937D02*
X1287172Y648929D01*
G01Y673929D02*
X1287183Y673913D01*
G01X1287148Y673937D02*
X1287172Y673929D01*
G01Y678929D02*
X1287183Y678913D01*
G01X1287148Y678937D02*
X1287172Y678929D01*
G01Y683929D02*
X1287183Y683913D01*
G01X1287148Y683937D02*
X1287172Y683929D01*
G01Y688929D02*
X1287183Y688913D01*
G01X1287148Y688937D02*
X1287172Y688929D01*
G01Y693929D02*
X1287183Y693913D01*
G01X1287148Y693937D02*
X1287172Y693929D01*
G01X1287185Y648904D02*
Y648911D01*
G01X1287186Y648900D02*
X1287185Y648904D01*
G01X1287187Y648898D02*
X1287186Y648900D01*
G01X1287185Y673904D02*
Y673911D01*
G01X1287186Y673900D02*
X1287185Y673904D01*
G01X1287187Y673898D02*
X1287186Y673900D01*
G01X1287185Y678904D02*
Y678911D01*
G01X1287186Y678900D02*
X1287185Y678904D01*
G01X1287187Y678898D02*
X1287186Y678900D01*
G01X1287185Y683904D02*
Y683911D01*
G01X1287186Y683900D02*
X1287185Y683904D01*
G01X1287187Y683898D02*
X1287186Y683900D01*
G01X1287185Y688904D02*
Y688911D01*
G01X1287186Y688900D02*
X1287185Y688904D01*
G01X1287187Y688898D02*
X1287186Y688900D01*
G01X1287185Y693904D02*
Y693911D01*
G01X1287186Y693900D02*
X1287185Y693904D01*
G01X1287187Y693898D02*
X1287186Y693900D01*
G01X1286201Y648944D02*
Y648954D01*
G01X1286202Y648939D02*
X1286201Y648944D01*
G01X1286202Y648937D02*
Y648939D01*
G01X1286201Y673944D02*
Y673954D01*
G01X1286202Y673939D02*
X1286201Y673944D01*
G01X1286202Y673937D02*
Y673939D01*
G01X1286201Y678944D02*
Y678954D01*
G01X1286202Y678939D02*
X1286201Y678944D01*
G01X1286202Y678937D02*
Y678939D01*
G01X1286201Y683944D02*
Y683954D01*
G01X1286202Y683939D02*
X1286201Y683944D01*
G01X1286202Y683937D02*
Y683939D01*
G01X1286201Y688944D02*
Y688954D01*
G01X1286202Y688939D02*
X1286201Y688944D01*
G01X1286202Y688937D02*
Y688939D01*
G01X1286201Y693944D02*
Y693954D01*
G01X1286202Y693939D02*
X1286201Y693944D01*
G01X1286202Y693937D02*
Y693939D01*
G01X1287177Y649081D02*
X1287185Y649055D01*
G01X1287167Y649107D02*
X1287177Y649081D01*
G01X1287156Y649134D02*
X1287167Y649107D01*
G01X1287177Y674081D02*
X1287185Y674055D01*
G01X1287167Y674107D02*
X1287177Y674081D01*
G01X1287156Y674134D02*
X1287167Y674107D01*
G01X1287177Y679081D02*
X1287185Y679055D01*
G01X1287167Y679107D02*
X1287177Y679081D01*
G01X1287156Y679134D02*
X1287167Y679107D01*
G01X1287177Y684081D02*
X1287185Y684055D01*
G01X1287167Y684107D02*
X1287177Y684081D01*
G01X1287156Y684134D02*
X1287167Y684107D01*
G01X1287177Y689081D02*
X1287185Y689055D01*
G01X1287167Y689107D02*
X1287177Y689081D01*
G01X1287156Y689134D02*
X1287167Y689107D01*
G01X1287177Y694081D02*
X1287185Y694055D01*
G01X1287167Y694107D02*
X1287177Y694081D01*
G01X1287156Y694134D02*
X1287167Y694107D01*
G01X1287168Y648932D02*
X1287148Y648937D01*
G01X1287182Y648918D02*
X1287168Y648932D01*
G01X1287187Y648898D02*
X1287182Y648918D01*
G01X1287168Y673932D02*
X1287148Y673937D01*
G01X1287182Y673918D02*
X1287168Y673932D01*
G01X1287187Y673898D02*
X1287182Y673918D01*
G01X1287152Y649035D02*
X1287156Y649134D01*
G01X1287146Y648963D02*
X1287152Y649035D01*
G01X1287148Y648937D02*
X1287146Y648963D01*
G01X1287152Y674035D02*
X1287156Y674134D01*
G01X1287146Y673963D02*
X1287152Y674035D01*
G01X1287148Y673937D02*
X1287146Y673963D01*
G01X1287152Y679035D02*
X1287156Y679134D01*
G01X1287146Y678963D02*
X1287152Y679035D01*
G01X1287148Y678937D02*
X1287146Y678963D01*
G01X1287152Y684035D02*
X1287156Y684134D01*
G01X1287146Y683963D02*
X1287152Y684035D01*
G01X1287148Y683937D02*
X1287146Y683963D01*
G01X1287152Y689035D02*
X1287156Y689134D01*
G01X1287146Y688963D02*
X1287152Y689035D01*
G01X1287148Y688937D02*
X1287146Y688963D01*
G01X1287152Y694035D02*
X1287156Y694134D01*
G01X1287146Y693963D02*
X1287152Y694035D01*
G01X1287148Y693937D02*
X1287146Y693963D01*
G01X1286202Y692557D02*
Y692559D01*
G01X1286201Y692552D02*
X1286202Y692557D01*
G01X1286201Y692543D02*
Y692552D01*
G01X1286202Y687557D02*
Y687559D01*
G01X1286201Y687552D02*
X1286202Y687557D01*
G01X1286201Y687543D02*
Y687552D01*
G01X1286202Y682557D02*
Y682559D01*
G01X1286201Y682552D02*
X1286202Y682557D01*
G01X1286201Y682543D02*
Y682552D01*
G01X1286202Y677557D02*
Y677559D01*
G01X1286201Y677552D02*
X1286202Y677557D01*
G01X1286201Y677543D02*
Y677552D01*
G01X1286202Y672557D02*
Y672559D01*
G01X1286201Y672552D02*
X1286202Y672557D01*
G01X1286201Y672543D02*
Y672552D01*
G01X1287185Y692552D02*
Y692543D01*
G01X1287186Y692557D02*
X1287185Y692552D01*
G01X1287188Y692559D02*
X1287186Y692557D01*
G01X1287185Y687552D02*
Y687543D01*
G01X1287186Y687557D02*
X1287185Y687552D01*
G01X1287188Y687559D02*
X1287186Y687557D01*
G01X1287185Y682552D02*
Y682543D01*
G01X1287186Y682557D02*
X1287185Y682552D01*
G01X1287188Y682559D02*
X1287186Y682557D01*
G01X1287185Y677552D02*
Y677543D01*
G01X1287186Y677557D02*
X1287185Y677552D01*
G01X1287188Y677559D02*
X1287186Y677557D01*
G01X1287185Y672552D02*
Y672543D01*
G01X1287186Y672557D02*
X1287185Y672552D01*
G01X1287188Y672559D02*
X1287186Y672557D01*
G01X1287168Y678932D02*
X1287148Y678937D01*
G01X1287182Y678918D02*
X1287168Y678932D01*
G01X1287187Y678898D02*
X1287182Y678918D01*
G01X1287168Y683932D02*
X1287148Y683937D01*
G01X1287182Y683918D02*
X1287168Y683932D01*
G01X1287187Y683898D02*
X1287182Y683918D01*
G01X1287168Y688932D02*
X1287148Y688937D01*
G01X1287182Y688918D02*
X1287168Y688932D01*
G01X1287187Y688898D02*
X1287182Y688918D01*
G01X1287168Y693932D02*
X1287148Y693937D01*
G01X1287182Y693918D02*
X1287168Y693932D01*
G01X1287187Y693898D02*
X1287182Y693918D01*
G01X1286614Y670610D02*
X1287795Y671791D01*
G01X1282677Y670610D02*
X1283858Y671791D01*
G01X1287185Y648911D02*
Y648920D01*
G01Y673911D02*
Y673920D01*
G01Y678911D02*
Y678920D01*
G01Y683911D02*
Y683920D01*
G01Y688911D02*
Y688920D01*
G01Y693911D02*
Y693920D01*
G01X1291535Y692559D02*
Y693937D01*
G01Y687559D02*
Y688937D01*
G01Y682559D02*
Y683937D01*
G01Y677559D02*
Y678937D01*
G01Y672559D02*
Y673937D01*
G01X1288366D02*
Y672559D01*
G01Y678937D02*
Y677559D01*
G01Y683937D02*
Y682559D01*
G01Y688937D02*
Y687559D01*
G01Y693937D02*
Y692559D01*
G01X1287795Y671791D02*
Y649705D01*
G01X1287185Y692067D02*
Y694429D01*
G01Y687067D02*
Y689429D01*
G01Y682067D02*
Y684429D01*
G01Y677067D02*
Y679429D01*
G01Y672067D02*
Y674429D01*
G01X1286614Y670610D02*
Y650886D01*
G01X1286201Y674429D02*
Y672067D01*
G01Y679429D02*
Y677067D01*
G01Y684429D02*
Y682067D01*
G01Y689429D02*
Y687067D01*
G01Y694429D02*
Y692067D01*
G01X1283858Y748248D02*
Y671791D01*
G01X1282677Y747067D02*
Y670610D01*
G01X1286614Y650886D02*
X1287795Y649705D01*
G01X1282677Y650886D02*
X1283858Y649705D01*
G01X1287185Y694429D02*
X1286201D01*
G01X1286202Y693937D02*
X1291535D01*
G01Y693898D02*
X1287187D01*
G01X1291535Y692559D02*
X1286202D01*
G01X1286201Y692067D02*
X1287185D01*
G01Y689429D02*
X1286201D01*
G01X1286202Y688937D02*
X1291535D01*
G01Y688898D02*
X1287187D01*
G01X1291535Y687559D02*
X1286202D01*
G01X1286201Y687067D02*
X1287185D01*
G01Y684429D02*
X1286201D01*
G01X1286202Y683937D02*
X1291535D01*
G01Y683898D02*
X1287187D01*
G01X1291535Y682559D02*
X1286202D01*
G01X1286201Y682067D02*
X1287185D01*
G01Y679429D02*
X1286201D01*
G01X1286202Y678937D02*
X1291535D01*
G01Y678898D02*
X1287187D01*
G01X1291535Y677559D02*
X1286202D01*
G01X1286201Y677067D02*
X1287185D01*
G01Y674429D02*
X1286201D01*
G01X1286202Y673937D02*
X1291535D01*
G01Y673898D02*
X1287187D01*
G01X1291535Y672559D02*
X1286202D01*
G01X1286201Y672067D02*
X1287185D01*
G01X1283858Y671791D02*
X1287795D01*
G01X1282677Y670610D02*
X1286614D01*
G01Y650886D02*
X1282677D01*
G01X1287795Y649705D02*
X1283858D01*
G01X1287185Y649429D02*
X1286201D01*
G01X1286202Y648937D02*
X1291535D01*
G01Y648898D02*
X1287187D01*
G01X1286201Y694133D02*
X1287156Y694134D01*
G01X1287185Y692363D02*
X1286201Y692362D01*
G01Y689133D02*
X1287156Y689134D01*
G01X1287185Y687363D02*
X1286201Y687362D01*
G01Y684133D02*
X1287156Y684134D01*
G01X1287185Y682363D02*
X1286201Y682362D01*
G01Y679133D02*
X1287156Y679134D01*
G01X1287185Y677363D02*
X1286201Y677362D01*
G01Y674133D02*
X1287156Y674134D01*
G01X1287185Y672363D02*
X1286201Y672362D01*
G01Y649133D02*
X1287156Y649134D01*
G01X1287172Y698929D02*
X1287183Y698913D01*
G01X1287148Y698937D02*
X1287172Y698929D01*
G01Y703929D02*
X1287183Y703913D01*
G01X1287148Y703937D02*
X1287172Y703929D01*
G01Y708929D02*
X1287183Y708913D01*
G01X1287148Y708937D02*
X1287172Y708929D01*
G01Y713929D02*
X1287183Y713913D01*
G01X1287148Y713937D02*
X1287172Y713929D01*
G01Y718929D02*
X1287183Y718913D01*
G01X1287148Y718937D02*
X1287172Y718929D01*
G01Y723929D02*
X1287183Y723913D01*
G01X1287148Y723937D02*
X1287172Y723929D01*
G01Y728929D02*
X1287183Y728913D01*
G01X1287148Y728937D02*
X1287172Y728929D01*
G01Y733929D02*
X1287183Y733913D01*
G01X1287148Y733937D02*
X1287172Y733929D01*
G01Y738929D02*
X1287183Y738913D01*
G01X1287148Y738937D02*
X1287172Y738929D01*
G01Y743929D02*
X1287183Y743913D01*
G01X1287148Y743937D02*
X1287172Y743929D01*
G01X1287185Y742552D02*
Y742543D01*
G01X1287186Y742557D02*
X1287185Y742552D01*
G01X1287188Y742559D02*
X1287186Y742557D01*
G01X1287185Y737552D02*
Y737543D01*
G01X1287186Y737557D02*
X1287185Y737552D01*
G01X1287188Y737559D02*
X1287186Y737557D01*
G01X1287185Y732552D02*
Y732543D01*
G01X1287186Y732557D02*
X1287185Y732552D01*
G01X1287188Y732559D02*
X1287186Y732557D01*
G01X1287185Y698904D02*
Y698911D01*
G01X1287186Y698900D02*
X1287185Y698904D01*
G01X1287187Y698898D02*
X1287186Y698900D01*
G01X1287185Y703904D02*
Y703911D01*
G01X1287186Y703900D02*
X1287185Y703904D01*
G01X1287187Y703898D02*
X1287186Y703900D01*
G01X1287185Y708904D02*
Y708911D01*
G01X1287186Y708900D02*
X1287185Y708904D01*
G01X1287187Y708898D02*
X1287186Y708900D01*
G01X1287185Y713904D02*
Y713911D01*
G01X1287186Y713900D02*
X1287185Y713904D01*
G01X1287187Y713898D02*
X1287186Y713900D01*
G01X1287185Y718904D02*
Y718911D01*
G01X1287186Y718900D02*
X1287185Y718904D01*
G01X1287187Y718898D02*
X1287186Y718900D01*
G01X1287185Y723904D02*
Y723911D01*
G01X1287186Y723900D02*
X1287185Y723904D01*
G01X1287187Y723898D02*
X1287186Y723900D01*
G01X1287185Y728904D02*
Y728911D01*
G01X1287186Y728900D02*
X1287185Y728904D01*
G01X1287187Y728898D02*
X1287186Y728900D01*
G01X1287185Y733904D02*
Y733911D01*
G01X1287186Y733900D02*
X1287185Y733904D01*
G01X1287187Y733898D02*
X1287186Y733900D01*
G01X1287185Y738904D02*
Y738911D01*
G01X1287186Y738900D02*
X1287185Y738904D01*
G01X1287187Y738898D02*
X1287186Y738900D01*
G01X1287185Y743904D02*
Y743911D01*
G01X1287186Y743900D02*
X1287185Y743904D01*
G01X1287187Y743898D02*
X1287186Y743900D01*
G01X1286201Y698944D02*
Y698954D01*
G01X1286202Y698939D02*
X1286201Y698944D01*
G01X1286202Y698937D02*
Y698939D01*
G01X1286201Y703944D02*
Y703954D01*
G01X1286202Y703939D02*
X1286201Y703944D01*
G01X1286202Y703937D02*
Y703939D01*
G01X1286201Y708944D02*
Y708954D01*
G01X1286202Y708939D02*
X1286201Y708944D01*
G01X1286202Y708937D02*
Y708939D01*
G01X1286201Y713944D02*
Y713954D01*
G01X1286202Y713939D02*
X1286201Y713944D01*
G01X1286202Y713937D02*
Y713939D01*
G01X1286201Y718944D02*
Y718954D01*
G01X1286202Y718939D02*
X1286201Y718944D01*
G01X1286202Y718937D02*
Y718939D01*
G01X1286201Y723944D02*
Y723954D01*
G01X1286202Y723939D02*
X1286201Y723944D01*
G01X1286202Y723937D02*
Y723939D01*
G01X1286201Y728944D02*
Y728954D01*
G01X1286202Y728939D02*
X1286201Y728944D01*
G01X1286202Y728937D02*
Y728939D01*
G01X1286201Y733944D02*
Y733954D01*
G01X1286202Y733939D02*
X1286201Y733944D01*
G01X1286202Y733937D02*
Y733939D01*
G01X1286201Y738944D02*
Y738954D01*
G01X1286202Y738939D02*
X1286201Y738944D01*
G01X1286202Y738937D02*
Y738939D01*
G01X1286201Y743944D02*
Y743954D01*
G01X1286202Y743939D02*
X1286201Y743944D01*
G01X1286202Y743937D02*
Y743939D01*
G01X1287177Y699081D02*
X1287185Y699055D01*
G01X1287167Y699107D02*
X1287177Y699081D01*
G01X1287156Y699134D02*
X1287167Y699107D01*
G01X1287177Y704081D02*
X1287185Y704055D01*
G01X1287167Y704107D02*
X1287177Y704081D01*
G01X1287156Y704134D02*
X1287167Y704107D01*
G01X1287177Y709081D02*
X1287185Y709055D01*
G01X1287167Y709107D02*
X1287177Y709081D01*
G01X1287156Y709134D02*
X1287167Y709107D01*
G01X1287177Y714081D02*
X1287185Y714055D01*
G01X1287167Y714107D02*
X1287177Y714081D01*
G01X1287156Y714134D02*
X1287167Y714107D01*
G01X1287177Y719081D02*
X1287185Y719055D01*
G01X1287167Y719107D02*
X1287177Y719081D01*
G01X1287156Y719134D02*
X1287167Y719107D01*
G01X1287177Y724081D02*
X1287185Y724055D01*
G01X1287167Y724107D02*
X1287177Y724081D01*
G01X1287156Y724134D02*
X1287167Y724107D01*
G01X1287177Y729081D02*
X1287185Y729055D01*
G01X1287167Y729107D02*
X1287177Y729081D01*
G01X1287156Y729134D02*
X1287167Y729107D01*
G01X1287177Y734081D02*
X1287185Y734055D01*
G01X1287167Y734107D02*
X1287177Y734081D01*
G01X1287156Y734134D02*
X1287167Y734107D01*
G01X1287177Y739081D02*
X1287185Y739055D01*
G01X1287167Y739107D02*
X1287177Y739081D01*
G01X1287156Y739134D02*
X1287167Y739107D01*
G01X1287177Y744081D02*
X1287185Y744055D01*
G01X1287167Y744107D02*
X1287177Y744081D01*
G01X1287156Y744134D02*
X1287167Y744107D01*
G01X1287152Y699035D02*
X1287156Y699134D01*
G01X1287146Y698963D02*
X1287152Y699035D01*
G01X1287148Y698937D02*
X1287146Y698963D01*
G01X1287152Y704035D02*
X1287156Y704134D01*
G01X1287146Y703963D02*
X1287152Y704035D01*
G01X1287148Y703937D02*
X1287146Y703963D01*
G01X1287152Y709035D02*
X1287156Y709134D01*
G01X1287146Y708963D02*
X1287152Y709035D01*
G01X1287148Y708937D02*
X1287146Y708963D01*
G01X1287152Y714035D02*
X1287156Y714134D01*
G01X1287146Y713963D02*
X1287152Y714035D01*
G01X1287148Y713937D02*
X1287146Y713963D01*
G01X1287152Y719035D02*
X1287156Y719134D01*
G01X1287146Y718963D02*
X1287152Y719035D01*
G01X1287148Y718937D02*
X1287146Y718963D01*
G01X1287152Y724035D02*
X1287156Y724134D01*
G01X1287146Y723963D02*
X1287152Y724035D01*
G01X1287148Y723937D02*
X1287146Y723963D01*
G01X1287152Y729035D02*
X1287156Y729134D01*
G01X1287146Y728963D02*
X1287152Y729035D01*
G01X1287148Y728937D02*
X1287146Y728963D01*
G01X1287152Y734035D02*
X1287156Y734134D01*
G01X1287146Y733963D02*
X1287152Y734035D01*
G01X1287148Y733937D02*
X1287146Y733963D01*
G01X1287152Y739035D02*
X1287156Y739134D01*
G01X1287146Y738963D02*
X1287152Y739035D01*
G01X1287148Y738937D02*
X1287146Y738963D01*
G01X1287152Y744035D02*
X1287156Y744134D01*
G01X1287146Y743963D02*
X1287152Y744035D01*
G01X1287148Y743937D02*
X1287146Y743963D01*
G01X1286202Y742557D02*
Y742559D01*
G01X1286201Y742552D02*
X1286202Y742557D01*
G01X1286201Y742543D02*
Y742552D01*
G01X1286202Y737557D02*
Y737559D01*
G01X1286201Y737552D02*
X1286202Y737557D01*
G01X1286201Y737543D02*
Y737552D01*
G01X1286202Y732557D02*
Y732559D01*
G01X1286201Y732552D02*
X1286202Y732557D01*
G01X1286201Y732543D02*
Y732552D01*
G01X1286202Y727557D02*
Y727559D01*
G01X1286201Y727552D02*
X1286202Y727557D01*
G01X1286201Y727543D02*
Y727552D01*
G01X1286202Y722557D02*
Y722559D01*
G01X1286201Y722552D02*
X1286202Y722557D01*
G01X1286201Y722543D02*
Y722552D01*
G01X1286202Y717557D02*
Y717559D01*
G01X1286201Y717552D02*
X1286202Y717557D01*
G01X1286201Y717543D02*
Y717552D01*
G01X1286202Y712557D02*
Y712559D01*
G01X1286201Y712552D02*
X1286202Y712557D01*
G01X1286201Y712543D02*
Y712552D01*
G01X1286202Y707557D02*
Y707559D01*
G01X1286201Y707552D02*
X1286202Y707557D01*
G01X1286201Y707543D02*
Y707552D01*
G01X1286202Y702557D02*
Y702559D01*
G01X1286201Y702552D02*
X1286202Y702557D01*
G01X1286201Y702543D02*
Y702552D01*
G01X1286202Y697557D02*
Y697559D01*
G01X1286201Y697552D02*
X1286202Y697557D01*
G01X1286201Y697543D02*
Y697552D01*
G01X1287185Y727552D02*
Y727543D01*
G01X1287186Y727557D02*
X1287185Y727552D01*
G01X1287188Y727559D02*
X1287186Y727557D01*
G01X1287185Y722552D02*
Y722543D01*
G01X1287186Y722557D02*
X1287185Y722552D01*
G01X1287188Y722559D02*
X1287186Y722557D01*
G01X1287185Y717552D02*
Y717543D01*
G01X1287186Y717557D02*
X1287185Y717552D01*
G01X1287188Y717559D02*
X1287186Y717557D01*
G01X1287185Y712552D02*
Y712543D01*
G01X1287186Y712557D02*
X1287185Y712552D01*
G01X1287188Y712559D02*
X1287186Y712557D01*
G01X1287185Y707552D02*
Y707543D01*
G01X1287186Y707557D02*
X1287185Y707552D01*
G01X1287188Y707559D02*
X1287186Y707557D01*
G01X1287185Y702552D02*
Y702543D01*
G01X1287186Y702557D02*
X1287185Y702552D01*
G01X1287188Y702559D02*
X1287186Y702557D01*
G01X1287185Y697552D02*
Y697543D01*
G01X1287186Y697557D02*
X1287185Y697552D01*
G01X1287188Y697559D02*
X1287186Y697557D01*
G01X1287168Y698932D02*
X1287148Y698937D01*
G01X1287182Y698918D02*
X1287168Y698932D01*
G01X1287187Y698898D02*
X1287182Y698918D01*
G01X1287168Y703932D02*
X1287148Y703937D01*
G01X1287182Y703918D02*
X1287168Y703932D01*
G01X1287187Y703898D02*
X1287182Y703918D01*
G01X1287168Y708932D02*
X1287148Y708937D01*
G01X1287182Y708918D02*
X1287168Y708932D01*
G01X1287187Y708898D02*
X1287182Y708918D01*
G01X1287168Y713932D02*
X1287148Y713937D01*
G01X1287182Y713918D02*
X1287168Y713932D01*
G01X1287187Y713898D02*
X1287182Y713918D01*
G01X1287168Y718932D02*
X1287148Y718937D01*
G01X1287182Y718918D02*
X1287168Y718932D01*
G01X1287187Y718898D02*
X1287182Y718918D01*
G01X1287168Y723932D02*
X1287148Y723937D01*
G01X1287182Y723918D02*
X1287168Y723932D01*
G01X1287187Y723898D02*
X1287182Y723918D01*
G01X1287168Y728932D02*
X1287148Y728937D01*
G01X1287182Y728918D02*
X1287168Y728932D01*
G01X1287187Y728898D02*
X1287182Y728918D01*
G01X1287168Y733932D02*
X1287148Y733937D01*
G01X1287182Y733918D02*
X1287168Y733932D01*
G01X1287187Y733898D02*
X1287182Y733918D01*
G01X1287168Y738932D02*
X1287148Y738937D01*
G01X1287182Y738918D02*
X1287168Y738932D01*
G01X1287187Y738898D02*
X1287182Y738918D01*
G01X1287168Y743932D02*
X1287148Y743937D01*
G01X1287182Y743918D02*
X1287168Y743932D01*
G01X1287187Y743898D02*
X1287182Y743918D01*
G01X1287185Y698911D02*
Y698920D01*
G01Y703911D02*
Y703920D01*
G01Y708911D02*
Y708920D01*
G01Y713911D02*
Y713920D01*
G01Y718911D02*
Y718920D01*
G01Y723911D02*
Y723920D01*
G01Y728911D02*
Y728920D01*
G01Y733911D02*
Y733920D01*
G01Y738911D02*
Y738920D01*
G01Y743911D02*
Y743920D01*
G01X1291535Y742559D02*
Y743937D01*
G01Y737559D02*
Y738937D01*
G01Y732559D02*
Y733937D01*
G01Y727559D02*
Y728937D01*
G01Y722559D02*
Y723937D01*
G01Y717559D02*
Y718937D01*
G01Y712559D02*
Y713937D01*
G01Y707559D02*
Y708937D01*
G01Y702559D02*
Y703937D01*
G01Y697559D02*
Y698937D01*
G01X1288366D02*
Y697559D01*
G01Y703937D02*
Y702559D01*
G01Y708937D02*
Y707559D01*
G01Y713937D02*
Y712559D01*
G01Y718937D02*
Y717559D01*
G01Y723937D02*
Y722559D01*
G01Y728937D02*
Y727559D01*
G01Y733937D02*
Y732559D01*
G01Y738937D02*
Y737559D01*
G01Y743937D02*
Y742559D01*
G01X1287185Y742067D02*
Y744429D01*
G01Y737067D02*
Y739429D01*
G01Y732067D02*
Y734429D01*
G01Y727067D02*
Y729429D01*
G01Y722067D02*
Y724429D01*
G01Y717067D02*
Y719429D01*
G01Y712067D02*
Y714429D01*
G01Y707067D02*
Y709429D01*
G01Y702067D02*
Y704429D01*
G01Y697067D02*
Y699429D01*
G01X1286201D02*
Y697067D01*
G01Y704429D02*
Y702067D01*
G01Y709429D02*
Y707067D01*
G01Y714429D02*
Y712067D01*
G01Y719429D02*
Y717067D01*
G01Y724429D02*
Y722067D01*
G01Y729429D02*
Y727067D01*
G01Y734429D02*
Y732067D01*
G01Y739429D02*
Y737067D01*
G01Y744429D02*
Y742067D01*
G01X1287185Y744429D02*
X1286201D01*
G01X1286202Y743937D02*
X1291535D01*
G01Y743898D02*
X1287187D01*
G01X1291535Y742559D02*
X1286202D01*
G01X1286201Y742067D02*
X1287185D01*
G01Y739429D02*
X1286201D01*
G01X1286202Y738937D02*
X1291535D01*
G01Y738898D02*
X1287187D01*
G01X1291535Y737559D02*
X1286202D01*
G01X1286201Y737067D02*
X1287185D01*
G01Y734429D02*
X1286201D01*
G01X1286202Y733937D02*
X1291535D01*
G01Y733898D02*
X1287187D01*
G01X1291535Y732559D02*
X1286202D01*
G01X1286201Y732067D02*
X1287185D01*
G01Y729429D02*
X1286201D01*
G01X1286202Y728937D02*
X1291535D01*
G01Y728898D02*
X1287187D01*
G01X1291535Y727559D02*
X1286202D01*
G01X1286201Y727067D02*
X1287185D01*
G01Y724429D02*
X1286201D01*
G01X1286202Y723937D02*
X1291535D01*
G01Y723898D02*
X1287187D01*
G01X1291535Y722559D02*
X1286202D01*
G01X1286201Y722067D02*
X1287185D01*
G01Y719429D02*
X1286201D01*
G01X1286202Y718937D02*
X1291535D01*
G01Y718898D02*
X1287187D01*
G01X1291535Y717559D02*
X1286202D01*
G01X1286201Y717067D02*
X1287185D01*
G01Y714429D02*
X1286201D01*
G01X1286202Y713937D02*
X1291535D01*
G01Y713898D02*
X1287187D01*
G01X1291535Y712559D02*
X1286202D01*
G01X1286201Y712067D02*
X1287185D01*
G01Y709429D02*
X1286201D01*
G01X1286202Y708937D02*
X1291535D01*
G01Y708898D02*
X1287187D01*
G01X1291535Y707559D02*
X1286202D01*
G01X1286201Y707067D02*
X1287185D01*
G01X1286201Y744133D02*
X1287156Y744134D01*
G01X1287185Y742363D02*
X1286201Y742362D01*
G01Y739133D02*
X1287156Y739134D01*
G01X1287185Y737363D02*
X1286201Y737362D01*
G01Y734133D02*
X1287156Y734134D01*
G01X1287185Y732363D02*
X1286201Y732362D01*
G01Y729133D02*
X1287156Y729134D01*
G01X1287185Y727363D02*
X1286201Y727362D01*
G01Y724133D02*
X1287156Y724134D01*
G01X1287185Y722363D02*
X1286201Y722362D01*
G01Y719133D02*
X1287156Y719134D01*
G01X1287185Y717363D02*
X1286201Y717362D01*
G01Y714133D02*
X1287156Y714134D01*
G01X1287185Y712363D02*
X1286201Y712362D01*
G01Y709133D02*
X1287156Y709134D01*
G01X1287185Y707363D02*
X1286201Y707362D01*
G01X1287185Y704429D02*
X1286201D01*
G01X1286202Y703937D02*
X1291535D01*
G01Y703898D02*
X1287187D01*
G01X1291535Y702559D02*
X1286202D01*
G01X1286201Y702067D02*
X1287185D01*
G01Y699429D02*
X1286201D01*
G01X1286202Y698937D02*
X1291535D01*
G01Y698898D02*
X1287187D01*
G01X1291535Y697559D02*
X1286202D01*
G01X1286201Y697067D02*
X1287185D01*
G01X1286201Y704133D02*
X1287156Y704134D01*
G01X1287185Y702363D02*
X1286201Y702362D01*
G01Y699133D02*
X1287156Y699134D01*
G01X1287185Y697363D02*
X1286201Y697362D01*
G01X1285630Y769429D02*
G03X1285039Y770020I-591J0D01*
G01X1282874Y766280D02*
G03Y768248I0J984D01*
G01X1292520Y768839D02*
G03X1290551Y770807I-1969J-1D01*
G01X1285433Y759154D02*
G03X1284252Y760335I-1181J0D01*
G01X1285184Y759879D02*
X1282874Y755650D01*
G01X1292520Y753091D02*
Y768839D01*
G01X1285630Y763327D02*
Y769429D01*
G01X1285433Y759154D02*
Y750610D01*
G01X1282874Y755650D02*
Y753957D01*
G01D02*
X1284178Y751988D01*
G01X1292520Y753091D02*
X1289173Y749744D01*
G01X1282677Y747067D02*
X1283858Y748248D01*
G01X1288583Y750610D02*
X1285433D01*
G01X1311851Y844772D02*
G03X1318775Y831641I37663J11469D01*
G01X1284965D02*
G03X1291890Y844772I-30737J24602D01*
G01X1311850D02*
G03X1318776Y831641I37662J11473D01*
G01X1284965D02*
G03X1291890Y844772I-30737J24602D01*
G01X1311851D02*
G03X1291890I-9980J-3039D01*
G01X1311850D02*
G03X1291890I-9980J-3040D01*
G01X1287185Y1080308D02*
Y1080299D01*
G01X1287186Y1080313D02*
X1287185Y1080308D01*
G01X1287188Y1080315D02*
X1287186Y1080313D01*
G01X1287185Y1075308D02*
Y1075299D01*
G01X1287186Y1075313D02*
X1287185Y1075308D01*
G01X1287188Y1075315D02*
X1287186Y1075313D01*
G01X1287185Y1070308D02*
Y1070299D01*
G01X1287186Y1070313D02*
X1287185Y1070308D01*
G01X1287188Y1070315D02*
X1287186Y1070313D01*
G01X1287152Y1071791D02*
X1287156Y1071890D01*
G01X1287146Y1071719D02*
X1287152Y1071791D01*
G01X1287148Y1071693D02*
X1287146Y1071719D01*
G01X1287152Y1076791D02*
X1287156Y1076890D01*
G01X1287146Y1076719D02*
X1287152Y1076791D01*
G01X1287148Y1076693D02*
X1287146Y1076719D01*
G01X1287152Y1081791D02*
X1287156Y1081890D01*
G01X1287146Y1081719D02*
X1287152Y1081791D01*
G01X1287148Y1081693D02*
X1287146Y1081719D01*
G01X1286202Y1080313D02*
Y1080315D01*
G01X1286201Y1080308D02*
X1286202Y1080313D01*
G01X1286201Y1080299D02*
Y1080308D01*
G01X1286202Y1075313D02*
Y1075315D01*
G01X1286201Y1075308D02*
X1286202Y1075313D01*
G01X1286201Y1075299D02*
Y1075308D01*
G01X1286202Y1070313D02*
Y1070315D01*
G01X1286201Y1070308D02*
X1286202Y1070313D01*
G01X1286201Y1070299D02*
Y1070308D01*
G01X1287172Y1071685D02*
X1287183Y1071669D01*
G01X1287148Y1071693D02*
X1287172Y1071685D01*
G01Y1076685D02*
X1287183Y1076669D01*
G01X1287148Y1076693D02*
X1287172Y1076685D01*
G01Y1081685D02*
X1287183Y1081669D01*
G01X1287148Y1081693D02*
X1287172Y1081685D01*
G01X1287185Y1071660D02*
Y1071667D01*
G01X1287186Y1071656D02*
X1287185Y1071660D01*
G01X1287187Y1071654D02*
X1287186Y1071656D01*
G01X1287185Y1076660D02*
Y1076667D01*
G01X1287186Y1076656D02*
X1287185Y1076660D01*
G01X1287187Y1076654D02*
X1287186Y1076656D01*
G01X1287185Y1081660D02*
Y1081667D01*
G01X1287186Y1081656D02*
X1287185Y1081660D01*
G01X1287187Y1081654D02*
X1287186Y1081656D01*
G01X1286201Y1071700D02*
Y1071709D01*
G01X1286202Y1071695D02*
X1286201Y1071700D01*
G01X1286202Y1071693D02*
Y1071695D01*
G01X1286201Y1076700D02*
Y1076709D01*
G01X1286202Y1076695D02*
X1286201Y1076700D01*
G01X1286202Y1076693D02*
Y1076695D01*
G01X1286201Y1081700D02*
Y1081709D01*
G01X1286202Y1081695D02*
X1286201Y1081700D01*
G01X1286202Y1081693D02*
Y1081695D01*
G01X1287177Y1071837D02*
X1287185Y1071811D01*
G01X1287167Y1071863D02*
X1287177Y1071837D01*
G01X1287156Y1071890D02*
X1287167Y1071863D01*
G01X1287177Y1076837D02*
X1287185Y1076811D01*
G01X1287167Y1076863D02*
X1287177Y1076837D01*
G01X1287156Y1076890D02*
X1287167Y1076863D01*
G01X1287177Y1081837D02*
X1287185Y1081811D01*
G01X1287167Y1081863D02*
X1287177Y1081837D01*
G01X1287156Y1081890D02*
X1287167Y1081863D01*
G01X1287168Y1071688D02*
X1287148Y1071693D01*
G01X1287182Y1071674D02*
X1287168Y1071688D01*
G01X1287187Y1071654D02*
X1287182Y1071674D01*
G01X1287168Y1076688D02*
X1287148Y1076693D01*
G01X1287182Y1076674D02*
X1287168Y1076688D01*
G01X1287187Y1076654D02*
X1287182Y1076674D01*
G01X1287168Y1081688D02*
X1287148Y1081693D01*
G01X1287182Y1081674D02*
X1287168Y1081688D01*
G01X1287187Y1081654D02*
X1287182Y1081674D01*
G01X1285039Y1044232D02*
G03X1285630Y1044823I0J591D01*
G01X1282874Y1046004D02*
G03Y1047972I0J984D01*
G01X1284252Y1053917D02*
G03X1285433Y1055098I0J1181D01*
G01X1290551Y1043445D02*
G03X1292520Y1045413I0J1969D01*
G01X1282874Y1058602D02*
X1285184Y1054373D01*
G01X1289173Y1064508D02*
X1292520Y1061161D01*
G01X1282677Y1067185D02*
X1283858Y1066004D01*
G01X1287185Y1082185D02*
X1286201D01*
G01X1286202Y1081693D02*
X1291535D01*
G01Y1081654D02*
X1287187D01*
G01X1291535Y1080315D02*
X1286202D01*
G01X1286201Y1079823D02*
X1287185D01*
G01Y1077185D02*
X1286201D01*
G01X1286202Y1076693D02*
X1291535D01*
G01Y1076654D02*
X1287187D01*
G01X1291535Y1075315D02*
X1286202D01*
G01X1286201Y1074823D02*
X1287185D01*
G01Y1072185D02*
X1286201D01*
G01X1286202Y1071693D02*
X1291535D01*
G01Y1071654D02*
X1287187D01*
G01X1291535Y1070315D02*
X1286202D01*
G01X1286201Y1069823D02*
X1287185D01*
G01X1286201Y1081889D02*
X1287156Y1081890D01*
G01X1287185Y1080119D02*
X1286201Y1080118D01*
G01Y1076889D02*
X1287156Y1076890D01*
G01X1287185Y1075119D02*
X1286201Y1075118D01*
G01Y1071889D02*
X1287156Y1071890D01*
G01X1287185Y1070119D02*
X1286201Y1070118D01*
G01X1287185Y1071667D02*
Y1071676D01*
G01Y1076667D02*
Y1076676D01*
G01Y1081667D02*
Y1081676D01*
G01X1292520Y1045413D02*
Y1061161D01*
G01X1291535Y1080315D02*
Y1081693D01*
G01Y1075315D02*
Y1076693D01*
G01Y1070315D02*
Y1071693D01*
G01X1289173Y1202500D02*
Y1064508D01*
G01X1288583Y1204744D02*
Y1062264D01*
G01X1288366Y1071693D02*
Y1070315D01*
G01Y1076693D02*
Y1075315D01*
G01Y1081693D02*
Y1080315D01*
G01X1287185Y1079823D02*
Y1082185D01*
G01Y1074823D02*
Y1077185D01*
G01Y1069823D02*
Y1072185D01*
G01Y1071667D02*
Y1071811D01*
G01Y1076667D02*
Y1076811D01*
G01Y1081667D02*
Y1081811D01*
G01X1286201Y1072185D02*
Y1069823D01*
G01Y1077185D02*
Y1074823D01*
G01Y1082185D02*
Y1079823D01*
G01X1285630Y1050925D02*
Y1044823D01*
G01X1285433Y1063642D02*
Y1055098D01*
G01X1283858Y1102461D02*
Y1066004D01*
G01X1282874Y1060295D02*
Y1058602D01*
G01X1282677Y1103642D02*
Y1067185D01*
G01X1285433Y1063642D02*
X1288583D01*
G01X1284178Y1062264D02*
X1282874Y1060295D01*
G01X1287185Y1130308D02*
Y1130299D01*
G01X1287186Y1130313D02*
X1287185Y1130308D01*
G01X1287188Y1130315D02*
X1287186Y1130313D01*
G01X1287185Y1125308D02*
Y1125299D01*
G01X1287186Y1125313D02*
X1287185Y1125308D01*
G01X1287188Y1125315D02*
X1287186Y1125313D01*
G01X1287185Y1100308D02*
Y1100299D01*
G01X1287186Y1100313D02*
X1287185Y1100308D01*
G01X1287188Y1100315D02*
X1287186Y1100313D01*
G01X1287185Y1095308D02*
Y1095299D01*
G01X1287186Y1095313D02*
X1287185Y1095308D01*
G01X1287188Y1095315D02*
X1287186Y1095313D01*
G01X1287185Y1090308D02*
Y1090299D01*
G01X1287186Y1090313D02*
X1287185Y1090308D01*
G01X1287188Y1090315D02*
X1287186Y1090313D01*
G01X1287185Y1085308D02*
Y1085299D01*
G01X1287186Y1085313D02*
X1287185Y1085308D01*
G01X1287188Y1085315D02*
X1287186Y1085313D01*
G01X1287152Y1086791D02*
X1287156Y1086890D01*
G01X1287146Y1086719D02*
X1287152Y1086791D01*
G01X1287148Y1086693D02*
X1287146Y1086719D01*
G01X1287152Y1091791D02*
X1287156Y1091890D01*
G01X1287146Y1091719D02*
X1287152Y1091791D01*
G01X1287148Y1091693D02*
X1287146Y1091719D01*
G01X1287152Y1096791D02*
X1287156Y1096890D01*
G01X1287146Y1096719D02*
X1287152Y1096791D01*
G01X1287148Y1096693D02*
X1287146Y1096719D01*
G01X1287152Y1101791D02*
X1287156Y1101890D01*
G01X1287146Y1101719D02*
X1287152Y1101791D01*
G01X1287148Y1101693D02*
X1287146Y1101719D01*
G01X1287152Y1126791D02*
X1287156Y1126890D01*
G01X1287146Y1126719D02*
X1287152Y1126791D01*
G01X1287148Y1126693D02*
X1287146Y1126719D01*
G01X1286202Y1130313D02*
Y1130315D01*
G01X1286201Y1130308D02*
X1286202Y1130313D01*
G01X1286201Y1130299D02*
Y1130308D01*
G01X1286202Y1125313D02*
Y1125315D01*
G01X1286201Y1125308D02*
X1286202Y1125313D01*
G01X1286201Y1125299D02*
Y1125308D01*
G01X1286202Y1100313D02*
Y1100315D01*
G01X1286201Y1100308D02*
X1286202Y1100313D01*
G01X1286201Y1100299D02*
Y1100308D01*
G01X1286202Y1095313D02*
Y1095315D01*
G01X1286201Y1095308D02*
X1286202Y1095313D01*
G01X1286201Y1095299D02*
Y1095308D01*
G01X1286202Y1090313D02*
Y1090315D01*
G01X1286201Y1090308D02*
X1286202Y1090313D01*
G01X1286201Y1090299D02*
Y1090308D01*
G01X1286202Y1085313D02*
Y1085315D01*
G01X1286201Y1085308D02*
X1286202Y1085313D01*
G01X1286201Y1085299D02*
Y1085308D01*
G01X1287172Y1086685D02*
X1287183Y1086669D01*
G01X1287148Y1086693D02*
X1287172Y1086685D01*
G01Y1091685D02*
X1287183Y1091669D01*
G01X1287148Y1091693D02*
X1287172Y1091685D01*
G01Y1096685D02*
X1287183Y1096669D01*
G01X1287148Y1096693D02*
X1287172Y1096685D01*
G01Y1101685D02*
X1287183Y1101669D01*
G01X1287148Y1101693D02*
X1287172Y1101685D01*
G01Y1126685D02*
X1287183Y1126669D01*
G01X1287148Y1126693D02*
X1287172Y1126685D01*
G01X1287185Y1086660D02*
Y1086667D01*
G01X1287186Y1086656D02*
X1287185Y1086660D01*
G01X1287187Y1086654D02*
X1287186Y1086656D01*
G01X1287185Y1091660D02*
Y1091667D01*
G01X1287186Y1091656D02*
X1287185Y1091660D01*
G01X1287187Y1091654D02*
X1287186Y1091656D01*
G01X1287185Y1096660D02*
Y1096667D01*
G01X1287186Y1096656D02*
X1287185Y1096660D01*
G01X1287187Y1096654D02*
X1287186Y1096656D01*
G01X1287185Y1101660D02*
Y1101667D01*
G01X1287186Y1101656D02*
X1287185Y1101660D01*
G01X1287187Y1101654D02*
X1287186Y1101656D01*
G01X1286201Y1086700D02*
Y1086709D01*
G01X1286202Y1086695D02*
X1286201Y1086700D01*
G01X1286202Y1086693D02*
Y1086695D01*
G01X1286201Y1091700D02*
Y1091709D01*
G01X1286202Y1091695D02*
X1286201Y1091700D01*
G01X1286202Y1091693D02*
Y1091695D01*
G01X1286201Y1096700D02*
Y1096709D01*
G01X1286202Y1096695D02*
X1286201Y1096700D01*
G01X1286202Y1096693D02*
Y1096695D01*
G01X1286201Y1101700D02*
Y1101709D01*
G01X1286202Y1101695D02*
X1286201Y1101700D01*
G01X1286202Y1101693D02*
Y1101695D01*
G01X1286201Y1126700D02*
Y1126709D01*
G01X1286202Y1126695D02*
X1286201Y1126700D01*
G01X1286202Y1126693D02*
Y1126695D01*
G01X1287177Y1086837D02*
X1287185Y1086811D01*
G01X1287167Y1086863D02*
X1287177Y1086837D01*
G01X1287156Y1086890D02*
X1287167Y1086863D01*
G01X1287177Y1091837D02*
X1287185Y1091811D01*
G01X1287167Y1091863D02*
X1287177Y1091837D01*
G01X1287156Y1091890D02*
X1287167Y1091863D01*
G01X1287177Y1096837D02*
X1287185Y1096811D01*
G01X1287167Y1096863D02*
X1287177Y1096837D01*
G01X1287156Y1096890D02*
X1287167Y1096863D01*
G01X1287177Y1101837D02*
X1287185Y1101811D01*
G01X1287167Y1101863D02*
X1287177Y1101837D01*
G01X1287156Y1101890D02*
X1287167Y1101863D01*
G01X1287177Y1126837D02*
X1287185Y1126811D01*
G01X1287167Y1126863D02*
X1287177Y1126837D01*
G01X1287156Y1126890D02*
X1287167Y1126863D01*
G01X1287168Y1086688D02*
X1287148Y1086693D01*
G01X1287182Y1086674D02*
X1287168Y1086688D01*
G01X1287187Y1086654D02*
X1287182Y1086674D01*
G01X1287168Y1091688D02*
X1287148Y1091693D01*
G01X1287182Y1091674D02*
X1287168Y1091688D01*
G01X1287187Y1091654D02*
X1287182Y1091674D01*
G01X1287168Y1096688D02*
X1287148Y1096693D01*
G01X1287182Y1096674D02*
X1287168Y1096688D01*
G01X1287187Y1096654D02*
X1287182Y1096674D01*
G01X1287168Y1101688D02*
X1287148Y1101693D01*
G01X1287182Y1101674D02*
X1287168Y1101688D01*
G01X1287187Y1101654D02*
X1287182Y1101674D01*
G01X1287168Y1126688D02*
X1287148Y1126693D01*
G01X1287182Y1126674D02*
X1287168Y1126688D01*
G01X1287187Y1126654D02*
X1287182Y1126674D01*
G01X1287185Y1126660D02*
Y1126667D01*
G01X1287186Y1126656D02*
X1287185Y1126660D01*
G01X1287187Y1126654D02*
X1287186Y1126656D01*
G01X1286614Y1103642D02*
X1287795Y1102461D01*
G01X1282677Y1103642D02*
X1283858Y1102461D01*
G01X1291535Y1130315D02*
X1286202D01*
G01X1286201Y1129823D02*
X1287185D01*
G01Y1127185D02*
X1286201D01*
G01X1286202Y1126693D02*
X1291535D01*
G01Y1126654D02*
X1287187D01*
G01X1291535Y1125315D02*
X1286202D01*
G01X1286201Y1124823D02*
X1287185D01*
G01X1283858Y1124547D02*
X1287795D01*
G01X1282677Y1123366D02*
X1286614D01*
G01Y1103642D02*
X1282677D01*
G01X1287795Y1102461D02*
X1283858D01*
G01X1287185Y1102185D02*
X1286201D01*
G01X1286202Y1101693D02*
X1291535D01*
G01Y1101654D02*
X1287187D01*
G01X1291535Y1100315D02*
X1286202D01*
G01X1286201Y1099823D02*
X1287185D01*
G01Y1097185D02*
X1286201D01*
G01X1286202Y1096693D02*
X1291535D01*
G01Y1096654D02*
X1287187D01*
G01X1291535Y1095315D02*
X1286202D01*
G01X1286201Y1094823D02*
X1287185D01*
G01Y1092185D02*
X1286201D01*
G01X1286202Y1091693D02*
X1291535D01*
G01Y1091654D02*
X1287187D01*
G01X1291535Y1090315D02*
X1286202D01*
G01X1286201Y1089823D02*
X1287185D01*
G01Y1087185D02*
X1286201D01*
G01X1286202Y1086693D02*
X1291535D01*
G01Y1086654D02*
X1287187D01*
G01X1291535Y1085315D02*
X1286202D01*
G01X1286201Y1084823D02*
X1287185D01*
G01Y1130119D02*
X1286201Y1130118D01*
G01Y1126889D02*
X1287156Y1126890D01*
G01X1287185Y1125119D02*
X1286201Y1125118D01*
G01Y1101889D02*
X1287156Y1101890D01*
G01X1287185Y1100119D02*
X1286201Y1100118D01*
G01Y1096889D02*
X1287156Y1096890D01*
G01X1287185Y1095119D02*
X1286201Y1095118D01*
G01Y1091889D02*
X1287156Y1091890D01*
G01X1287185Y1090119D02*
X1286201Y1090118D01*
G01Y1086889D02*
X1287156Y1086890D01*
G01X1287185Y1085119D02*
X1286201Y1085118D01*
G01X1287185Y1086667D02*
Y1086676D01*
G01Y1091667D02*
Y1091676D01*
G01Y1096667D02*
Y1096676D01*
G01Y1101667D02*
Y1101676D01*
G01Y1126667D02*
Y1126676D01*
G01X1291535Y1130315D02*
Y1131693D01*
G01Y1125315D02*
Y1126693D01*
G01Y1100315D02*
Y1101693D01*
G01Y1095315D02*
Y1096693D01*
G01Y1090315D02*
Y1091693D01*
G01Y1085315D02*
Y1086693D01*
G01X1288366D02*
Y1085315D01*
G01Y1091693D02*
Y1090315D01*
G01Y1096693D02*
Y1095315D01*
G01Y1101693D02*
Y1100315D01*
G01Y1126693D02*
Y1125315D01*
G01Y1131693D02*
Y1130315D01*
G01X1287795Y1124547D02*
Y1102461D01*
G01X1287185Y1129823D02*
Y1132185D01*
G01Y1124823D02*
Y1127185D01*
G01Y1099823D02*
Y1102185D01*
G01Y1094823D02*
Y1097185D01*
G01Y1089823D02*
Y1092185D01*
G01Y1084823D02*
Y1087185D01*
G01Y1086667D02*
Y1086811D01*
G01Y1091667D02*
Y1091811D01*
G01Y1096667D02*
Y1096811D01*
G01Y1101667D02*
Y1101811D01*
G01Y1126667D02*
Y1126811D01*
G01X1286614Y1123366D02*
Y1103642D01*
G01X1286201Y1087185D02*
Y1084823D01*
G01Y1092185D02*
Y1089823D01*
G01Y1097185D02*
Y1094823D01*
G01Y1102185D02*
Y1099823D01*
G01Y1127185D02*
Y1124823D01*
G01Y1132185D02*
Y1129823D01*
G01X1283858Y1201004D02*
Y1124547D01*
G01X1282677Y1199823D02*
Y1123366D01*
G01X1286614D02*
X1287795Y1124547D01*
G01X1282677Y1123366D02*
X1283858Y1124547D01*
G01X1287185Y1175308D02*
Y1175299D01*
G01X1287186Y1175313D02*
X1287185Y1175308D01*
G01X1287188Y1175315D02*
X1287186Y1175313D01*
G01X1287185Y1170308D02*
Y1170299D01*
G01X1287186Y1170313D02*
X1287185Y1170308D01*
G01X1287188Y1170315D02*
X1287186Y1170313D01*
G01X1287185Y1165308D02*
Y1165299D01*
G01X1287186Y1165313D02*
X1287185Y1165308D01*
G01X1287188Y1165315D02*
X1287186Y1165313D01*
G01X1287185Y1160308D02*
Y1160299D01*
G01X1287186Y1160313D02*
X1287185Y1160308D01*
G01X1287188Y1160315D02*
X1287186Y1160313D01*
G01X1287185Y1155308D02*
Y1155299D01*
G01X1287186Y1155313D02*
X1287185Y1155308D01*
G01X1287188Y1155315D02*
X1287186Y1155313D01*
G01X1287185Y1150308D02*
Y1150299D01*
G01X1287186Y1150313D02*
X1287185Y1150308D01*
G01X1287188Y1150315D02*
X1287186Y1150313D01*
G01X1287185Y1145308D02*
Y1145299D01*
G01X1287186Y1145313D02*
X1287185Y1145308D01*
G01X1287188Y1145315D02*
X1287186Y1145313D01*
G01X1287185Y1140308D02*
Y1140299D01*
G01X1287186Y1140313D02*
X1287185Y1140308D01*
G01X1287188Y1140315D02*
X1287186Y1140313D01*
G01X1287185Y1135308D02*
Y1135299D01*
G01X1287186Y1135313D02*
X1287185Y1135308D01*
G01X1287188Y1135315D02*
X1287186Y1135313D01*
G01X1287152Y1131791D02*
X1287156Y1131890D01*
G01X1287146Y1131719D02*
X1287152Y1131791D01*
G01X1287148Y1131693D02*
X1287146Y1131719D01*
G01X1287152Y1136791D02*
X1287156Y1136890D01*
G01X1287146Y1136719D02*
X1287152Y1136791D01*
G01X1287148Y1136693D02*
X1287146Y1136719D01*
G01X1287152Y1141791D02*
X1287156Y1141890D01*
G01X1287146Y1141719D02*
X1287152Y1141791D01*
G01X1287148Y1141693D02*
X1287146Y1141719D01*
G01X1287152Y1146791D02*
X1287156Y1146890D01*
G01X1287146Y1146719D02*
X1287152Y1146791D01*
G01X1287148Y1146693D02*
X1287146Y1146719D01*
G01X1287152Y1151791D02*
X1287156Y1151890D01*
G01X1287146Y1151719D02*
X1287152Y1151791D01*
G01X1287148Y1151693D02*
X1287146Y1151719D01*
G01X1287152Y1156791D02*
X1287156Y1156890D01*
G01X1287146Y1156719D02*
X1287152Y1156791D01*
G01X1287148Y1156693D02*
X1287146Y1156719D01*
G01X1287152Y1161791D02*
X1287156Y1161890D01*
G01X1287146Y1161719D02*
X1287152Y1161791D01*
G01X1287148Y1161693D02*
X1287146Y1161719D01*
G01X1287152Y1166791D02*
X1287156Y1166890D01*
G01X1287146Y1166719D02*
X1287152Y1166791D01*
G01X1287148Y1166693D02*
X1287146Y1166719D01*
G01X1287152Y1171791D02*
X1287156Y1171890D01*
G01X1287146Y1171719D02*
X1287152Y1171791D01*
G01X1287148Y1171693D02*
X1287146Y1171719D01*
G01X1287152Y1176791D02*
X1287156Y1176890D01*
G01X1287146Y1176719D02*
X1287152Y1176791D01*
G01X1287148Y1176693D02*
X1287146Y1176719D01*
G01X1286202Y1175313D02*
Y1175315D01*
G01X1286201Y1175308D02*
X1286202Y1175313D01*
G01X1286201Y1175299D02*
Y1175308D01*
G01X1286202Y1170313D02*
Y1170315D01*
G01X1286201Y1170308D02*
X1286202Y1170313D01*
G01X1286201Y1170299D02*
Y1170308D01*
G01X1286202Y1165313D02*
Y1165315D01*
G01X1286201Y1165308D02*
X1286202Y1165313D01*
G01X1286201Y1165299D02*
Y1165308D01*
G01X1286202Y1160313D02*
Y1160315D01*
G01X1286201Y1160308D02*
X1286202Y1160313D01*
G01X1286201Y1160299D02*
Y1160308D01*
G01X1286202Y1155313D02*
Y1155315D01*
G01X1286201Y1155308D02*
X1286202Y1155313D01*
G01X1286201Y1155299D02*
Y1155308D01*
G01X1286202Y1150313D02*
Y1150315D01*
G01X1286201Y1150308D02*
X1286202Y1150313D01*
G01X1286201Y1150299D02*
Y1150308D01*
G01X1286202Y1145313D02*
Y1145315D01*
G01X1286201Y1145308D02*
X1286202Y1145313D01*
G01X1286201Y1145299D02*
Y1145308D01*
G01X1286202Y1140313D02*
Y1140315D01*
G01X1286201Y1140308D02*
X1286202Y1140313D01*
G01X1286201Y1140299D02*
Y1140308D01*
G01X1286202Y1135313D02*
Y1135315D01*
G01X1286201Y1135308D02*
X1286202Y1135313D01*
G01X1286201Y1135299D02*
Y1135308D01*
G01X1287172Y1131685D02*
X1287183Y1131669D01*
G01X1287148Y1131693D02*
X1287172Y1131685D01*
G01Y1136685D02*
X1287183Y1136669D01*
G01X1287148Y1136693D02*
X1287172Y1136685D01*
G01Y1141685D02*
X1287183Y1141669D01*
G01X1287148Y1141693D02*
X1287172Y1141685D01*
G01Y1146685D02*
X1287183Y1146669D01*
G01X1287148Y1146693D02*
X1287172Y1146685D01*
G01Y1151685D02*
X1287183Y1151669D01*
G01X1287148Y1151693D02*
X1287172Y1151685D01*
G01Y1156685D02*
X1287183Y1156669D01*
G01X1287148Y1156693D02*
X1287172Y1156685D01*
G01X1286201Y1131700D02*
Y1131709D01*
G01X1286202Y1131695D02*
X1286201Y1131700D01*
G01X1286202Y1131693D02*
Y1131695D01*
G01X1286201Y1136700D02*
Y1136709D01*
G01X1286202Y1136695D02*
X1286201Y1136700D01*
G01X1286202Y1136693D02*
Y1136695D01*
G01X1286201Y1141700D02*
Y1141709D01*
G01X1286202Y1141695D02*
X1286201Y1141700D01*
G01X1286202Y1141693D02*
Y1141695D01*
G01X1286201Y1146700D02*
Y1146709D01*
G01X1286202Y1146695D02*
X1286201Y1146700D01*
G01X1286202Y1146693D02*
Y1146695D01*
G01X1286201Y1151700D02*
Y1151709D01*
G01X1286202Y1151695D02*
X1286201Y1151700D01*
G01X1286202Y1151693D02*
Y1151695D01*
G01X1286201Y1156700D02*
Y1156709D01*
G01X1286202Y1156695D02*
X1286201Y1156700D01*
G01X1286202Y1156693D02*
Y1156695D01*
G01X1286201Y1161700D02*
Y1161709D01*
G01X1286202Y1161695D02*
X1286201Y1161700D01*
G01X1286202Y1161693D02*
Y1161695D01*
G01X1286201Y1166700D02*
Y1166709D01*
G01X1286202Y1166695D02*
X1286201Y1166700D01*
G01X1286202Y1166693D02*
Y1166695D01*
G01X1286201Y1171700D02*
Y1171709D01*
G01X1286202Y1171695D02*
X1286201Y1171700D01*
G01X1286202Y1171693D02*
Y1171695D01*
G01X1286201Y1176700D02*
Y1176709D01*
G01X1286202Y1176695D02*
X1286201Y1176700D01*
G01X1286202Y1176693D02*
Y1176695D01*
G01X1287177Y1131837D02*
X1287185Y1131811D01*
G01X1287167Y1131863D02*
X1287177Y1131837D01*
G01X1287156Y1131890D02*
X1287167Y1131863D01*
G01X1287177Y1136837D02*
X1287185Y1136811D01*
G01X1287167Y1136863D02*
X1287177Y1136837D01*
G01X1287156Y1136890D02*
X1287167Y1136863D01*
G01X1287177Y1141837D02*
X1287185Y1141811D01*
G01X1287167Y1141863D02*
X1287177Y1141837D01*
G01X1287156Y1141890D02*
X1287167Y1141863D01*
G01X1287177Y1146837D02*
X1287185Y1146811D01*
G01X1287167Y1146863D02*
X1287177Y1146837D01*
G01X1287156Y1146890D02*
X1287167Y1146863D01*
G01X1287177Y1151837D02*
X1287185Y1151811D01*
G01X1287167Y1151863D02*
X1287177Y1151837D01*
G01X1287156Y1151890D02*
X1287167Y1151863D01*
G01X1287177Y1156837D02*
X1287185Y1156811D01*
G01X1287167Y1156863D02*
X1287177Y1156837D01*
G01X1287156Y1156890D02*
X1287167Y1156863D01*
G01X1287177Y1161837D02*
X1287185Y1161811D01*
G01X1287167Y1161863D02*
X1287177Y1161837D01*
G01X1287156Y1161890D02*
X1287167Y1161863D01*
G01X1287177Y1166837D02*
X1287185Y1166811D01*
G01X1287167Y1166863D02*
X1287177Y1166837D01*
G01X1287156Y1166890D02*
X1287167Y1166863D01*
G01X1287177Y1171837D02*
X1287185Y1171811D01*
G01X1287167Y1171863D02*
X1287177Y1171837D01*
G01X1287156Y1171890D02*
X1287167Y1171863D01*
G01X1287177Y1176837D02*
X1287185Y1176811D01*
G01X1287167Y1176863D02*
X1287177Y1176837D01*
G01X1287156Y1176890D02*
X1287167Y1176863D01*
G01X1287168Y1131688D02*
X1287148Y1131693D01*
G01X1287182Y1131674D02*
X1287168Y1131688D01*
G01X1287187Y1131654D02*
X1287182Y1131674D01*
G01X1287168Y1136688D02*
X1287148Y1136693D01*
G01X1287182Y1136674D02*
X1287168Y1136688D01*
G01X1287187Y1136654D02*
X1287182Y1136674D01*
G01X1287168Y1141688D02*
X1287148Y1141693D01*
G01X1287182Y1141674D02*
X1287168Y1141688D01*
G01X1287187Y1141654D02*
X1287182Y1141674D01*
G01X1287168Y1146688D02*
X1287148Y1146693D01*
G01X1287182Y1146674D02*
X1287168Y1146688D01*
G01X1287187Y1146654D02*
X1287182Y1146674D01*
G01X1287168Y1151688D02*
X1287148Y1151693D01*
G01X1287182Y1151674D02*
X1287168Y1151688D01*
G01X1287187Y1151654D02*
X1287182Y1151674D01*
G01X1287168Y1156688D02*
X1287148Y1156693D01*
G01X1287182Y1156674D02*
X1287168Y1156688D01*
G01X1287187Y1156654D02*
X1287182Y1156674D01*
G01X1287168Y1161688D02*
X1287148Y1161693D01*
G01X1287182Y1161674D02*
X1287168Y1161688D01*
G01X1287187Y1161654D02*
X1287182Y1161674D01*
G01X1287168Y1166688D02*
X1287148Y1166693D01*
G01X1287182Y1166674D02*
X1287168Y1166688D01*
G01X1287187Y1166654D02*
X1287182Y1166674D01*
G01X1287168Y1171688D02*
X1287148Y1171693D01*
G01X1287182Y1171674D02*
X1287168Y1171688D01*
G01X1287187Y1171654D02*
X1287182Y1171674D01*
G01X1287168Y1176688D02*
X1287148Y1176693D01*
G01X1287182Y1176674D02*
X1287168Y1176688D01*
G01X1287187Y1176654D02*
X1287182Y1176674D01*
G01X1287172Y1161685D02*
X1287183Y1161669D01*
G01X1287148Y1161693D02*
X1287172Y1161685D01*
G01Y1166685D02*
X1287183Y1166669D01*
G01X1287148Y1166693D02*
X1287172Y1166685D01*
G01Y1171685D02*
X1287183Y1171669D01*
G01X1287148Y1171693D02*
X1287172Y1171685D01*
G01Y1176685D02*
X1287183Y1176669D01*
G01X1287148Y1176693D02*
X1287172Y1176685D01*
G01X1287185Y1131660D02*
Y1131667D01*
G01X1287186Y1131656D02*
X1287185Y1131660D01*
G01X1287187Y1131654D02*
X1287186Y1131656D01*
G01X1287185Y1136660D02*
Y1136667D01*
G01X1287186Y1136656D02*
X1287185Y1136660D01*
G01X1287187Y1136654D02*
X1287186Y1136656D01*
G01X1287185Y1141660D02*
Y1141667D01*
G01X1287186Y1141656D02*
X1287185Y1141660D01*
G01X1287187Y1141654D02*
X1287186Y1141656D01*
G01X1287185Y1146660D02*
Y1146667D01*
G01X1287186Y1146656D02*
X1287185Y1146660D01*
G01X1287187Y1146654D02*
X1287186Y1146656D01*
G01X1287185Y1151660D02*
Y1151667D01*
G01X1287186Y1151656D02*
X1287185Y1151660D01*
G01X1287187Y1151654D02*
X1287186Y1151656D01*
G01X1287185Y1156660D02*
Y1156667D01*
G01X1287186Y1156656D02*
X1287185Y1156660D01*
G01X1287187Y1156654D02*
X1287186Y1156656D01*
G01X1287185Y1161660D02*
Y1161667D01*
G01X1287186Y1161656D02*
X1287185Y1161660D01*
G01X1287187Y1161654D02*
X1287186Y1161656D01*
G01X1287185Y1166660D02*
Y1166667D01*
G01X1287186Y1166656D02*
X1287185Y1166660D01*
G01X1287187Y1166654D02*
X1287186Y1166656D01*
G01X1287185Y1171660D02*
Y1171667D01*
G01X1287186Y1171656D02*
X1287185Y1171660D01*
G01X1287187Y1171654D02*
X1287186Y1171656D01*
G01X1287185Y1176660D02*
Y1176667D01*
G01X1287186Y1176656D02*
X1287185Y1176660D01*
G01X1287187Y1176654D02*
X1287186Y1176656D01*
G01X1287185Y1177185D02*
X1286201D01*
G01X1286202Y1176693D02*
X1291535D01*
G01Y1176654D02*
X1287187D01*
G01X1291535Y1175315D02*
X1286202D01*
G01X1286201Y1174823D02*
X1287185D01*
G01Y1172185D02*
X1286201D01*
G01X1286202Y1171693D02*
X1291535D01*
G01Y1171654D02*
X1287187D01*
G01X1291535Y1170315D02*
X1286202D01*
G01X1286201Y1169823D02*
X1287185D01*
G01Y1167185D02*
X1286201D01*
G01X1286202Y1166693D02*
X1291535D01*
G01Y1166654D02*
X1287187D01*
G01X1291535Y1165315D02*
X1286202D01*
G01X1286201Y1164823D02*
X1287185D01*
G01Y1162185D02*
X1286201D01*
G01X1286202Y1161693D02*
X1291535D01*
G01Y1161654D02*
X1287187D01*
G01X1291535Y1160315D02*
X1286202D01*
G01X1286201Y1159823D02*
X1287185D01*
G01Y1157185D02*
X1286201D01*
G01X1286202Y1156693D02*
X1291535D01*
G01Y1156654D02*
X1287187D01*
G01X1291535Y1155315D02*
X1286202D01*
G01X1286201Y1154823D02*
X1287185D01*
G01X1286201Y1176889D02*
X1287156Y1176890D01*
G01X1287185Y1175119D02*
X1286201Y1175118D01*
G01Y1171889D02*
X1287156Y1171890D01*
G01X1287185Y1170119D02*
X1286201Y1170118D01*
G01Y1166889D02*
X1287156Y1166890D01*
G01X1287185Y1165119D02*
X1286201Y1165118D01*
G01Y1161889D02*
X1287156Y1161890D01*
G01X1287185Y1160119D02*
X1286201Y1160118D01*
G01Y1156889D02*
X1287156Y1156890D01*
G01X1287185Y1155119D02*
X1286201Y1155118D01*
G01X1287185Y1152185D02*
X1286201D01*
G01X1286202Y1151693D02*
X1291535D01*
G01Y1151654D02*
X1287187D01*
G01X1291535Y1150315D02*
X1286202D01*
G01X1286201Y1149823D02*
X1287185D01*
G01Y1147185D02*
X1286201D01*
G01X1286202Y1146693D02*
X1291535D01*
G01Y1146654D02*
X1287187D01*
G01X1291535Y1145315D02*
X1286202D01*
G01X1286201Y1144823D02*
X1287185D01*
G01Y1142185D02*
X1286201D01*
G01X1286202Y1141693D02*
X1291535D01*
G01Y1141654D02*
X1287187D01*
G01X1291535Y1140315D02*
X1286202D01*
G01X1286201Y1139823D02*
X1287185D01*
G01Y1137185D02*
X1286201D01*
G01X1286202Y1136693D02*
X1291535D01*
G01Y1136654D02*
X1287187D01*
G01X1291535Y1135315D02*
X1286202D01*
G01X1286201Y1134823D02*
X1287185D01*
G01Y1132185D02*
X1286201D01*
G01X1286202Y1131693D02*
X1291535D01*
G01Y1131654D02*
X1287187D01*
G01X1286201Y1151889D02*
X1287156Y1151890D01*
G01X1287185Y1150119D02*
X1286201Y1150118D01*
G01Y1146889D02*
X1287156Y1146890D01*
G01X1287185Y1145119D02*
X1286201Y1145118D01*
G01Y1141889D02*
X1287156Y1141890D01*
G01X1287185Y1140119D02*
X1286201Y1140118D01*
G01Y1136889D02*
X1287156Y1136890D01*
G01X1287185Y1135119D02*
X1286201Y1135118D01*
G01Y1131889D02*
X1287156Y1131890D01*
G01X1287185Y1131667D02*
Y1131676D01*
G01Y1136667D02*
Y1136676D01*
G01Y1141667D02*
Y1141676D01*
G01Y1146667D02*
Y1146676D01*
G01Y1151667D02*
Y1151676D01*
G01Y1156667D02*
Y1156676D01*
G01Y1161667D02*
Y1161676D01*
G01Y1166667D02*
Y1166676D01*
G01Y1171667D02*
Y1171676D01*
G01Y1176667D02*
Y1176676D01*
G01X1291535Y1175315D02*
Y1176693D01*
G01Y1170315D02*
Y1171693D01*
G01Y1165315D02*
Y1166693D01*
G01Y1160315D02*
Y1161693D01*
G01Y1155315D02*
Y1156693D01*
G01Y1150315D02*
Y1151693D01*
G01Y1145315D02*
Y1146693D01*
G01Y1140315D02*
Y1141693D01*
G01Y1135315D02*
Y1136693D01*
G01X1288366D02*
Y1135315D01*
G01Y1141693D02*
Y1140315D01*
G01Y1146693D02*
Y1145315D01*
G01Y1151693D02*
Y1150315D01*
G01Y1156693D02*
Y1155315D01*
G01Y1161693D02*
Y1160315D01*
G01Y1166693D02*
Y1165315D01*
G01Y1171693D02*
Y1170315D01*
G01Y1176693D02*
Y1175315D01*
G01X1287185Y1174823D02*
Y1177185D01*
G01Y1169823D02*
Y1172185D01*
G01Y1164823D02*
Y1167185D01*
G01Y1159823D02*
Y1162185D01*
G01Y1154823D02*
Y1157185D01*
G01Y1149823D02*
Y1152185D01*
G01Y1144823D02*
Y1147185D01*
G01Y1139823D02*
Y1142185D01*
G01Y1134823D02*
Y1137185D01*
G01Y1131667D02*
Y1131811D01*
G01Y1136667D02*
Y1136811D01*
G01Y1141667D02*
Y1141811D01*
G01Y1146667D02*
Y1146811D01*
G01Y1151667D02*
Y1151811D01*
G01Y1156667D02*
Y1156811D01*
G01Y1161667D02*
Y1161811D01*
G01Y1166667D02*
Y1166811D01*
G01Y1171667D02*
Y1171811D01*
G01Y1176667D02*
Y1176811D01*
G01X1286201Y1137185D02*
Y1134823D01*
G01Y1142185D02*
Y1139823D01*
G01Y1147185D02*
Y1144823D01*
G01Y1152185D02*
Y1149823D01*
G01Y1157185D02*
Y1154823D01*
G01Y1162185D02*
Y1159823D01*
G01Y1167185D02*
Y1164823D01*
G01Y1172185D02*
Y1169823D01*
G01Y1177185D02*
Y1174823D01*
G01X1287185Y1195308D02*
Y1195299D01*
G01X1287186Y1195313D02*
X1287185Y1195308D01*
G01X1287188Y1195315D02*
X1287186Y1195313D01*
G01X1287185Y1190308D02*
Y1190299D01*
G01X1287186Y1190313D02*
X1287185Y1190308D01*
G01X1287188Y1190315D02*
X1287186Y1190313D01*
G01X1287185Y1185308D02*
Y1185299D01*
G01X1287186Y1185313D02*
X1287185Y1185308D01*
G01X1287188Y1185315D02*
X1287186Y1185313D01*
G01X1287185Y1180308D02*
Y1180299D01*
G01X1287186Y1180313D02*
X1287185Y1180308D01*
G01X1287188Y1180315D02*
X1287186Y1180313D01*
G01X1287152Y1181791D02*
X1287156Y1181890D01*
G01X1287146Y1181719D02*
X1287152Y1181791D01*
G01X1287148Y1181693D02*
X1287146Y1181719D01*
G01X1287152Y1186791D02*
X1287156Y1186890D01*
G01X1287146Y1186719D02*
X1287152Y1186791D01*
G01X1287148Y1186693D02*
X1287146Y1186719D01*
G01X1287152Y1191791D02*
X1287156Y1191890D01*
G01X1287146Y1191719D02*
X1287152Y1191791D01*
G01X1287148Y1191693D02*
X1287146Y1191719D01*
G01X1287152Y1196791D02*
X1287156Y1196890D01*
G01X1287146Y1196719D02*
X1287152Y1196791D01*
G01X1287148Y1196693D02*
X1287146Y1196719D01*
G01X1286202Y1195313D02*
Y1195315D01*
G01X1286201Y1195308D02*
X1286202Y1195313D01*
G01X1286201Y1195299D02*
Y1195308D01*
G01X1286202Y1190313D02*
Y1190315D01*
G01X1286201Y1190308D02*
X1286202Y1190313D01*
G01X1286201Y1190299D02*
Y1190308D01*
G01X1286202Y1185313D02*
Y1185315D01*
G01X1286201Y1185308D02*
X1286202Y1185313D01*
G01X1286201Y1185299D02*
Y1185308D01*
G01X1286202Y1180313D02*
Y1180315D01*
G01X1286201Y1180308D02*
X1286202Y1180313D01*
G01X1286201Y1180299D02*
Y1180308D01*
G01Y1181700D02*
Y1181709D01*
G01X1286202Y1181695D02*
X1286201Y1181700D01*
G01X1286202Y1181693D02*
Y1181695D01*
G01X1286201Y1186700D02*
Y1186709D01*
G01X1286202Y1186695D02*
X1286201Y1186700D01*
G01X1286202Y1186693D02*
Y1186695D01*
G01X1286201Y1191700D02*
Y1191709D01*
G01X1286202Y1191695D02*
X1286201Y1191700D01*
G01X1286202Y1191693D02*
Y1191695D01*
G01X1286201Y1196700D02*
Y1196709D01*
G01X1286202Y1196695D02*
X1286201Y1196700D01*
G01X1286202Y1196693D02*
Y1196695D01*
G01X1287177Y1181837D02*
X1287185Y1181811D01*
G01X1287167Y1181863D02*
X1287177Y1181837D01*
G01X1287156Y1181890D02*
X1287167Y1181863D01*
G01X1287177Y1186837D02*
X1287185Y1186811D01*
G01X1287167Y1186863D02*
X1287177Y1186837D01*
G01X1287156Y1186890D02*
X1287167Y1186863D01*
G01X1287177Y1191837D02*
X1287185Y1191811D01*
G01X1287167Y1191863D02*
X1287177Y1191837D01*
G01X1287156Y1191890D02*
X1287167Y1191863D01*
G01X1287177Y1196837D02*
X1287185Y1196811D01*
G01X1287167Y1196863D02*
X1287177Y1196837D01*
G01X1287156Y1196890D02*
X1287167Y1196863D01*
G01X1287168Y1181688D02*
X1287148Y1181693D01*
G01X1287182Y1181674D02*
X1287168Y1181688D01*
G01X1287187Y1181654D02*
X1287182Y1181674D01*
G01X1287168Y1186688D02*
X1287148Y1186693D01*
G01X1287182Y1186674D02*
X1287168Y1186688D01*
G01X1287187Y1186654D02*
X1287182Y1186674D01*
G01X1287168Y1191688D02*
X1287148Y1191693D01*
G01X1287182Y1191674D02*
X1287168Y1191688D01*
G01X1287187Y1191654D02*
X1287182Y1191674D01*
G01X1287168Y1196688D02*
X1287148Y1196693D01*
G01X1287182Y1196674D02*
X1287168Y1196688D01*
G01X1287187Y1196654D02*
X1287182Y1196674D01*
G01X1287172Y1181685D02*
X1287183Y1181669D01*
G01X1287148Y1181693D02*
X1287172Y1181685D01*
G01Y1186685D02*
X1287183Y1186669D01*
G01X1287148Y1186693D02*
X1287172Y1186685D01*
G01Y1191685D02*
X1287183Y1191669D01*
G01X1287148Y1191693D02*
X1287172Y1191685D01*
G01Y1196685D02*
X1287183Y1196669D01*
G01X1287148Y1196693D02*
X1287172Y1196685D01*
G01X1287185Y1181660D02*
Y1181667D01*
G01X1287186Y1181656D02*
X1287185Y1181660D01*
G01X1287187Y1181654D02*
X1287186Y1181656D01*
G01X1287185Y1186660D02*
Y1186667D01*
G01X1287186Y1186656D02*
X1287185Y1186660D01*
G01X1287187Y1186654D02*
X1287186Y1186656D01*
G01X1287185Y1191660D02*
Y1191667D01*
G01X1287186Y1191656D02*
X1287185Y1191660D01*
G01X1287187Y1191654D02*
X1287186Y1191656D01*
G01X1287185Y1196660D02*
Y1196667D01*
G01X1287186Y1196656D02*
X1287185Y1196660D01*
G01X1287187Y1196654D02*
X1287186Y1196656D01*
G01X1285630Y1222185D02*
G03X1285039Y1222776I-591J0D01*
G01X1282874Y1219035D02*
G03Y1221004I0J985D01*
G01X1292520Y1221594D02*
G03X1290551Y1223563I-1969J0D01*
G01X1285433Y1211909D02*
G03X1284252Y1213091I-1181J1D01*
G01X1282874Y1206713D02*
X1284178Y1204744D01*
G01X1288583Y1203366D02*
X1285433D01*
G01X1287185Y1197185D02*
X1286201D01*
G01X1286202Y1196693D02*
X1291535D01*
G01Y1196654D02*
X1287187D01*
G01X1291535Y1195315D02*
X1286202D01*
G01X1286201Y1194823D02*
X1287185D01*
G01Y1192185D02*
X1286201D01*
G01X1286202Y1191693D02*
X1291535D01*
G01Y1191654D02*
X1287187D01*
G01X1291535Y1190315D02*
X1286202D01*
G01X1286201Y1189823D02*
X1287185D01*
G01Y1187185D02*
X1286201D01*
G01X1286202Y1186693D02*
X1291535D01*
G01Y1186654D02*
X1287187D01*
G01X1291535Y1185315D02*
X1286202D01*
G01X1286201Y1184823D02*
X1287185D01*
G01Y1182185D02*
X1286201D01*
G01X1286202Y1181693D02*
X1291535D01*
G01Y1181654D02*
X1287187D01*
G01X1291535Y1180315D02*
X1286202D01*
G01X1286201Y1179823D02*
X1287185D01*
G01X1286201Y1196889D02*
X1287156Y1196890D01*
G01X1287185Y1195119D02*
X1286201Y1195118D01*
G01Y1191889D02*
X1287156Y1191890D01*
G01X1287185Y1190119D02*
X1286201Y1190118D01*
G01Y1186889D02*
X1287156Y1186890D01*
G01X1287185Y1185119D02*
X1286201Y1185118D01*
G01Y1181889D02*
X1287156Y1181890D01*
G01X1287185Y1180119D02*
X1286201Y1180118D01*
G01X1287185Y1181667D02*
Y1181676D01*
G01Y1186667D02*
Y1186676D01*
G01Y1191667D02*
Y1191676D01*
G01Y1196667D02*
Y1196676D01*
G01X1292520Y1205846D02*
Y1221594D01*
G01X1291535Y1195315D02*
Y1196693D01*
G01Y1190315D02*
Y1191693D01*
G01Y1185315D02*
Y1186693D01*
G01Y1180315D02*
Y1181693D01*
G01X1288366D02*
Y1180315D01*
G01Y1186693D02*
Y1185315D01*
G01Y1191693D02*
Y1190315D01*
G01Y1196693D02*
Y1195315D01*
G01X1287185Y1194823D02*
Y1197185D01*
G01Y1189823D02*
Y1192185D01*
G01Y1184823D02*
Y1187185D01*
G01Y1179823D02*
Y1182185D01*
G01Y1181667D02*
Y1181811D01*
G01Y1186667D02*
Y1186811D01*
G01Y1191667D02*
Y1191811D01*
G01Y1196667D02*
Y1196811D01*
G01X1286201Y1182185D02*
Y1179823D01*
G01Y1187185D02*
Y1184823D01*
G01Y1192185D02*
Y1189823D01*
G01Y1197185D02*
Y1194823D01*
G01X1285630Y1216083D02*
Y1222185D01*
G01X1285433Y1211909D02*
Y1203366D01*
G01X1282874Y1208406D02*
Y1206713D01*
G01X1285184Y1212635D02*
X1282874Y1208406D01*
G01X1292520Y1205846D02*
X1289173Y1202500D01*
G01X1282677Y1199823D02*
X1283858Y1201004D01*
G01X1311851Y1297528D02*
G03X1318775Y1284397I37663J11469D01*
G01X1311851Y1297528D02*
G03X1291890I-9980J-3040D01*
G01X1284965Y1284397D02*
G03X1291890Y1297528I-30737J24602D01*
G01X1311850D02*
G03X1318776Y1284397I37661J11473D01*
G01X1311850Y1297528D02*
G03X1291890I-9980J-3040D01*
G01X1284965Y1284397D02*
G03X1291890Y1297528I-30737J24602D01*
G01X1346457Y0D02*
G03Y-7874I0J-3937D01*
G01X1366142D02*
G03X1377953Y3937I0J11811D01*
G01D02*
Y51181D01*
G01X1346457Y-7874D02*
X1366142D01*
G01X1370079Y3937D02*
Y55118D01*
G01X1366142Y0D02*
G03X1370079Y3937I0J3937D01*
G01X1346457Y-7874D02*
X1366142D01*
G01X1346457Y0D02*
G03Y-7874I0J-3937D01*
G01X1377953Y3937D02*
Y51181D01*
G01X1366142Y-7874D02*
G03X1377953Y3937I0J11811D01*
G01X1366142Y0D02*
G03X1370079Y3937I0J3937D01*
G01D02*
Y55118D01*
G01X1377953Y51181D02*
X1551181D01*
G01X1374016Y59055D02*
X1555118D01*
G01X1374016Y59056D02*
G03X1370079Y55118I0J-3937D01*
G01X1377953Y51181D02*
X1551181D01*
G01X1374016Y59055D02*
G03X1370079Y55118I0J-3937D01*
G01X1374016Y59055D02*
X1555118D01*
G01X1365945Y374803D02*
G03X1367126I590J0D01*
G01Y368504D02*
G03X1365945I-591J0D01*
G01X1363976D02*
G03X1362795I-591J0D01*
G01Y374803D02*
G03X1363976I591J0D01*
G01X1365945D02*
G03X1367126I590J0D01*
G01Y368504D02*
G03X1365945I-591J0D01*
G01X1363976D02*
G03X1362795I-591J0D01*
G01Y374803D02*
G03X1363976I591J0D01*
G01X1367913Y368504D02*
Y374803D01*
G01Y368504D02*
Y374803D01*
G01X1362008Y368504D02*
Y374803D01*
G01D02*
Y368504D01*
G01X1365945Y374803D02*
X1363976D01*
G01X1362795D02*
X1362008D01*
G01X1365945D02*
X1363976D01*
G01X1362795D02*
X1362008D01*
G01X1367913D02*
X1367126D01*
G01X1367913D02*
X1367126D01*
G01X1367913Y373819D02*
X1362008D01*
G01Y373622D02*
X1367913D01*
G01X1362008Y369685D02*
X1367913D01*
G01Y369488D02*
X1362008D01*
G01X1367126Y368504D02*
X1367913D01*
G01X1367126D02*
X1367913D01*
G01X1363976D02*
X1365945D01*
G01X1362008D02*
X1362795D01*
G01X1363976D02*
X1365945D01*
G01X1362008D02*
X1362795D01*
G01X1374409Y646457D02*
G03X1357874I-8267J0D01*
G01D02*
G03X1374409I8268J0D01*
G01D02*
G03I-8267J0D01*
G01X1365945Y827559D02*
G03X1367126I590J0D01*
G01Y821260D02*
G03X1365945I-591J0D01*
G01X1363976D02*
G03X1362795I-591J0D01*
G01Y827559D02*
G03X1363976I591J0D01*
G01X1365945D02*
G03X1367126I590J0D01*
G01Y821260D02*
G03X1365945I-591J0D01*
G01X1363976D02*
G03X1362795I-591J0D01*
G01Y827559D02*
G03X1363976I591J0D01*
G01X1367913Y821260D02*
Y827559D01*
G01Y821260D02*
Y827559D01*
G01X1362008Y821260D02*
Y827559D01*
G01D02*
Y821260D01*
G01X1365945Y827559D02*
X1363976D01*
G01X1362795D02*
X1362008D01*
G01X1365945D02*
X1363976D01*
G01X1362795D02*
X1362008D01*
G01X1367913D02*
X1367126D01*
G01X1367913D02*
X1367126D01*
G01X1367913Y826575D02*
X1362008D01*
G01Y826378D02*
X1367913D01*
G01X1362008Y822441D02*
X1367913D01*
G01Y822244D02*
X1362008D01*
G01X1367126Y821260D02*
X1367913D01*
G01X1367126D02*
X1367913D01*
G01X1363976D02*
X1365945D01*
G01X1362008D02*
X1362795D01*
G01X1363976D02*
X1365945D01*
G01X1362008D02*
X1362795D01*
G01X1336713Y1062992D02*
G03X1350689I6988J0D01*
G01D02*
G03X1336713I-6988J0D01*
G01X1350689D02*
G03I-6988J0D01*
G01X1338189Y1114173D02*
G03X1349213I5512J0D01*
G01D02*
G03X1338189I-5512J0D01*
G01X1349213D02*
G03I-5512J0D01*
G01X1367126Y1274016D02*
G03X1365945I-591J0D01*
G01X1363976D02*
G03X1362795I-591J0D01*
G01X1367126D02*
G03X1365945I-591J0D01*
G01X1363976D02*
G03X1362795I-591J0D01*
G01X1362008Y1275197D02*
X1367913D01*
G01Y1275000D02*
X1362008D01*
G01X1367126Y1274016D02*
X1367913D01*
G01X1367126D02*
X1367913D01*
G01X1363976D02*
X1365945D01*
G01X1362008D02*
X1362795D01*
G01X1363976D02*
X1365945D01*
G01X1362008D02*
X1362795D01*
G01X1367913D02*
Y1280315D01*
G01Y1274016D02*
Y1280315D01*
G01X1362008Y1274016D02*
Y1280315D01*
G01D02*
Y1274016D01*
G01X1365945Y1280315D02*
G03X1367126I590J0D01*
G01X1362795D02*
G03X1363976I591J0D01*
G01X1365945D02*
G03X1367126I590J0D01*
G01X1362795D02*
G03X1363976I591J0D01*
G01X1365945D02*
X1363976D01*
G01X1362795D02*
X1362008D01*
G01X1365945D02*
X1363976D01*
G01X1362795D02*
X1362008D01*
G01X1367913D02*
X1367126D01*
G01X1367913D02*
X1367126D01*
G01X1367913Y1279331D02*
X1362008D01*
G01Y1279134D02*
X1367913D01*
G01X1418913Y-335933D02*
Y-354870D01*
G01X1401969Y139311D02*
G03X1402559Y138720I591J0D01*
G01X1409252D02*
G03X1409843Y139311I0J591D01*
G01X1407087Y140492D02*
G03Y142461I0J984D01*
G01X1404724D02*
G03Y140492I0J-984D01*
G01X1407008Y153681D02*
G03I-1102J0D01*
G01X1408465Y148406D02*
G03X1409646Y149587I0J1181D01*
G01X1402165D02*
G03X1403346Y148406I1181J0D01*
G01X1407480Y153681D02*
G03I-1574J0D01*
G01X1395079Y139902D02*
G03X1397047Y137933I1968J-1D01*
G01X1414764D02*
G03X1416732Y139902I0J1968D01*
G01X1401378Y161673D02*
X1400197Y160492D01*
G01X1398425Y158996D02*
X1395079Y155650D01*
G01X1408390Y156752D02*
X1407087Y154783D01*
G01X1402414Y148861D02*
X1404724Y153091D01*
G01X1416732Y139902D02*
Y155650D01*
G01X1413386Y296988D02*
Y158996D01*
G01X1412795Y299232D02*
Y156752D01*
G01X1409843Y145413D02*
Y139311D01*
G01X1409646Y158130D02*
Y149587D01*
G01X1408071Y196949D02*
Y160492D01*
G01X1407087Y154783D02*
Y153091D01*
G01X1406890Y198130D02*
Y161673D01*
G01X1404724Y153091D02*
Y154783D01*
G01X1402165Y149587D02*
Y158130D01*
G01X1401969Y145413D02*
Y139311D01*
G01X1401378Y161673D02*
Y294311D01*
G01X1400197Y160492D02*
Y295492D01*
G01X1398425Y195787D02*
Y156752D01*
G01X1395079Y155650D02*
Y139902D01*
G01X1407087Y153091D02*
X1409397Y148861D01*
G01X1404724Y154783D02*
X1403421Y156752D01*
G01X1413386Y158996D02*
X1416732Y155650D01*
G01X1406890Y161673D02*
X1408071Y160492D01*
G01X1406890Y161673D02*
X1401378D01*
G01X1408071Y160492D02*
X1400197D01*
G01X1413386Y158996D02*
X1398425D01*
G01X1409646Y158130D02*
X1412795D01*
G01X1402165D02*
X1398425D01*
G01Y156752D02*
X1412795D01*
G01X1407087Y154783D02*
X1404724D01*
G01X1407087Y153091D02*
X1404724D01*
G01X1408465Y148406D02*
X1403346D01*
G01X1416732Y148366D02*
X1395079D01*
G01X1409843Y145413D02*
X1401969D01*
G01Y143839D02*
X1409843D01*
G01X1407087Y142461D02*
X1404724D01*
G01Y140492D02*
X1407087D01*
G01X1409252Y138720D02*
X1402559D01*
G01X1414764Y137933D02*
X1397047D01*
G01X1396991Y199114D02*
X1396986Y199094D01*
G01X1397006Y199129D02*
X1396991Y199114D01*
G01X1397025Y199134D02*
X1397006Y199129D01*
G01X1396991Y202264D02*
X1396986Y202244D01*
G01X1397006Y202278D02*
X1396991Y202264D01*
G01X1397025Y202283D02*
X1397006Y202278D01*
G01X1396991Y205413D02*
X1396986Y205394D01*
G01X1397006Y205428D02*
X1396991Y205413D01*
G01X1397025Y205433D02*
X1397006Y205428D01*
G01X1396991Y208563D02*
X1396986Y208543D01*
G01X1397006Y208578D02*
X1396991Y208563D01*
G01X1397025Y208583D02*
X1397006Y208578D01*
G01X1396991Y211713D02*
X1396986Y211693D01*
G01X1397006Y211727D02*
X1396991Y211713D01*
G01X1397025Y211732D02*
X1397006Y211727D01*
G01X1397966Y197972D02*
X1397971Y197992D01*
G01X1397951Y197958D02*
X1397966Y197972D01*
G01X1397931Y197953D02*
X1397951Y197958D01*
G01X1397966Y201122D02*
X1397971Y201142D01*
G01X1397951Y201108D02*
X1397966Y201122D01*
G01X1397931Y201102D02*
X1397951Y201108D01*
G01X1397966Y204272D02*
X1397971Y204291D01*
G01X1397951Y204257D02*
X1397966Y204272D01*
G01X1397931Y204252D02*
X1397951Y204257D01*
G01X1397966Y207421D02*
X1397971Y207441D01*
G01X1397951Y207407D02*
X1397966Y207421D01*
G01X1397931Y207402D02*
X1397951Y207407D01*
G01X1397966Y210571D02*
X1397971Y210591D01*
G01X1397951Y210557D02*
X1397966Y210571D01*
G01X1397931Y210551D02*
X1397951Y210557D01*
G01X1397950Y197945D02*
X1397953Y197947D01*
G01X1397947Y197944D02*
X1397950Y197945D01*
G01X1397944Y197943D02*
X1397947Y197944D01*
G01X1397940Y197942D02*
X1397944Y197943D01*
G01X1397937Y197942D02*
X1397940D01*
G01X1397933D02*
X1397937D01*
G01X1397011Y199142D02*
X1397007Y199140D01*
G01X1397014Y199143D02*
X1397011Y199142D01*
G01X1397017Y199144D02*
X1397014Y199143D01*
G01X1397020Y199144D02*
X1397017D01*
G01X1397024Y199145D02*
X1397020Y199144D01*
G01X1397028Y199145D02*
X1397024D01*
G01X1397950Y201095D02*
X1397953Y201096D01*
G01X1397947Y201094D02*
X1397950Y201095D01*
G01X1397944Y201093D02*
X1397947Y201094D01*
G01X1397940Y201092D02*
X1397944Y201093D01*
G01X1397937Y201091D02*
X1397940Y201092D01*
G01X1397933Y201091D02*
X1397937D01*
G01X1397011Y202291D02*
X1397007Y202290D01*
G01X1397014Y202293D02*
X1397011Y202291D01*
G01X1397017Y202294D02*
X1397014Y202293D01*
G01X1397020Y202294D02*
X1397017D01*
G01X1397024Y202295D02*
X1397020Y202294D01*
G01X1397028Y202295D02*
X1397024D01*
G01X1397950Y204244D02*
X1397953Y204246D01*
G01X1397947Y204243D02*
X1397950Y204244D01*
G01X1397944Y204242D02*
X1397947Y204243D01*
G01X1397940Y204241D02*
X1397944Y204242D01*
G01X1397937Y204241D02*
X1397940D01*
G01X1397933D02*
X1397937D01*
G01X1397011Y205441D02*
X1397007Y205439D01*
G01X1397014Y205442D02*
X1397011Y205441D01*
G01X1397017Y205443D02*
X1397014Y205442D01*
G01X1397020Y205444D02*
X1397017Y205443D01*
G01X1397024Y205444D02*
X1397020D01*
G01X1397028D02*
X1397024D01*
G01X1397950Y207394D02*
X1397953Y207396D01*
G01X1397947Y207393D02*
X1397950Y207394D01*
G01X1397944Y207392D02*
X1397947Y207393D01*
G01X1397940Y207391D02*
X1397944Y207392D01*
G01X1397937Y207391D02*
X1397940D01*
G01X1397933D02*
X1397937D01*
G01X1397011Y208591D02*
X1397007Y208589D01*
G01X1397014Y208592D02*
X1397011Y208591D01*
G01X1397017Y208593D02*
X1397014Y208592D01*
G01X1397020Y208593D02*
X1397017D01*
G01X1397024Y208594D02*
X1397020Y208593D01*
G01X1397028Y208594D02*
X1397024D01*
G01X1397950Y210544D02*
X1397953Y210545D01*
G01X1397947Y210543D02*
X1397950Y210544D01*
G01X1397944Y210541D02*
X1397947Y210543D01*
G01X1397940Y210541D02*
X1397944D01*
G01X1397937Y210540D02*
X1397940Y210541D01*
G01X1397933Y210540D02*
X1397937D01*
G01X1397011Y211740D02*
X1397007Y211739D01*
G01X1397014Y211741D02*
X1397011Y211740D01*
G01X1397017Y211743D02*
X1397014Y211741D01*
G01X1397020Y211743D02*
X1397017D01*
G01X1397024Y211744D02*
X1397020Y211743D01*
G01X1397028Y211744D02*
X1397024D01*
G01X1397963Y199132D02*
X1397967Y199127D01*
G01X1397958Y199137D02*
X1397963Y199132D01*
G01X1397952Y199141D02*
X1397958Y199137D01*
G01X1397946Y199143D02*
X1397952Y199141D01*
G01X1397940Y199145D02*
X1397946Y199143D01*
G01X1397933Y199145D02*
X1397940D01*
G01X1397963Y202282D02*
X1397967Y202277D01*
G01X1397958Y202286D02*
X1397963Y202282D01*
G01X1397952Y202290D02*
X1397958Y202286D01*
G01X1397946Y202293D02*
X1397952Y202290D01*
G01X1397940Y202294D02*
X1397946Y202293D01*
G01X1397933Y202295D02*
X1397940Y202294D01*
G01X1397963Y205431D02*
X1397967Y205426D01*
G01X1397958Y205436D02*
X1397963Y205431D01*
G01X1397952Y205440D02*
X1397958Y205436D01*
G01X1397946Y205442D02*
X1397952Y205440D01*
G01X1397940Y205444D02*
X1397946Y205442D01*
G01X1397933Y205444D02*
X1397940D01*
G01X1397963Y208581D02*
X1397967Y208576D01*
G01X1397958Y208585D02*
X1397963Y208581D01*
G01X1397952Y208589D02*
X1397958Y208585D01*
G01X1397946Y208592D02*
X1397952Y208589D01*
G01X1397940Y208594D02*
X1397946Y208592D01*
G01X1397933Y208594D02*
X1397940D01*
G01X1397963Y211731D02*
X1397967Y211726D01*
G01X1397958Y211735D02*
X1397963Y211731D01*
G01X1397952Y211739D02*
X1397958Y211735D01*
G01X1397946Y211741D02*
X1397952Y211739D01*
G01X1397940Y211743D02*
X1397946Y211741D01*
G01X1397933Y211744D02*
X1397940Y211743D01*
G01X1396989Y197971D02*
X1396988Y197979D01*
G01X1396991Y197965D02*
X1396989Y197971D01*
G01X1396995Y197958D02*
X1396991Y197965D01*
G01X1397000Y197952D02*
X1396995Y197958D01*
G01X1397006Y197948D02*
X1397000Y197952D01*
G01X1397013Y197944D02*
X1397006Y197948D01*
G01X1397020Y197943D02*
X1397013Y197944D01*
G01X1397028Y197942D02*
X1397020Y197943D01*
G01X1396989Y201121D02*
X1396988Y201128D01*
G01X1396991Y201114D02*
X1396989Y201121D01*
G01X1396995Y201108D02*
X1396991Y201114D01*
G01X1397000Y201102D02*
X1396995Y201108D01*
G01X1397006Y201097D02*
X1397000Y201102D01*
G01X1397013Y201094D02*
X1397006Y201097D01*
G01X1397020Y201092D02*
X1397013Y201094D01*
G01X1397028Y201091D02*
X1397020Y201092D01*
G01X1396989Y204270D02*
X1396988Y204278D01*
G01X1396991Y204264D02*
X1396989Y204270D01*
G01X1396995Y204257D02*
X1396991Y204264D01*
G01X1397000Y204252D02*
X1396995Y204257D01*
G01X1397006Y204247D02*
X1397000Y204252D01*
G01X1397013Y204244D02*
X1397006Y204247D01*
G01X1397020Y204242D02*
X1397013Y204244D01*
G01X1397028Y204241D02*
X1397020Y204242D01*
G01X1396989Y207420D02*
X1396988Y207428D01*
G01X1396991Y207413D02*
X1396989Y207420D01*
G01X1396995Y207407D02*
X1396991Y207413D01*
G01X1397000Y207401D02*
X1396995Y207407D01*
G01X1397006Y207396D02*
X1397000Y207401D01*
G01X1397013Y207393D02*
X1397006Y207396D01*
G01X1397020Y207391D02*
X1397013Y207393D01*
G01X1397028Y207391D02*
X1397020D01*
G01X1396989Y210570D02*
X1396988Y210577D01*
G01X1396991Y210563D02*
X1396989Y210570D01*
G01X1396995Y210557D02*
X1396991Y210563D01*
G01X1397000Y210551D02*
X1396995Y210557D01*
G01X1397006Y210546D02*
X1397000Y210551D01*
G01X1397013Y210543D02*
X1397006Y210546D01*
G01X1397020Y210541D02*
X1397013Y210543D01*
G01X1397028Y210540D02*
X1397020Y210541D01*
G01X1397942Y199133D02*
X1397952Y199128D01*
G01X1397931Y199134D02*
X1397942Y199133D01*
G01Y202282D02*
X1397952Y202278D01*
G01X1397931Y202283D02*
X1397942Y202282D01*
G01Y205432D02*
X1397952Y205428D01*
G01X1397931Y205433D02*
X1397942Y205432D01*
G01Y208581D02*
X1397952Y208577D01*
G01X1397931Y208583D02*
X1397942Y208581D01*
G01Y211731D02*
X1397952Y211727D01*
G01X1397931Y211732D02*
X1397942Y211731D01*
G01X1396988Y201132D02*
Y201128D01*
G01X1396990Y201126D02*
X1396988Y201132D01*
G01X1397002Y201111D02*
X1396990Y201126D01*
G01X1397026Y201102D02*
X1397002Y201111D01*
G01X1396988Y204282D02*
Y204278D01*
G01X1396990Y204276D02*
X1396988Y204282D01*
G01X1397001Y204260D02*
X1396990Y204276D01*
G01X1397026Y204252D02*
X1397001Y204260D01*
G01X1396988Y210581D02*
Y210577D01*
G01X1396990Y210575D02*
X1396988Y210581D01*
G01X1397001Y210559D02*
X1396990Y210575D01*
G01X1397026Y210551D02*
X1397001Y210559D01*
G01X1396988Y197983D02*
Y197979D01*
G01X1396990Y197976D02*
X1396988Y197983D01*
G01X1397001Y197961D02*
X1396990Y197976D01*
G01X1397026Y197953D02*
X1397001Y197961D01*
G01X1411385Y166173D02*
X1411396Y166157D01*
G01X1411361Y166181D02*
X1411385Y166173D01*
G01Y171173D02*
X1411396Y171157D01*
G01X1411361Y171181D02*
X1411385Y171173D01*
G01Y176173D02*
X1411396Y176157D01*
G01X1411361Y176181D02*
X1411385Y176173D01*
G01Y181173D02*
X1411396Y181157D01*
G01X1411361Y181181D02*
X1411385Y181173D01*
G01Y186173D02*
X1411396Y186157D01*
G01X1411361Y186181D02*
X1411385Y186173D01*
G01Y191173D02*
X1411396Y191157D01*
G01X1411361Y191181D02*
X1411385Y191173D01*
G01Y196173D02*
X1411396Y196157D01*
G01X1411361Y196181D02*
X1411385Y196173D01*
G01X1396988Y207431D02*
Y207428D01*
G01X1396989Y207426D02*
X1396988Y207431D01*
G01X1397000Y207411D02*
X1396989Y207426D01*
G01X1397023Y207402D02*
X1397000Y207411D01*
G01X1397941Y205432D02*
X1397931Y205433D01*
G01X1397950Y205429D02*
X1397941Y205432D01*
G01X1397957Y205424D02*
X1397950Y205429D01*
G01X1397941Y199133D02*
X1397931Y199134D01*
G01X1397950Y199130D02*
X1397941Y199133D01*
G01X1397957Y199124D02*
X1397950Y199130D01*
G01X1397941Y202282D02*
X1397931Y202283D01*
G01X1397950Y202279D02*
X1397941Y202282D01*
G01X1397957Y202274D02*
X1397950Y202279D01*
G01X1397941Y208581D02*
X1397931Y208583D01*
G01X1397950Y208578D02*
X1397941Y208581D01*
G01X1397957Y208573D02*
X1397950Y208578D01*
G01X1397941Y211731D02*
X1397931Y211732D01*
G01X1397950Y211728D02*
X1397941Y211731D01*
G01X1397957Y211723D02*
X1397950Y211728D01*
G01X1397027Y197948D02*
X1397028Y197942D01*
G01X1397026Y197952D02*
X1397027Y197948D01*
G01X1397025Y197953D02*
X1397026Y197952D01*
G01X1397027Y201098D02*
X1397028Y201091D01*
G01X1397026Y201101D02*
X1397027Y201098D01*
G01X1397025Y201102D02*
X1397026Y201101D01*
G01X1397027Y204247D02*
X1397028Y204241D01*
G01X1397026Y204251D02*
X1397027Y204247D01*
G01X1397025Y204252D02*
X1397026Y204251D01*
G01X1397027Y207397D02*
X1397028Y207391D01*
G01X1397026Y207400D02*
X1397027Y207397D01*
G01X1397025Y207402D02*
X1397026Y207400D01*
G01X1397027Y210546D02*
X1397028Y210540D01*
G01X1397026Y210550D02*
X1397027Y210546D01*
G01X1397025Y210551D02*
X1397026Y210550D01*
G01X1411398Y166148D02*
Y166156D01*
G01X1411399Y166144D02*
X1411398Y166148D01*
G01X1411400Y166142D02*
X1411399Y166144D01*
G01X1411398Y171148D02*
Y171156D01*
G01X1411399Y171144D02*
X1411398Y171148D01*
G01X1411400Y171142D02*
X1411399Y171144D01*
G01X1411398Y176148D02*
Y176156D01*
G01X1411399Y176144D02*
X1411398Y176148D01*
G01X1411400Y176142D02*
X1411399Y176144D01*
G01X1411398Y181148D02*
Y181156D01*
G01X1411399Y181144D02*
X1411398Y181148D01*
G01X1411400Y181142D02*
X1411399Y181144D01*
G01X1411398Y186148D02*
Y186156D01*
G01X1411399Y186144D02*
X1411398Y186148D01*
G01X1411400Y186142D02*
X1411399Y186144D01*
G01X1411398Y191148D02*
Y191156D01*
G01X1411399Y191144D02*
X1411398Y191148D01*
G01X1411400Y191142D02*
X1411399Y191144D01*
G01X1411398Y196148D02*
Y196156D01*
G01X1411399Y196144D02*
X1411398Y196148D01*
G01X1411400Y196142D02*
X1411399Y196144D01*
G01X1397011Y201105D02*
X1397025Y201102D01*
G01X1397000Y201112D02*
X1397011Y201105D01*
G01X1396987Y201131D02*
X1397000Y201112D01*
G01X1397011Y210554D02*
X1397025Y210551D01*
G01X1396999Y210561D02*
X1397011Y210554D01*
G01X1396987Y210580D02*
X1396999Y210561D01*
G01X1397011Y204255D02*
X1397025Y204252D01*
G01X1396998Y204263D02*
X1397011Y204255D01*
G01X1396987Y204283D02*
X1396998Y204263D01*
G01X1397972Y197986D02*
Y197979D01*
G01Y197991D02*
Y197986D01*
G01X1397971Y197992D02*
X1397972Y197991D01*
G01Y201136D02*
Y201128D01*
G01Y201141D02*
Y201136D01*
G01X1397971Y201142D02*
X1397972Y201141D01*
G01Y204285D02*
Y204278D01*
G01Y204290D02*
Y204285D01*
G01X1397971Y204291D02*
X1397972Y204290D01*
G01Y207435D02*
Y207428D01*
G01Y207440D02*
Y207435D01*
G01X1397971Y207441D02*
X1397972Y207440D01*
G01Y210585D02*
Y210577D01*
G01Y210589D02*
Y210585D01*
G01X1397971Y210591D02*
X1397972Y210589D01*
G01X1397010Y197956D02*
X1397025Y197953D01*
G01X1396997Y197964D02*
X1397010Y197956D01*
G01X1396987Y197985D02*
X1396997Y197964D01*
G01X1397972Y199115D02*
Y199108D01*
G01X1397970Y199121D02*
X1397972Y199115D01*
G01X1397967Y199127D02*
X1397970Y199121D01*
G01X1397972Y202265D02*
Y202258D01*
G01X1397970Y202271D02*
X1397972Y202265D01*
G01X1397967Y202277D02*
X1397970Y202271D01*
G01X1397972Y205414D02*
Y205407D01*
G01X1397970Y205420D02*
X1397972Y205414D01*
G01X1397967Y205426D02*
X1397970Y205420D01*
G01X1397972Y208564D02*
Y208557D01*
G01X1397970Y208570D02*
X1397972Y208564D01*
G01X1397967Y208576D02*
X1397970Y208570D01*
G01X1397972Y211713D02*
Y211707D01*
G01X1397970Y211720D02*
X1397972Y211713D01*
G01X1397967Y211726D02*
X1397970Y211720D01*
G01X1397933Y197948D02*
X1397934Y197942D01*
G01X1397932Y197952D02*
X1397933Y197948D01*
G01X1397931Y197953D02*
X1397932Y197952D01*
G01X1397933Y201097D02*
X1397934Y201091D01*
G01X1397932Y201101D02*
X1397933Y201097D01*
G01X1397931Y201102D02*
X1397932Y201101D01*
G01X1397933Y204247D02*
X1397934Y204241D01*
G01X1397932Y204251D02*
X1397933Y204247D01*
G01X1397931Y204252D02*
X1397932Y204251D01*
G01X1397933Y207396D02*
X1397934Y207391D01*
G01X1397932Y207400D02*
X1397933Y207396D01*
G01X1397931Y207402D02*
X1397932Y207400D01*
G01X1397933Y210546D02*
X1397934Y210540D01*
G01X1397932Y210550D02*
X1397933Y210546D01*
G01X1397931Y210551D02*
X1397932Y210550D01*
G01X1410413Y166189D02*
Y166198D01*
G01X1410414Y166183D02*
X1410413Y166189D01*
G01X1410415Y166181D02*
X1410414Y166183D01*
G01X1410413Y171189D02*
Y171198D01*
G01X1410414Y171183D02*
X1410413Y171189D01*
G01X1410415Y171181D02*
X1410414Y171183D01*
G01X1410413Y176189D02*
Y176198D01*
G01X1410414Y176183D02*
X1410413Y176189D01*
G01X1410415Y176181D02*
X1410414Y176183D01*
G01X1410413Y181189D02*
Y181198D01*
G01X1410414Y181183D02*
X1410413Y181189D01*
G01X1410415Y181181D02*
X1410414Y181183D01*
G01X1410413Y186189D02*
Y186198D01*
G01X1410414Y186183D02*
X1410413Y186189D01*
G01X1410415Y186181D02*
X1410414Y186183D01*
G01X1410413Y191189D02*
Y191198D01*
G01X1410414Y191183D02*
X1410413Y191189D01*
G01X1410415Y191181D02*
X1410414Y191183D01*
G01X1410413Y196189D02*
Y196198D01*
G01X1410414Y196183D02*
X1410413Y196189D01*
G01X1410415Y196181D02*
X1410414Y196183D01*
G01X1411390Y166325D02*
X1411398Y166299D01*
G01X1411380Y166352D02*
X1411390Y166325D01*
G01X1411369Y166378D02*
X1411380Y166352D01*
G01X1411390Y171325D02*
X1411398Y171299D01*
G01X1411380Y171352D02*
X1411390Y171325D01*
G01X1411369Y171378D02*
X1411380Y171352D01*
G01X1411390Y176325D02*
X1411398Y176299D01*
G01X1411380Y176352D02*
X1411390Y176325D01*
G01X1411369Y176378D02*
X1411380Y176352D01*
G01X1411390Y181325D02*
X1411398Y181299D01*
G01X1411380Y181352D02*
X1411390Y181325D01*
G01X1411369Y181378D02*
X1411380Y181352D01*
G01X1411390Y186325D02*
X1411398Y186299D01*
G01X1411380Y186352D02*
X1411390Y186325D01*
G01X1411369Y186378D02*
X1411380Y186352D01*
G01X1411390Y191325D02*
X1411398Y191299D01*
G01X1411380Y191352D02*
X1411390Y191325D01*
G01X1411369Y191378D02*
X1411380Y191352D01*
G01X1411390Y196325D02*
X1411398Y196299D01*
G01X1411380Y196352D02*
X1411390Y196325D01*
G01X1411369Y196378D02*
X1411380Y196352D01*
G01X1397006Y207407D02*
X1397025Y207402D01*
G01X1396993Y207419D02*
X1397006Y207407D01*
G01X1396986Y207437D02*
X1396993Y207419D01*
G01X1411380Y166176D02*
X1411361Y166181D01*
G01X1411395Y166162D02*
X1411380Y166176D01*
G01X1411400Y166142D02*
X1411395Y166162D01*
G01X1411380Y171176D02*
X1411361Y171181D01*
G01X1411395Y171162D02*
X1411380Y171176D01*
G01X1411400Y171142D02*
X1411395Y171162D01*
G01X1411380Y176176D02*
X1411361Y176181D01*
G01X1411395Y176162D02*
X1411380Y176176D01*
G01X1411400Y176142D02*
X1411395Y176162D01*
G01X1411380Y181176D02*
X1411361Y181181D01*
G01X1411395Y181162D02*
X1411380Y181176D01*
G01X1411400Y181142D02*
X1411395Y181162D01*
G01X1411380Y186176D02*
X1411361Y186181D01*
G01X1411395Y186162D02*
X1411380Y186176D01*
G01X1411400Y186142D02*
X1411395Y186162D01*
G01X1411380Y191176D02*
X1411361Y191181D01*
G01X1411395Y191162D02*
X1411380Y191176D01*
G01X1411400Y191142D02*
X1411395Y191162D01*
G01X1411380Y196176D02*
X1411361Y196181D01*
G01X1411395Y196162D02*
X1411380Y196176D01*
G01X1411400Y196142D02*
X1411395Y196162D01*
G01X1397965Y205415D02*
X1397957Y205424D01*
G01X1397969Y205405D02*
X1397965Y205415D01*
G01X1397971Y205394D02*
X1397969Y205405D01*
G01X1397965Y199116D02*
X1397957Y199124D01*
G01X1397970Y199106D02*
X1397965Y199116D01*
G01X1397971Y199094D02*
X1397970Y199106D01*
G01X1397965Y202265D02*
X1397957Y202274D01*
G01X1397970Y202255D02*
X1397965Y202265D01*
G01X1397971Y202244D02*
X1397970Y202255D01*
G01X1397965Y208565D02*
X1397957Y208573D01*
G01X1397970Y208554D02*
X1397965Y208565D01*
G01X1397971Y208543D02*
X1397970Y208554D01*
G01X1397965Y211714D02*
X1397957Y211723D01*
G01X1397970Y211704D02*
X1397965Y211714D01*
G01X1397971Y211693D02*
X1397970Y211704D01*
G01X1411365Y166279D02*
X1411369Y166378D01*
G01X1411359Y166207D02*
X1411365Y166279D01*
G01X1411361Y166181D02*
X1411359Y166207D01*
G01X1411365Y171279D02*
X1411369Y171378D01*
G01X1411359Y171207D02*
X1411365Y171279D01*
G01X1411361Y171181D02*
X1411359Y171207D01*
G01X1411365Y176279D02*
X1411369Y176378D01*
G01X1411359Y176207D02*
X1411365Y176279D01*
G01X1411361Y176181D02*
X1411359Y176207D01*
G01X1411365Y181279D02*
X1411369Y181378D01*
G01X1411359Y181207D02*
X1411365Y181279D01*
G01X1411361Y181181D02*
X1411359Y181207D01*
G01X1411365Y186279D02*
X1411369Y186378D01*
G01X1411359Y186207D02*
X1411365Y186279D01*
G01X1411361Y186181D02*
X1411359Y186207D01*
G01X1411365Y191279D02*
X1411369Y191378D01*
G01X1411359Y191207D02*
X1411365Y191279D01*
G01X1411361Y191181D02*
X1411359Y191207D01*
G01X1411365Y196279D02*
X1411369Y196378D01*
G01X1411359Y196207D02*
X1411365Y196279D01*
G01X1411361Y196181D02*
X1411359Y196207D01*
G01X1396988Y210585D02*
Y210577D01*
G01X1396987Y210589D02*
X1396988Y210585D01*
G01X1396987Y210580D02*
Y210589D01*
G01X1397028Y211917D02*
Y211929D01*
G01X1397025Y211904D02*
X1397028Y211917D01*
G01X1397025Y211890D02*
Y211904D01*
G01X1397028Y208767D02*
Y208780D01*
G01X1397025Y208754D02*
X1397028Y208767D01*
G01X1397025Y208741D02*
Y208754D01*
G01X1397028Y205618D02*
Y205630D01*
G01X1397025Y205605D02*
X1397028Y205618D01*
G01X1397025Y205591D02*
Y205605D01*
G01X1397028Y202468D02*
Y202480D01*
G01X1397025Y202455D02*
X1397028Y202468D01*
G01X1397025Y202441D02*
Y202455D01*
G01X1397028Y199319D02*
Y199331D01*
G01X1397025Y199306D02*
X1397028Y199319D01*
G01X1397025Y199292D02*
Y199306D01*
G01X1410414Y194802D02*
X1410415Y194803D01*
G01X1410413Y194796D02*
X1410414Y194802D01*
G01X1410413Y194787D02*
Y194796D01*
G01X1410414Y189802D02*
X1410415Y189803D01*
G01X1410413Y189796D02*
X1410414Y189802D01*
G01X1410413Y189787D02*
Y189796D01*
G01X1410414Y184802D02*
X1410415Y184803D01*
G01X1410413Y184796D02*
X1410414Y184802D01*
G01X1410413Y184787D02*
Y184796D01*
G01X1410414Y179802D02*
X1410415Y179803D01*
G01X1410413Y179796D02*
X1410414Y179802D01*
G01X1410413Y179787D02*
Y179796D01*
G01X1410414Y174802D02*
X1410415Y174803D01*
G01X1410413Y174796D02*
X1410414Y174802D01*
G01X1410413Y174787D02*
Y174796D01*
G01X1410414Y169802D02*
X1410415Y169803D01*
G01X1410413Y169796D02*
X1410414Y169802D01*
G01X1410413Y169787D02*
Y169796D01*
G01X1410414Y164802D02*
X1410415Y164803D01*
G01X1410413Y164796D02*
X1410414Y164802D01*
G01X1410413Y164787D02*
Y164796D01*
G01X1397025Y210380D02*
X1397024Y210393D01*
G01X1397028Y210367D02*
X1397025Y210380D01*
G01X1397028Y210354D02*
Y210367D01*
G01X1397025Y207230D02*
X1397024Y207244D01*
G01X1397028Y207217D02*
X1397025Y207230D01*
G01X1397028Y207205D02*
Y207217D01*
G01X1397025Y204081D02*
X1397024Y204094D01*
G01X1397028Y204068D02*
X1397025Y204081D01*
G01X1397028Y204055D02*
Y204068D01*
G01X1397025Y200931D02*
X1397024Y200944D01*
G01X1397028Y200918D02*
X1397025Y200931D01*
G01X1397028Y200906D02*
Y200918D01*
G01X1397025Y197781D02*
X1397024Y197795D01*
G01X1397028Y197769D02*
X1397025Y197781D01*
G01X1397028Y197756D02*
Y197769D01*
G01X1397935Y211904D02*
X1397937Y211890D01*
G01X1397932Y211917D02*
X1397935Y211904D01*
G01X1397933Y211929D02*
X1397932Y211917D01*
G01X1397935Y208754D02*
X1397937Y208741D01*
G01X1397932Y208767D02*
X1397935Y208754D01*
G01X1397933Y208780D02*
X1397932Y208767D01*
G01X1397935Y205604D02*
X1397937Y205591D01*
G01X1397932Y205617D02*
X1397935Y205604D01*
G01X1397933Y205630D02*
X1397932Y205617D01*
G01X1397935Y202455D02*
X1397937Y202441D01*
G01X1397932Y202468D02*
X1397935Y202455D01*
G01X1397933Y202480D02*
X1397932Y202468D01*
G01X1397935Y199305D02*
X1397937Y199292D01*
G01X1397932Y199318D02*
X1397935Y199305D01*
G01X1397933Y199331D02*
X1397932Y199318D01*
G01X1396988Y204285D02*
Y204278D01*
G01X1396987Y204290D02*
X1396988Y204285D01*
G01X1396987Y204283D02*
Y204290D01*
G01X1397932Y210367D02*
X1397933Y210354D01*
G01X1397935Y210380D02*
X1397932Y210367D01*
G01X1397936Y210393D02*
X1397935Y210380D01*
G01X1397932Y207217D02*
X1397933Y207205D01*
G01X1397935Y207230D02*
X1397932Y207217D01*
G01X1397936Y207244D02*
X1397935Y207230D01*
G01X1397932Y204068D02*
X1397933Y204055D01*
G01X1397935Y204081D02*
X1397932Y204068D01*
G01X1397936Y204094D02*
X1397935Y204081D01*
G01X1397932Y200918D02*
X1397933Y200906D01*
G01X1397935Y200931D02*
X1397932Y200918D01*
G01X1397936Y200944D02*
X1397935Y200931D01*
G01X1397932Y197769D02*
X1397933Y197756D01*
G01X1397935Y197781D02*
X1397932Y197769D01*
G01X1397936Y197795D02*
X1397935Y197781D01*
G01X1396988Y197987D02*
Y197979D01*
G01X1396987Y197991D02*
X1396988Y197987D01*
G01X1396987Y197985D02*
Y197991D01*
G01X1397001Y211724D02*
X1397025Y211732D01*
G01X1396990Y211709D02*
X1397001Y211724D01*
G01X1396988Y211703D02*
X1396990Y211709D01*
G01X1397001Y208574D02*
X1397025Y208583D01*
G01X1396990Y208560D02*
X1397001Y208574D01*
G01X1396988Y208553D02*
X1396990Y208560D01*
G01X1397001Y205425D02*
X1397025Y205433D01*
G01X1396990Y205410D02*
X1397001Y205425D01*
G01X1396988Y205404D02*
X1396990Y205410D01*
G01X1397001Y202275D02*
X1397025Y202283D01*
G01X1396990Y202261D02*
X1397001Y202275D01*
G01X1396988Y202254D02*
X1396990Y202261D01*
G01X1397001Y199126D02*
X1397025Y199134D01*
G01X1396990Y199111D02*
X1397001Y199126D01*
G01X1396988Y199104D02*
X1396990Y199111D01*
G01X1397972Y211699D02*
Y211706D01*
G01Y211695D02*
Y211699D01*
G01X1397971Y211693D02*
X1397972Y211695D01*
G01Y208550D02*
Y208557D01*
G01Y208545D02*
Y208550D01*
G01X1397971Y208543D02*
X1397972Y208545D01*
G01Y205400D02*
Y205407D01*
G01Y205396D02*
Y205400D01*
G01X1397971Y205394D02*
X1397972Y205396D01*
G01Y202250D02*
Y202257D01*
G01Y202246D02*
Y202250D01*
G01X1397971Y202244D02*
X1397972Y202246D01*
G01Y199101D02*
Y199108D01*
G01Y199096D02*
Y199101D01*
G01X1397971Y199094D02*
X1397972Y199096D01*
G01X1396988Y207435D02*
Y207428D01*
G01X1396987Y207440D02*
X1396988Y207435D01*
G01X1396986Y207437D02*
X1396987Y207440D01*
G01X1396988Y201136D02*
Y201128D01*
G01X1396987Y201141D02*
X1396988Y201136D01*
G01X1396986Y201138D02*
X1396987Y201141D01*
G01X1397933Y211737D02*
Y211744D01*
G01X1397932Y211734D02*
X1397933Y211737D01*
G01X1397931Y211732D02*
X1397932Y211734D01*
G01X1397933Y208588D02*
Y208594D01*
G01X1397932Y208584D02*
X1397933Y208588D01*
G01X1397931Y208583D02*
X1397932Y208584D01*
G01X1397933Y205438D02*
Y205444D01*
G01X1397932Y205435D02*
X1397933Y205438D01*
G01X1397931Y205433D02*
X1397932Y205435D01*
G01X1397933Y202289D02*
Y202295D01*
G01X1397932Y202285D02*
X1397933Y202289D01*
G01X1397931Y202283D02*
X1397932Y202285D01*
G01X1397933Y199139D02*
Y199145D01*
G01X1397932Y199135D02*
X1397933Y199139D01*
G01X1397931Y199134D02*
X1397932Y199135D01*
G01X1411398Y194796D02*
Y194787D01*
G01X1411399Y194802D02*
X1411398Y194796D01*
G01X1411400Y194803D02*
X1411399Y194802D01*
G01X1411398Y189796D02*
Y189787D01*
G01X1411399Y189802D02*
X1411398Y189796D01*
G01X1411400Y189803D02*
X1411399Y189802D01*
G01X1411398Y184796D02*
Y184787D01*
G01X1411399Y184802D02*
X1411398Y184796D01*
G01X1411400Y184803D02*
X1411399Y184802D01*
G01X1411398Y179796D02*
Y179787D01*
G01X1411399Y179802D02*
X1411398Y179796D01*
G01X1411400Y179803D02*
X1411399Y179802D01*
G01X1411398Y174796D02*
Y174787D01*
G01X1411399Y174802D02*
X1411398Y174796D01*
G01X1411400Y174803D02*
X1411399Y174802D01*
G01X1396988Y211699D02*
Y211707D01*
G01X1396987Y211694D02*
X1396988Y211699D01*
G01X1396986Y211693D02*
X1396987Y211694D01*
G01X1396988Y208550D02*
Y208557D01*
G01X1396987Y208545D02*
X1396988Y208550D01*
G01X1396986Y208543D02*
X1396987Y208545D01*
G01X1396988Y205400D02*
Y205407D01*
G01X1396987Y205395D02*
X1396988Y205400D01*
G01X1396986Y205394D02*
X1396987Y205395D01*
G01X1396988Y202250D02*
Y202258D01*
G01X1396987Y202246D02*
X1396988Y202250D01*
G01X1396986Y202244D02*
X1396987Y202246D01*
G01X1396988Y199101D02*
Y199108D01*
G01X1396987Y199096D02*
X1396988Y199101D01*
G01X1396986Y199094D02*
X1396987Y199096D01*
G01X1397970Y210565D02*
X1397972Y210577D01*
G01X1397963Y210554D02*
X1397970Y210565D01*
G01X1397953Y210545D02*
X1397963Y210554D01*
G01X1397970Y207415D02*
X1397972Y207428D01*
G01X1397963Y207404D02*
X1397970Y207415D01*
G01X1397953Y207396D02*
X1397963Y207404D01*
G01X1397970Y204265D02*
X1397972Y204278D01*
G01X1397963Y204254D02*
X1397970Y204265D01*
G01X1397953Y204246D02*
X1397963Y204254D01*
G01X1397970Y201116D02*
X1397972Y201128D01*
G01X1397963Y201105D02*
X1397970Y201116D01*
G01X1397953Y201096D02*
X1397963Y201105D01*
G01X1397970Y197966D02*
X1397972Y197979D01*
G01X1397963Y197955D02*
X1397970Y197966D01*
G01X1397953Y197947D02*
X1397963Y197955D01*
G01X1397027Y211737D02*
Y211744D01*
G01Y211733D02*
Y211737D01*
G01X1397025Y211732D02*
X1397027Y211733D01*
G01Y208588D02*
Y208594D01*
G01Y208584D02*
Y208588D01*
G01X1397025Y208583D02*
X1397027Y208584D01*
G01Y205438D02*
Y205444D01*
G01Y205434D02*
Y205438D01*
G01X1397025Y205433D02*
X1397027Y205434D01*
G01Y202289D02*
Y202295D01*
G01Y202285D02*
Y202289D01*
G01X1397025Y202283D02*
X1397027Y202285D01*
G01Y199139D02*
Y199145D01*
G01Y199135D02*
Y199139D01*
G01X1397025Y199134D02*
X1397027Y199135D01*
G01X1396989Y211713D02*
X1396988Y211707D01*
G01X1396991Y211719D02*
X1396989Y211713D01*
G01X1396993Y211725D02*
X1396991Y211719D01*
G01X1396997Y211730D02*
X1396993Y211725D01*
G01X1397002Y211735D02*
X1396997Y211730D01*
G01X1397007Y211739D02*
X1397002Y211735D01*
G01X1396989Y208563D02*
X1396988Y208557D01*
G01X1396991Y208570D02*
X1396989Y208563D01*
G01X1396993Y208575D02*
X1396991Y208570D01*
G01X1396997Y208581D02*
X1396993Y208575D01*
G01X1397002Y208585D02*
X1396997Y208581D01*
G01X1397007Y208589D02*
X1397002Y208585D01*
G01X1396989Y205414D02*
X1396988Y205407D01*
G01X1396991Y205420D02*
X1396989Y205414D01*
G01X1396993Y205426D02*
X1396991Y205420D01*
G01X1396997Y205431D02*
X1396993Y205426D01*
G01X1397002Y205435D02*
X1396997Y205431D01*
G01X1397007Y205439D02*
X1397002Y205435D01*
G01X1396989Y202264D02*
X1396988Y202258D01*
G01X1396991Y202270D02*
X1396989Y202264D01*
G01X1396993Y202276D02*
X1396991Y202270D01*
G01X1396997Y202281D02*
X1396993Y202276D01*
G01X1397002Y202286D02*
X1396997Y202281D01*
G01X1397007Y202290D02*
X1397002Y202286D01*
G01X1396989Y199115D02*
X1396988Y199108D01*
G01X1396991Y199121D02*
X1396989Y199115D01*
G01X1396993Y199126D02*
X1396991Y199121D01*
G01X1396997Y199132D02*
X1396993Y199126D01*
G01X1397002Y199136D02*
X1396997Y199132D01*
G01X1397007Y199140D02*
X1397002Y199136D01*
G01X1397944Y210553D02*
X1397931Y210551D01*
G01X1397954Y210558D02*
X1397944Y210553D01*
G01Y207404D02*
X1397931Y207402D01*
G01X1397954Y207409D02*
X1397944Y207404D01*
G01Y204254D02*
X1397931Y204252D01*
G01X1397954Y204259D02*
X1397944Y204254D01*
G01Y201104D02*
X1397931Y201102D01*
G01X1397954Y201109D02*
X1397944Y201104D01*
G01Y197955D02*
X1397931Y197953D01*
G01X1397954Y197960D02*
X1397944Y197955D01*
G01X1411398Y169796D02*
Y169787D01*
G01X1411399Y169802D02*
X1411398Y169796D01*
G01X1411400Y169803D02*
X1411399Y169802D01*
G01X1411398Y164796D02*
Y164787D01*
G01X1411399Y164802D02*
X1411398Y164796D01*
G01X1411400Y164803D02*
X1411399Y164802D01*
G01X1397972Y199097D02*
Y199108D01*
G01Y202246D02*
Y202257D01*
G01Y205396D02*
Y205407D01*
G01Y208546D02*
Y208557D01*
G01Y211695D02*
Y211706D01*
G01X1411398Y166155D02*
Y166164D01*
G01Y171155D02*
Y171164D01*
G01Y176155D02*
Y176164D01*
G01Y181155D02*
Y181164D01*
G01Y186155D02*
Y186164D01*
G01Y191155D02*
Y191164D01*
G01Y196155D02*
Y196164D01*
G01X1415748Y194803D02*
Y196181D01*
G01Y189803D02*
Y191181D01*
G01Y184803D02*
Y186181D01*
G01Y179803D02*
Y181181D01*
G01Y174803D02*
Y176181D01*
G01Y169803D02*
Y171181D01*
G01Y164803D02*
Y166181D01*
G01X1412579D02*
Y164803D01*
G01Y171181D02*
Y169803D01*
G01Y176181D02*
Y174803D01*
G01Y181181D02*
Y179803D01*
G01Y186181D02*
Y184803D01*
G01Y191181D02*
Y189803D01*
G01Y196181D02*
Y194803D01*
G01X1412008Y219035D02*
Y196949D01*
G01X1411398Y166156D02*
Y166299D01*
G01Y171156D02*
Y171299D01*
G01Y176156D02*
Y176299D01*
G01Y181156D02*
Y181299D01*
G01Y186156D02*
Y186299D01*
G01Y191156D02*
Y191299D01*
G01Y196156D02*
Y196299D01*
G01Y194311D02*
Y196673D01*
G01Y189311D02*
Y191673D01*
G01Y184311D02*
Y186673D01*
G01Y179311D02*
Y181673D01*
G01Y174311D02*
Y176673D01*
G01Y169311D02*
Y171673D01*
G01Y164311D02*
Y166673D01*
G01X1410827Y217854D02*
Y198130D01*
G01X1410413Y166673D02*
Y164311D01*
G01Y171673D02*
Y169311D01*
G01Y176673D02*
Y174311D01*
G01Y181673D02*
Y179311D01*
G01Y186673D02*
Y184311D01*
G01Y191673D02*
Y189311D01*
G01Y196673D02*
Y194311D01*
G01X1397972Y210394D02*
Y211890D01*
G01Y207244D02*
Y208740D01*
G01Y204094D02*
Y205591D01*
G01Y200945D02*
Y202441D01*
G01Y197795D02*
Y199291D01*
G01X1397933Y197942D02*
Y197795D01*
G01Y201091D02*
Y200944D01*
G01Y202441D02*
Y202295D01*
G01Y199292D02*
Y199145D01*
G01Y207391D02*
Y207244D01*
G01Y204241D02*
Y204094D01*
G01Y205591D02*
Y205444D01*
G01Y210540D02*
Y210393D01*
G01Y211890D02*
Y211744D01*
G01Y208741D02*
Y208594D01*
G01X1397028Y210393D02*
Y210540D01*
G01Y211744D02*
Y211891D01*
G01Y208594D02*
Y208741D01*
G01Y207243D02*
Y207391D01*
G01Y204094D02*
Y204241D01*
G01Y205444D02*
Y205591D01*
G01Y200944D02*
Y201091D01*
G01Y202295D02*
Y202442D01*
G01Y199145D02*
Y199292D01*
G01Y197794D02*
Y197942D01*
G01X1396988Y202441D02*
Y200945D01*
G01Y199291D02*
Y197795D01*
G01Y205591D02*
Y204094D01*
G01Y211890D02*
Y210394D01*
G01Y208740D02*
Y207244D01*
G01X1395807Y199134D02*
Y197953D01*
G01Y202283D02*
Y201102D01*
G01Y208583D02*
Y207402D01*
G01Y205433D02*
Y204252D01*
G01Y211732D02*
Y210551D01*
G01X1395472Y220197D02*
Y195787D01*
G01X1395079D02*
Y220197D01*
G01X1392047Y210551D02*
Y211732D01*
G01Y207402D02*
Y208583D01*
G01Y204252D02*
Y205433D01*
G01Y201102D02*
Y202283D01*
G01Y197953D02*
Y199134D01*
G01X1397972Y210577D02*
Y210588D01*
G01Y207428D02*
Y207439D01*
G01Y204278D02*
Y204289D01*
G01Y201128D02*
Y201139D01*
G01Y197979D02*
Y197990D01*
G01X1410827Y198130D02*
X1412008Y196949D01*
G01X1406890Y198130D02*
X1408071Y196949D01*
G01X1396986Y207437D02*
X1396875Y207441D01*
G01X1396986Y201138D02*
X1396875Y201142D01*
G01X1396986Y210587D02*
X1396875Y210591D01*
G01X1397933Y211929D02*
X1397028D01*
G01X1397972Y211890D02*
X1396988D01*
G01X1397931Y211732D02*
X1392047D01*
G01Y211693D02*
X1397971D01*
G01X1396241Y210591D02*
X1395807D01*
G01X1397971D02*
X1392047D01*
G01X1397931Y210551D02*
X1392047D01*
G01X1396988Y210394D02*
X1397972D01*
G01X1397028Y210354D02*
X1397933D01*
G01Y208780D02*
X1397028D01*
G01X1397972Y208740D02*
X1396988D01*
G01X1397931Y208583D02*
X1392047D01*
G01Y208543D02*
X1397971D01*
G01X1396241Y207441D02*
X1395807D01*
G01X1397971D02*
X1392047D01*
G01X1397931Y207402D02*
X1392047D01*
G01X1396988Y207244D02*
X1397972D01*
G01X1397028Y207205D02*
X1397933D01*
G01Y205630D02*
X1397028D01*
G01X1397972Y205591D02*
X1396988D01*
G01X1397931Y205433D02*
X1392047D01*
G01Y205394D02*
X1397971D01*
G01Y204291D02*
X1392047D01*
G01X1397931Y204252D02*
X1392047D01*
G01X1396988Y204094D02*
X1397972D01*
G01X1397028Y204055D02*
X1397933D01*
G01Y202480D02*
X1397028D01*
G01X1397972Y202441D02*
X1396988D01*
G01X1397931Y202283D02*
X1392047D01*
G01Y202244D02*
X1397971D01*
G01X1396241Y201142D02*
X1395807D01*
G01X1397971D02*
X1392047D01*
G01X1397931Y201102D02*
X1392047D01*
G01X1396988Y200945D02*
X1397972D01*
G01X1397028Y200906D02*
X1397933D01*
G01Y199331D02*
X1397028D01*
G01X1397972Y199291D02*
X1396988D01*
G01X1397931Y199134D02*
X1392047D01*
G01Y199094D02*
X1397971D01*
G01X1410827Y198130D02*
X1406890D01*
G01X1397971Y197992D02*
X1392047D01*
G01X1397931Y197953D02*
X1392047D01*
G01X1396988Y197795D02*
X1397972D01*
G01X1397028Y197756D02*
X1397933D01*
G01X1412008Y196949D02*
X1408071D01*
G01X1411398Y196673D02*
X1410413D01*
G01X1410415Y196181D02*
X1415748D01*
G01Y196142D02*
X1411400D01*
G01X1398425Y195787D02*
X1395079D01*
G01X1415748Y194803D02*
X1410415D01*
G01X1410413Y194311D02*
X1411398D01*
G01Y191673D02*
X1410413D01*
G01X1410415Y191181D02*
X1415748D01*
G01Y191142D02*
X1411400D01*
G01X1415748Y189803D02*
X1410415D01*
G01X1410413Y189311D02*
X1411398D01*
G01Y186673D02*
X1410413D01*
G01X1410415Y186181D02*
X1415748D01*
G01Y186142D02*
X1411400D01*
G01X1415748Y184803D02*
X1410415D01*
G01X1410413Y184311D02*
X1411398D01*
G01Y181673D02*
X1410413D01*
G01X1410415Y181181D02*
X1415748D01*
G01Y181142D02*
X1411400D01*
G01X1415748Y179803D02*
X1410415D01*
G01X1410413Y179311D02*
X1411398D01*
G01Y176673D02*
X1410413D01*
G01X1410415Y176181D02*
X1415748D01*
G01Y176142D02*
X1411400D01*
G01X1415748Y174803D02*
X1410415D01*
G01X1410413Y174311D02*
X1411398D01*
G01Y171673D02*
X1410413D01*
G01X1410415Y171181D02*
X1415748D01*
G01Y171142D02*
X1411400D01*
G01X1415748Y169803D02*
X1410415D01*
G01X1410413Y169311D02*
X1411398D01*
G01X1410413Y196377D02*
X1411369Y196378D01*
G01X1411398Y194607D02*
X1410413Y194606D01*
G01Y191377D02*
X1411369Y191378D01*
G01X1411398Y189607D02*
X1410413Y189606D01*
G01Y186377D02*
X1411369Y186378D01*
G01X1411398Y184607D02*
X1410413Y184606D01*
G01Y181377D02*
X1411369Y181378D01*
G01X1411398Y179607D02*
X1410413Y179606D01*
G01Y176377D02*
X1411369Y176378D01*
G01X1411398Y174607D02*
X1410413Y174606D01*
G01Y171377D02*
X1411369Y171378D01*
G01X1411398Y169607D02*
X1410413Y169606D01*
G01X1411398Y166673D02*
X1410413D01*
G01X1410415Y166181D02*
X1415748D01*
G01Y166142D02*
X1411400D01*
G01X1415748Y164803D02*
X1410415D01*
G01X1410413Y164311D02*
X1411398D01*
G01X1410413Y166377D02*
X1411369Y166378D01*
G01X1411398Y164607D02*
X1410413Y164606D01*
G01X1396991Y214862D02*
X1396986Y214843D01*
G01X1397006Y214877D02*
X1396991Y214862D01*
G01X1397025Y214882D02*
X1397006Y214877D01*
G01X1396991Y218012D02*
X1396986Y217992D01*
G01X1397006Y218026D02*
X1396991Y218012D01*
G01X1397025Y218031D02*
X1397006Y218026D01*
G01X1397966Y213720D02*
X1397971Y213740D01*
G01X1397951Y213706D02*
X1397966Y213720D01*
G01X1397931Y213701D02*
X1397951Y213706D01*
G01X1397966Y216870D02*
X1397971Y216890D01*
G01X1397951Y216856D02*
X1397966Y216870D01*
G01X1397931Y216850D02*
X1397951Y216856D01*
G01X1397972Y213719D02*
Y213727D01*
G01X1397969Y213713D02*
X1397972Y213719D01*
G01X1397966Y213706D02*
X1397969Y213713D01*
G01X1397961Y213700D02*
X1397966Y213706D01*
G01X1397955Y213696D02*
X1397961Y213700D01*
G01X1397948Y213693D02*
X1397955Y213696D01*
G01X1397941Y213691D02*
X1397948Y213693D01*
G01X1397933Y213690D02*
X1397941Y213691D01*
G01X1397011Y214890D02*
X1397007Y214888D01*
G01X1397014Y214891D02*
X1397011Y214890D01*
G01X1397017Y214892D02*
X1397014Y214891D01*
G01X1397020Y214893D02*
X1397017Y214892D01*
G01X1397024Y214893D02*
X1397020D01*
G01X1397028D02*
X1397024D01*
G01X1397950Y216843D02*
X1397953Y216844D01*
G01X1397947Y216842D02*
X1397950Y216843D01*
G01X1397944Y216841D02*
X1397947Y216842D01*
G01X1397940Y216840D02*
X1397944Y216841D01*
G01X1397937Y216839D02*
X1397940Y216840D01*
G01X1397933Y216839D02*
X1397937D01*
G01X1397011Y218039D02*
X1397007Y218038D01*
G01X1397014Y218041D02*
X1397011Y218039D01*
G01X1397017Y218042D02*
X1397014Y218041D01*
G01X1397020Y218042D02*
X1397017D01*
G01X1397024Y218043D02*
X1397020Y218042D01*
G01X1397028Y218043D02*
X1397024D01*
G01X1397963Y214880D02*
X1397967Y214875D01*
G01X1397958Y214885D02*
X1397963Y214880D01*
G01X1397952Y214889D02*
X1397958Y214885D01*
G01X1397946Y214891D02*
X1397952Y214889D01*
G01X1397940Y214893D02*
X1397946Y214891D01*
G01X1397933Y214893D02*
X1397940D01*
G01X1397963Y218030D02*
X1397967Y218025D01*
G01X1397958Y218034D02*
X1397963Y218030D01*
G01X1397952Y218038D02*
X1397958Y218034D01*
G01X1397946Y218041D02*
X1397952Y218038D01*
G01X1397940Y218043D02*
X1397946Y218041D01*
G01X1397933Y218043D02*
X1397940D01*
G01X1396989Y213719D02*
X1396988Y213727D01*
G01X1396991Y213713D02*
X1396989Y213719D01*
G01X1396995Y213706D02*
X1396991Y213713D01*
G01X1397000Y213700D02*
X1396995Y213706D01*
G01X1397006Y213696D02*
X1397000Y213700D01*
G01X1397013Y213693D02*
X1397006Y213696D01*
G01X1397020Y213691D02*
X1397013Y213693D01*
G01X1397028Y213690D02*
X1397020Y213691D01*
G01X1396989Y216869D02*
X1396988Y216876D01*
G01X1396991Y216862D02*
X1396989Y216869D01*
G01X1396995Y216856D02*
X1396991Y216862D01*
G01X1397000Y216850D02*
X1396995Y216856D01*
G01X1397006Y216845D02*
X1397000Y216850D01*
G01X1397013Y216842D02*
X1397006Y216845D01*
G01X1397020Y216840D02*
X1397013Y216842D01*
G01X1397028Y216839D02*
X1397020Y216840D01*
G01X1397942Y214881D02*
X1397952Y214876D01*
G01X1397931Y214882D02*
X1397942Y214881D01*
G01Y218030D02*
X1397952Y218026D01*
G01X1397931Y218031D02*
X1397942Y218030D01*
G01X1396988Y213731D02*
Y213727D01*
G01X1396990Y213724D02*
X1396988Y213731D01*
G01X1397001Y213709D02*
X1396990Y213724D01*
G01X1397026Y213701D02*
X1397001Y213709D01*
G01X1396988Y216880D02*
Y216876D01*
G01X1396990Y216874D02*
X1396988Y216880D01*
G01X1397001Y216859D02*
X1396990Y216874D01*
G01X1397026Y216850D02*
X1397001Y216859D01*
G01X1411385Y221173D02*
X1411396Y221157D01*
G01X1411361Y221181D02*
X1411385Y221173D01*
G01Y226173D02*
X1411396Y226157D01*
G01X1411361Y226181D02*
X1411385Y226173D01*
G01Y231173D02*
X1411396Y231157D01*
G01X1411361Y231181D02*
X1411385Y231173D01*
G01Y236173D02*
X1411396Y236157D01*
G01X1411361Y236181D02*
X1411385Y236173D01*
G01Y241173D02*
X1411396Y241157D01*
G01X1411361Y241181D02*
X1411385Y241173D01*
G01Y246173D02*
X1411396Y246157D01*
G01X1411361Y246181D02*
X1411385Y246173D01*
G01Y251173D02*
X1411396Y251157D01*
G01X1411361Y251181D02*
X1411385Y251173D01*
G01Y256173D02*
X1411396Y256157D01*
G01X1411361Y256181D02*
X1411385Y256173D01*
G01X1397941Y214881D02*
X1397931Y214882D01*
G01X1397950Y214878D02*
X1397941Y214881D01*
G01X1397957Y214872D02*
X1397950Y214878D01*
G01X1397941Y218030D02*
X1397931Y218031D01*
G01X1397950Y218027D02*
X1397941Y218030D01*
G01X1397957Y218022D02*
X1397950Y218027D01*
G01X1397027Y213696D02*
X1397028Y213690D01*
G01X1397026Y213700D02*
X1397027Y213696D01*
G01X1397025Y213701D02*
X1397026Y213700D01*
G01X1397027Y216846D02*
X1397028Y216839D01*
G01X1397026Y216849D02*
X1397027Y216846D01*
G01X1397025Y216850D02*
X1397026Y216849D01*
G01X1411398Y221148D02*
Y221156D01*
G01X1411399Y221144D02*
X1411398Y221148D01*
G01X1411400Y221142D02*
X1411399Y221144D01*
G01X1411398Y226148D02*
Y226156D01*
G01X1411399Y226144D02*
X1411398Y226148D01*
G01X1411400Y226142D02*
X1411399Y226144D01*
G01X1411398Y231148D02*
Y231156D01*
G01X1411399Y231144D02*
X1411398Y231148D01*
G01X1411400Y231142D02*
X1411399Y231144D01*
G01X1411398Y236148D02*
Y236156D01*
G01X1411399Y236144D02*
X1411398Y236148D01*
G01X1411400Y236142D02*
X1411399Y236144D01*
G01X1411398Y241148D02*
Y241156D01*
G01X1411399Y241144D02*
X1411398Y241148D01*
G01X1411400Y241142D02*
X1411399Y241144D01*
G01X1411398Y246148D02*
Y246156D01*
G01X1411399Y246144D02*
X1411398Y246148D01*
G01X1411400Y246142D02*
X1411399Y246144D01*
G01X1411398Y251148D02*
Y251156D01*
G01X1411399Y251144D02*
X1411398Y251148D01*
G01X1411400Y251142D02*
X1411399Y251144D01*
G01X1411398Y256148D02*
Y256156D01*
G01X1411399Y256144D02*
X1411398Y256148D01*
G01X1411400Y256142D02*
X1411399Y256144D01*
G01X1397011Y213704D02*
X1397025Y213701D01*
G01X1396998Y213711D02*
X1397011Y213704D01*
G01X1396987Y213731D02*
X1396998Y213711D01*
G01X1397972Y213734D02*
Y213727D01*
G01Y213739D02*
Y213734D01*
G01X1397971Y213740D02*
X1397972Y213739D01*
G01Y216884D02*
Y216876D01*
G01Y216889D02*
Y216884D01*
G01X1397971Y216890D02*
X1397972Y216889D01*
G01X1397011Y216853D02*
X1397025Y216850D01*
G01X1396998Y216861D02*
X1397011Y216853D01*
G01X1396987Y216881D02*
X1396998Y216861D01*
G01X1397972Y214863D02*
Y214856D01*
G01X1397970Y214869D02*
X1397972Y214863D01*
G01X1397967Y214875D02*
X1397970Y214869D01*
G01X1397972Y218013D02*
Y218006D01*
G01X1397970Y218019D02*
X1397972Y218013D01*
G01X1397967Y218025D02*
X1397970Y218019D01*
G01X1397933Y216845D02*
X1397934Y216839D01*
G01X1397932Y216849D02*
X1397933Y216845D01*
G01X1397931Y216850D02*
X1397932Y216849D01*
G01X1410413Y221189D02*
Y221198D01*
G01X1410414Y221183D02*
X1410413Y221189D01*
G01X1410415Y221181D02*
X1410414Y221183D01*
G01X1410413Y226189D02*
Y226198D01*
G01X1410414Y226183D02*
X1410413Y226189D01*
G01X1410415Y226181D02*
X1410414Y226183D01*
G01X1410413Y231189D02*
Y231198D01*
G01X1410414Y231183D02*
X1410413Y231189D01*
G01X1410415Y231181D02*
X1410414Y231183D01*
G01X1410413Y236189D02*
Y236198D01*
G01X1410414Y236183D02*
X1410413Y236189D01*
G01X1410415Y236181D02*
X1410414Y236183D01*
G01X1410413Y241189D02*
Y241198D01*
G01X1410414Y241183D02*
X1410413Y241189D01*
G01X1410415Y241181D02*
X1410414Y241183D01*
G01X1410413Y246189D02*
Y246198D01*
G01X1410414Y246183D02*
X1410413Y246189D01*
G01X1410415Y246181D02*
X1410414Y246183D01*
G01X1410413Y251189D02*
Y251198D01*
G01X1410414Y251183D02*
X1410413Y251189D01*
G01X1410415Y251181D02*
X1410414Y251183D01*
G01X1411390Y221325D02*
X1411398Y221299D01*
G01X1411380Y221352D02*
X1411390Y221325D01*
G01X1411369Y221378D02*
X1411380Y221352D01*
G01X1411390Y226325D02*
X1411398Y226299D01*
G01X1411380Y226352D02*
X1411390Y226325D01*
G01X1411369Y226378D02*
X1411380Y226352D01*
G01X1411390Y231325D02*
X1411398Y231299D01*
G01X1411380Y231352D02*
X1411390Y231325D01*
G01X1411369Y231378D02*
X1411380Y231352D01*
G01X1411390Y236325D02*
X1411398Y236299D01*
G01X1411380Y236352D02*
X1411390Y236325D01*
G01X1411369Y236378D02*
X1411380Y236352D01*
G01X1410413Y256189D02*
Y256198D01*
G01X1410414Y256183D02*
X1410413Y256189D01*
G01X1410415Y256181D02*
X1410414Y256183D01*
G01X1411390Y241325D02*
X1411398Y241299D01*
G01X1411380Y241352D02*
X1411390Y241325D01*
G01X1411369Y241378D02*
X1411380Y241352D01*
G01X1411390Y246325D02*
X1411398Y246299D01*
G01X1411380Y246352D02*
X1411390Y246325D01*
G01X1411369Y246378D02*
X1411380Y246352D01*
G01X1411390Y251325D02*
X1411398Y251299D01*
G01X1411380Y251352D02*
X1411390Y251325D01*
G01X1411369Y251378D02*
X1411380Y251352D01*
G01X1411390Y256325D02*
X1411398Y256299D01*
G01X1411380Y256352D02*
X1411390Y256325D01*
G01X1411369Y256378D02*
X1411380Y256352D01*
G01Y221176D02*
X1411361Y221181D01*
G01X1411395Y221162D02*
X1411380Y221176D01*
G01X1411400Y221142D02*
X1411395Y221162D01*
G01X1411380Y226176D02*
X1411361Y226181D01*
G01X1411395Y226162D02*
X1411380Y226176D01*
G01X1411400Y226142D02*
X1411395Y226162D01*
G01X1411380Y231176D02*
X1411361Y231181D01*
G01X1411395Y231162D02*
X1411380Y231176D01*
G01X1411400Y231142D02*
X1411395Y231162D01*
G01X1411380Y236176D02*
X1411361Y236181D01*
G01X1411395Y236162D02*
X1411380Y236176D01*
G01X1411400Y236142D02*
X1411395Y236162D01*
G01X1411380Y241176D02*
X1411361Y241181D01*
G01X1411395Y241162D02*
X1411380Y241176D01*
G01X1411400Y241142D02*
X1411395Y241162D01*
G01X1411380Y246176D02*
X1411361Y246181D01*
G01X1411395Y246162D02*
X1411380Y246176D01*
G01X1411400Y246142D02*
X1411395Y246162D01*
G01X1411380Y251176D02*
X1411361Y251181D01*
G01X1411395Y251162D02*
X1411380Y251176D01*
G01X1411400Y251142D02*
X1411395Y251162D01*
G01X1411380Y256176D02*
X1411361Y256181D01*
G01X1411395Y256162D02*
X1411380Y256176D01*
G01X1411400Y256142D02*
X1411395Y256162D01*
G01X1397965Y214864D02*
X1397957Y214872D01*
G01X1397970Y214854D02*
X1397965Y214864D01*
G01X1397971Y214843D02*
X1397970Y214854D01*
G01X1397965Y218013D02*
X1397957Y218022D01*
G01X1397970Y218003D02*
X1397965Y218013D01*
G01X1397971Y217992D02*
X1397970Y218003D01*
G01X1411365Y221279D02*
X1411369Y221378D01*
G01X1411359Y221207D02*
X1411365Y221279D01*
G01X1411361Y221181D02*
X1411359Y221207D01*
G01X1411365Y226279D02*
X1411369Y226378D01*
G01X1411359Y226207D02*
X1411365Y226279D01*
G01X1411361Y226181D02*
X1411359Y226207D01*
G01X1411365Y231279D02*
X1411369Y231378D01*
G01X1411359Y231207D02*
X1411365Y231279D01*
G01X1411361Y231181D02*
X1411359Y231207D01*
G01X1411365Y236279D02*
X1411369Y236378D01*
G01X1411359Y236207D02*
X1411365Y236279D01*
G01X1411361Y236181D02*
X1411359Y236207D01*
G01X1411365Y241279D02*
X1411369Y241378D01*
G01X1411359Y241207D02*
X1411365Y241279D01*
G01X1411361Y241181D02*
X1411359Y241207D01*
G01X1411365Y246279D02*
X1411369Y246378D01*
G01X1411359Y246207D02*
X1411365Y246279D01*
G01X1411361Y246181D02*
X1411359Y246207D01*
G01X1411365Y251279D02*
X1411369Y251378D01*
G01X1411359Y251207D02*
X1411365Y251279D01*
G01X1411361Y251181D02*
X1411359Y251207D01*
G01X1411365Y256279D02*
X1411369Y256378D01*
G01X1411359Y256207D02*
X1411365Y256279D01*
G01X1411361Y256181D02*
X1411359Y256207D01*
G01X1397028Y218216D02*
Y218228D01*
G01X1397025Y218203D02*
X1397028Y218216D01*
G01X1397025Y218189D02*
Y218203D01*
G01X1397028Y215067D02*
Y215079D01*
G01X1397025Y215054D02*
X1397028Y215067D01*
G01X1397025Y215040D02*
Y215054D01*
G01X1410414Y259802D02*
X1410415Y259803D01*
G01X1410413Y259796D02*
X1410414Y259802D01*
G01X1410413Y259787D02*
Y259796D01*
G01X1410414Y254802D02*
X1410415Y254803D01*
G01X1410413Y254796D02*
X1410414Y254802D01*
G01X1410413Y254787D02*
Y254796D01*
G01X1410414Y249802D02*
X1410415Y249803D01*
G01X1410413Y249796D02*
X1410414Y249802D01*
G01X1410413Y249787D02*
Y249796D01*
G01X1410414Y244802D02*
X1410415Y244803D01*
G01X1410413Y244796D02*
X1410414Y244802D01*
G01X1410413Y244787D02*
Y244796D01*
G01X1410414Y239802D02*
X1410415Y239803D01*
G01X1410413Y239796D02*
X1410414Y239802D01*
G01X1410413Y239787D02*
Y239796D01*
G01X1410414Y234802D02*
X1410415Y234803D01*
G01X1410413Y234796D02*
X1410414Y234802D01*
G01X1410413Y234787D02*
Y234796D01*
G01X1410414Y229802D02*
X1410415Y229803D01*
G01X1410413Y229796D02*
X1410414Y229802D01*
G01X1410413Y229787D02*
Y229796D01*
G01X1410414Y224802D02*
X1410415Y224803D01*
G01X1410413Y224796D02*
X1410414Y224802D01*
G01X1410413Y224787D02*
Y224796D01*
G01X1410414Y219802D02*
X1410415Y219803D01*
G01X1410413Y219796D02*
X1410414Y219802D01*
G01X1410413Y219787D02*
Y219796D01*
G01X1396988Y216884D02*
Y216876D01*
G01X1396987Y216889D02*
X1396988Y216884D01*
G01X1396987Y216881D02*
Y216889D01*
G01X1397025Y216679D02*
X1397024Y216693D01*
G01X1397028Y216666D02*
X1397025Y216679D01*
G01X1397028Y216654D02*
Y216666D01*
G01X1397025Y213530D02*
X1397024Y213543D01*
G01X1397028Y213517D02*
X1397025Y213530D01*
G01X1397028Y213504D02*
Y213517D01*
G01X1397935Y218203D02*
X1397937Y218189D01*
G01X1397932Y218216D02*
X1397935Y218203D01*
G01X1397933Y218228D02*
X1397932Y218216D01*
G01X1397935Y215053D02*
X1397937Y215040D01*
G01X1397932Y215066D02*
X1397935Y215053D01*
G01X1397933Y215079D02*
X1397932Y215066D01*
G01X1396988Y213734D02*
Y213727D01*
G01X1396987Y213739D02*
X1396988Y213734D01*
G01X1396987Y213732D02*
Y213739D01*
G01X1397932Y216666D02*
X1397933Y216654D01*
G01X1397935Y216679D02*
X1397932Y216666D01*
G01X1397936Y216693D02*
X1397935Y216679D01*
G01X1397932Y213517D02*
X1397933Y213504D01*
G01X1397935Y213530D02*
X1397932Y213517D01*
G01X1397936Y213543D02*
X1397935Y213530D01*
G01X1397001Y218023D02*
X1397025Y218031D01*
G01X1396990Y218009D02*
X1397001Y218023D01*
G01X1396988Y218002D02*
X1396990Y218009D01*
G01X1397001Y214874D02*
X1397025Y214882D01*
G01X1396990Y214859D02*
X1397001Y214874D01*
G01X1396988Y214852D02*
X1396990Y214859D01*
G01X1397972Y217998D02*
Y218006D01*
G01Y217994D02*
Y217998D01*
G01X1397971Y217992D02*
X1397972Y217994D01*
G01Y214849D02*
Y214856D01*
G01Y214844D02*
Y214849D01*
G01X1397971Y214843D02*
X1397972Y214844D01*
G01X1397933Y218037D02*
Y218043D01*
G01X1397932Y218033D02*
X1397933Y218037D01*
G01X1397931Y218031D02*
X1397932Y218033D01*
G01X1397933Y214887D02*
Y214893D01*
G01X1397932Y214883D02*
X1397933Y214887D01*
G01X1397931Y214882D02*
X1397932Y214883D01*
G01X1411398Y259796D02*
Y259787D01*
G01X1411399Y259802D02*
X1411398Y259796D01*
G01X1411400Y259803D02*
X1411399Y259802D01*
G01X1411398Y254796D02*
Y254787D01*
G01X1411399Y254802D02*
X1411398Y254796D01*
G01X1411400Y254803D02*
X1411399Y254802D01*
G01X1411398Y249796D02*
Y249787D01*
G01X1411399Y249802D02*
X1411398Y249796D01*
G01X1411400Y249803D02*
X1411399Y249802D01*
G01X1411398Y244796D02*
Y244787D01*
G01X1411399Y244802D02*
X1411398Y244796D01*
G01X1411400Y244803D02*
X1411399Y244802D01*
G01X1411398Y239796D02*
Y239787D01*
G01X1411399Y239802D02*
X1411398Y239796D01*
G01X1411400Y239803D02*
X1411399Y239802D01*
G01X1411398Y234796D02*
Y234787D01*
G01X1411399Y234802D02*
X1411398Y234796D01*
G01X1411400Y234803D02*
X1411399Y234802D01*
G01X1411398Y229796D02*
Y229787D01*
G01X1411399Y229802D02*
X1411398Y229796D01*
G01X1411400Y229803D02*
X1411399Y229802D01*
G01X1411398Y224796D02*
Y224787D01*
G01X1411399Y224802D02*
X1411398Y224796D01*
G01X1411400Y224803D02*
X1411399Y224802D01*
G01X1411398Y219796D02*
Y219787D01*
G01X1411399Y219802D02*
X1411398Y219796D01*
G01X1411400Y219803D02*
X1411399Y219802D01*
G01X1396988Y217998D02*
Y218006D01*
G01X1396987Y217994D02*
X1396988Y217998D01*
G01X1396986Y217992D02*
X1396987Y217994D01*
G01X1396988Y214849D02*
Y214856D01*
G01X1396987Y214844D02*
X1396988Y214849D01*
G01X1396986Y214843D02*
X1396987Y214844D01*
G01X1397970Y216864D02*
X1397972Y216876D01*
G01X1397963Y216853D02*
X1397970Y216864D01*
G01X1397953Y216844D02*
X1397963Y216853D01*
G01X1397027Y218037D02*
Y218043D01*
G01Y218033D02*
Y218037D01*
G01X1397025Y218031D02*
X1397027Y218033D01*
G01Y214887D02*
Y214893D01*
G01Y214883D02*
Y214887D01*
G01X1397025Y214882D02*
X1397027Y214883D01*
G01X1396989Y218012D02*
X1396988Y218006D01*
G01X1396991Y218019D02*
X1396989Y218012D01*
G01X1396993Y218024D02*
X1396991Y218019D01*
G01X1396997Y218030D02*
X1396993Y218024D01*
G01X1397002Y218034D02*
X1396997Y218030D01*
G01X1397007Y218038D02*
X1397002Y218034D01*
G01X1396989Y214863D02*
X1396988Y214856D01*
G01X1396991Y214869D02*
X1396989Y214863D01*
G01X1396993Y214874D02*
X1396991Y214869D01*
G01X1396997Y214880D02*
X1396993Y214874D01*
G01X1397002Y214884D02*
X1396997Y214880D01*
G01X1397007Y214888D02*
X1397002Y214884D01*
G01X1397944Y216852D02*
X1397931Y216850D01*
G01X1397954Y216857D02*
X1397944Y216852D01*
G01Y213703D02*
X1397931Y213701D01*
G01X1397954Y213708D02*
X1397944Y213703D01*
G01X1410827Y217854D02*
X1412008Y219035D01*
G01X1406890Y217854D02*
X1408071Y219035D01*
G01X1397972Y214845D02*
Y214856D01*
G01Y217994D02*
Y218006D01*
G01X1411398Y221155D02*
Y221164D01*
G01Y226155D02*
Y226164D01*
G01Y231155D02*
Y231164D01*
G01Y236155D02*
Y236164D01*
G01Y241155D02*
Y241164D01*
G01Y246155D02*
Y246164D01*
G01Y251155D02*
Y251164D01*
G01Y256155D02*
Y256164D01*
G01X1415748Y259803D02*
Y261181D01*
G01Y254803D02*
Y256181D01*
G01Y249803D02*
Y251181D01*
G01Y244803D02*
Y246181D01*
G01Y239803D02*
Y241181D01*
G01Y234803D02*
Y236181D01*
G01Y229803D02*
Y231181D01*
G01Y224803D02*
Y226181D01*
G01Y219803D02*
Y221181D01*
G01X1412579D02*
Y219803D01*
G01Y226181D02*
Y224803D01*
G01Y231181D02*
Y229803D01*
G01Y236181D02*
Y234803D01*
G01Y241181D02*
Y239803D01*
G01Y246181D02*
Y244803D01*
G01Y251181D02*
Y249803D01*
G01Y256181D02*
Y254803D01*
G01Y261181D02*
Y259803D01*
G01X1411398Y221156D02*
Y221299D01*
G01Y226156D02*
Y226299D01*
G01Y231156D02*
Y231299D01*
G01Y236156D02*
Y236299D01*
G01Y241156D02*
Y241299D01*
G01Y246156D02*
Y246299D01*
G01Y251156D02*
Y251299D01*
G01Y256156D02*
Y256299D01*
G01Y259311D02*
Y261673D01*
G01Y254311D02*
Y256673D01*
G01Y249311D02*
Y251673D01*
G01Y244311D02*
Y246673D01*
G01Y239311D02*
Y241673D01*
G01Y234311D02*
Y236673D01*
G01Y229311D02*
Y231673D01*
G01Y224311D02*
Y226673D01*
G01Y219311D02*
Y221673D01*
G01X1410413D02*
Y219311D01*
G01Y226673D02*
Y224311D01*
G01Y231673D02*
Y229311D01*
G01Y236673D02*
Y234311D01*
G01Y241673D02*
Y239311D01*
G01Y246673D02*
Y244311D01*
G01Y251673D02*
Y249311D01*
G01Y256673D02*
Y254311D01*
G01Y261673D02*
Y259311D01*
G01X1408071Y295492D02*
Y219035D01*
G01X1406890Y294311D02*
Y217854D01*
G01X1398425Y299232D02*
Y220197D01*
G01X1397972Y216693D02*
Y218189D01*
G01Y213543D02*
Y215039D01*
G01X1397933Y216839D02*
Y216693D01*
G01Y213690D02*
Y213543D01*
G01Y215040D02*
Y214893D01*
G01Y218189D02*
Y218043D01*
G01X1397028D02*
Y218190D01*
G01Y216692D02*
Y216839D01*
G01Y213543D02*
Y213690D01*
G01Y214893D02*
Y215040D01*
G01X1396988Y215039D02*
Y213543D01*
G01Y218189D02*
Y216693D01*
G01X1395807Y218031D02*
Y216850D01*
G01Y214882D02*
Y213701D01*
G01X1392047Y216850D02*
Y218031D01*
G01Y213701D02*
Y214882D01*
G01X1397972Y216876D02*
Y216887D01*
G01Y213727D02*
Y213738D01*
G01X1397931Y213701D02*
X1397935Y213690D01*
G01X1415748Y259803D02*
X1410415D01*
G01X1410413Y259311D02*
X1411398D01*
G01Y256673D02*
X1410413D01*
G01X1411398Y259607D02*
X1410413Y259606D01*
G01X1396875Y216890D02*
X1396987Y216881D01*
G01X1410415Y256181D02*
X1415748D01*
G01Y256142D02*
X1411400D01*
G01X1415748Y254803D02*
X1410415D01*
G01X1410413Y254311D02*
X1411398D01*
G01Y251673D02*
X1410413D01*
G01X1410415Y251181D02*
X1415748D01*
G01Y251142D02*
X1411400D01*
G01X1415748Y249803D02*
X1410415D01*
G01X1410413Y249311D02*
X1411398D01*
G01Y246673D02*
X1410413D01*
G01X1410415Y246181D02*
X1415748D01*
G01Y246142D02*
X1411400D01*
G01X1415748Y244803D02*
X1410415D01*
G01X1410413Y244311D02*
X1411398D01*
G01Y241673D02*
X1410413D01*
G01X1410415Y241181D02*
X1415748D01*
G01Y241142D02*
X1411400D01*
G01X1415748Y239803D02*
X1410415D01*
G01X1410413Y239311D02*
X1411398D01*
G01Y236673D02*
X1410413D01*
G01X1410415Y236181D02*
X1415748D01*
G01Y236142D02*
X1411400D01*
G01X1415748Y234803D02*
X1410415D01*
G01X1410413Y234311D02*
X1411398D01*
G01Y231673D02*
X1410413D01*
G01X1410415Y231181D02*
X1415748D01*
G01Y231142D02*
X1411400D01*
G01X1415748Y229803D02*
X1410415D01*
G01X1410413Y229311D02*
X1411398D01*
G01Y226673D02*
X1410413D01*
G01X1410415Y226181D02*
X1415748D01*
G01Y226142D02*
X1411400D01*
G01X1415748Y224803D02*
X1410415D01*
G01X1410413Y224311D02*
X1411398D01*
G01Y221673D02*
X1410413D01*
G01X1410415Y221181D02*
X1415748D01*
G01Y221142D02*
X1411400D01*
G01X1398425Y220197D02*
X1395079D01*
G01X1415748Y219803D02*
X1410415D01*
G01X1410413Y219311D02*
X1411398D01*
G01X1408071Y219035D02*
X1412008D01*
G01X1397933Y218228D02*
X1397028D01*
G01X1397972Y218189D02*
X1396988D01*
G01X1397931Y218031D02*
X1392047D01*
G01Y217992D02*
X1397971D01*
G01X1406890Y217854D02*
X1410827D01*
G01X1397971Y216890D02*
X1392047D01*
G01X1397931Y216850D02*
X1392047D01*
G01X1396988Y216693D02*
X1397972D01*
G01X1397028Y216654D02*
X1397933D01*
G01Y215079D02*
X1397028D01*
G01X1397972Y215039D02*
X1396988D01*
G01X1397931Y214882D02*
X1392047D01*
G01Y214843D02*
X1397971D01*
G01Y213740D02*
X1392047D01*
G01X1397931Y213701D02*
X1392047D01*
G01X1396988Y213543D02*
X1397972D01*
G01X1397028Y213504D02*
X1397933D01*
G01X1410413Y256377D02*
X1411369Y256378D01*
G01X1411398Y254607D02*
X1410413Y254606D01*
G01Y251377D02*
X1411369Y251378D01*
G01X1411398Y249607D02*
X1410413Y249606D01*
G01Y246377D02*
X1411369Y246378D01*
G01X1411398Y244607D02*
X1410413Y244606D01*
G01Y241377D02*
X1411369Y241378D01*
G01X1411398Y239607D02*
X1410413Y239606D01*
G01Y236377D02*
X1411369Y236378D01*
G01X1411398Y234607D02*
X1410413Y234606D01*
G01Y231377D02*
X1411369Y231378D01*
G01X1411398Y229607D02*
X1410413Y229606D01*
G01Y226377D02*
X1411369Y226378D01*
G01X1411398Y224607D02*
X1410413Y224606D01*
G01Y221377D02*
X1411369Y221378D01*
G01X1411398Y219607D02*
X1410413Y219606D01*
G01X1411385Y261173D02*
X1411396Y261157D01*
G01X1411361Y261181D02*
X1411385Y261173D01*
G01Y266173D02*
X1411396Y266157D01*
G01X1411361Y266181D02*
X1411385Y266173D01*
G01Y271173D02*
X1411396Y271157D01*
G01X1411361Y271181D02*
X1411385Y271173D01*
G01Y276173D02*
X1411396Y276157D01*
G01X1411361Y276181D02*
X1411385Y276173D01*
G01Y281173D02*
X1411396Y281157D01*
G01X1411361Y281181D02*
X1411385Y281173D01*
G01Y286173D02*
X1411396Y286157D01*
G01X1411361Y286181D02*
X1411385Y286173D01*
G01Y291173D02*
X1411396Y291157D01*
G01X1411361Y291181D02*
X1411385Y291173D01*
G01X1411398Y261148D02*
Y261156D01*
G01X1411399Y261144D02*
X1411398Y261148D01*
G01X1411400Y261142D02*
X1411399Y261144D01*
G01X1411398Y266148D02*
Y266156D01*
G01X1411399Y266144D02*
X1411398Y266148D01*
G01X1411400Y266142D02*
X1411399Y266144D01*
G01X1411398Y271148D02*
Y271156D01*
G01X1411399Y271144D02*
X1411398Y271148D01*
G01X1411400Y271142D02*
X1411399Y271144D01*
G01X1411398Y276148D02*
Y276156D01*
G01X1411399Y276144D02*
X1411398Y276148D01*
G01X1411400Y276142D02*
X1411399Y276144D01*
G01X1411398Y281148D02*
Y281156D01*
G01X1411399Y281144D02*
X1411398Y281148D01*
G01X1411400Y281142D02*
X1411399Y281144D01*
G01X1411398Y286148D02*
Y286156D01*
G01X1411399Y286144D02*
X1411398Y286148D01*
G01X1411400Y286142D02*
X1411399Y286144D01*
G01X1411398Y291148D02*
Y291156D01*
G01X1411399Y291144D02*
X1411398Y291148D01*
G01X1411400Y291142D02*
X1411399Y291144D01*
G01X1410413Y261189D02*
Y261198D01*
G01X1410414Y261183D02*
X1410413Y261189D01*
G01X1410415Y261181D02*
X1410414Y261183D01*
G01X1410413Y266189D02*
Y266198D01*
G01X1410414Y266183D02*
X1410413Y266189D01*
G01X1410415Y266181D02*
X1410414Y266183D01*
G01X1410413Y271189D02*
Y271198D01*
G01X1410414Y271183D02*
X1410413Y271189D01*
G01X1410415Y271181D02*
X1410414Y271183D01*
G01X1410413Y276189D02*
Y276198D01*
G01X1410414Y276183D02*
X1410413Y276189D01*
G01X1410415Y276181D02*
X1410414Y276183D01*
G01X1410413Y281189D02*
Y281198D01*
G01X1410414Y281183D02*
X1410413Y281189D01*
G01X1410415Y281181D02*
X1410414Y281183D01*
G01X1410413Y286189D02*
Y286198D01*
G01X1410414Y286183D02*
X1410413Y286189D01*
G01X1410415Y286181D02*
X1410414Y286183D01*
G01X1410413Y291189D02*
Y291198D01*
G01X1410414Y291183D02*
X1410413Y291189D01*
G01X1410415Y291181D02*
X1410414Y291183D01*
G01X1411390Y261325D02*
X1411398Y261299D01*
G01X1411380Y261352D02*
X1411390Y261325D01*
G01X1411369Y261378D02*
X1411380Y261352D01*
G01X1411390Y266325D02*
X1411398Y266299D01*
G01X1411380Y266352D02*
X1411390Y266325D01*
G01X1411369Y266378D02*
X1411380Y266352D01*
G01X1411390Y271325D02*
X1411398Y271299D01*
G01X1411380Y271352D02*
X1411390Y271325D01*
G01X1411369Y271378D02*
X1411380Y271352D01*
G01X1411390Y276325D02*
X1411398Y276299D01*
G01X1411380Y276352D02*
X1411390Y276325D01*
G01X1411369Y276378D02*
X1411380Y276352D01*
G01X1411390Y281325D02*
X1411398Y281299D01*
G01X1411380Y281352D02*
X1411390Y281325D01*
G01X1411369Y281378D02*
X1411380Y281352D01*
G01X1411390Y286325D02*
X1411398Y286299D01*
G01X1411380Y286352D02*
X1411390Y286325D01*
G01X1411369Y286378D02*
X1411380Y286352D01*
G01X1411390Y291325D02*
X1411398Y291299D01*
G01X1411380Y291352D02*
X1411390Y291325D01*
G01X1411369Y291378D02*
X1411380Y291352D01*
G01Y261176D02*
X1411361Y261181D01*
G01X1411395Y261162D02*
X1411380Y261176D01*
G01X1411400Y261142D02*
X1411395Y261162D01*
G01X1411380Y266176D02*
X1411361Y266181D01*
G01X1411395Y266162D02*
X1411380Y266176D01*
G01X1411400Y266142D02*
X1411395Y266162D01*
G01X1411380Y271176D02*
X1411361Y271181D01*
G01X1411395Y271162D02*
X1411380Y271176D01*
G01X1411400Y271142D02*
X1411395Y271162D01*
G01X1411380Y276176D02*
X1411361Y276181D01*
G01X1411395Y276162D02*
X1411380Y276176D01*
G01X1411400Y276142D02*
X1411395Y276162D01*
G01X1411380Y281176D02*
X1411361Y281181D01*
G01X1411395Y281162D02*
X1411380Y281176D01*
G01X1411400Y281142D02*
X1411395Y281162D01*
G01X1411380Y286176D02*
X1411361Y286181D01*
G01X1411395Y286162D02*
X1411380Y286176D01*
G01X1411400Y286142D02*
X1411395Y286162D01*
G01X1411380Y291176D02*
X1411361Y291181D01*
G01X1411395Y291162D02*
X1411380Y291176D01*
G01X1411400Y291142D02*
X1411395Y291162D01*
G01X1411365Y261279D02*
X1411369Y261378D01*
G01X1411359Y261207D02*
X1411365Y261279D01*
G01X1411361Y261181D02*
X1411359Y261207D01*
G01X1411365Y266279D02*
X1411369Y266378D01*
G01X1411359Y266207D02*
X1411365Y266279D01*
G01X1411361Y266181D02*
X1411359Y266207D01*
G01X1411365Y271279D02*
X1411369Y271378D01*
G01X1411359Y271207D02*
X1411365Y271279D01*
G01X1411361Y271181D02*
X1411359Y271207D01*
G01X1411365Y276279D02*
X1411369Y276378D01*
G01X1411359Y276207D02*
X1411365Y276279D01*
G01X1411361Y276181D02*
X1411359Y276207D01*
G01X1411365Y281279D02*
X1411369Y281378D01*
G01X1411359Y281207D02*
X1411365Y281279D01*
G01X1411361Y281181D02*
X1411359Y281207D01*
G01X1411365Y286279D02*
X1411369Y286378D01*
G01X1411359Y286207D02*
X1411365Y286279D01*
G01X1411361Y286181D02*
X1411359Y286207D01*
G01X1411365Y291279D02*
X1411369Y291378D01*
G01X1411359Y291207D02*
X1411365Y291279D01*
G01X1411361Y291181D02*
X1411359Y291207D01*
G01X1410414Y289802D02*
X1410415Y289803D01*
G01X1410413Y289796D02*
X1410414Y289802D01*
G01X1410413Y289787D02*
Y289796D01*
G01X1410414Y284802D02*
X1410415Y284803D01*
G01X1410413Y284796D02*
X1410414Y284802D01*
G01X1410413Y284787D02*
Y284796D01*
G01X1410414Y279802D02*
X1410415Y279803D01*
G01X1410413Y279796D02*
X1410414Y279802D01*
G01X1410413Y279787D02*
Y279796D01*
G01X1410414Y274802D02*
X1410415Y274803D01*
G01X1410413Y274796D02*
X1410414Y274802D01*
G01X1410413Y274787D02*
Y274796D01*
G01X1410414Y269802D02*
X1410415Y269803D01*
G01X1410413Y269796D02*
X1410414Y269802D01*
G01X1410413Y269787D02*
Y269796D01*
G01X1410414Y264802D02*
X1410415Y264803D01*
G01X1410413Y264796D02*
X1410414Y264802D01*
G01X1410413Y264787D02*
Y264796D01*
G01X1411398Y289796D02*
Y289787D01*
G01X1411399Y289802D02*
X1411398Y289796D01*
G01X1411400Y289803D02*
X1411399Y289802D01*
G01X1411398Y284796D02*
Y284787D01*
G01X1411399Y284802D02*
X1411398Y284796D01*
G01X1411400Y284803D02*
X1411399Y284802D01*
G01X1411398Y279796D02*
Y279787D01*
G01X1411399Y279802D02*
X1411398Y279796D01*
G01X1411400Y279803D02*
X1411399Y279802D01*
G01X1411398Y274796D02*
Y274787D01*
G01X1411399Y274802D02*
X1411398Y274796D01*
G01X1411400Y274803D02*
X1411399Y274802D01*
G01X1411398Y269796D02*
Y269787D01*
G01X1411399Y269802D02*
X1411398Y269796D01*
G01X1411400Y269803D02*
X1411399Y269802D01*
G01X1411398Y264796D02*
Y264787D01*
G01X1411399Y264802D02*
X1411398Y264796D01*
G01X1411400Y264803D02*
X1411399Y264802D01*
G01X1403346Y307579D02*
G03X1402165Y306398I0J-1181D01*
G01X1409646D02*
G03X1408465Y307579I-1181J0D01*
G01X1407795Y302303D02*
G03I-1889J0D01*
G01X1408268D02*
G03I-2362J0D01*
G01X1416732Y300335D02*
X1413386Y296988D01*
G01X1406890Y294311D02*
X1408071Y295492D01*
G01X1403421Y299232D02*
X1404724Y301201D01*
G01X1409397Y307123D02*
X1407087Y302894D01*
G01X1411398Y261155D02*
Y261164D01*
G01Y266155D02*
Y266164D01*
G01Y271155D02*
Y271164D01*
G01Y276155D02*
Y276164D01*
G01Y281155D02*
Y281164D01*
G01Y286155D02*
Y286164D01*
G01Y291155D02*
Y291164D01*
G01X1416732Y300335D02*
Y316083D01*
G01X1415748Y289803D02*
Y291181D01*
G01Y284803D02*
Y286181D01*
G01Y279803D02*
Y281181D01*
G01Y274803D02*
Y276181D01*
G01Y269803D02*
Y271181D01*
G01Y264803D02*
Y266181D01*
G01X1412579D02*
Y264803D01*
G01Y271181D02*
Y269803D01*
G01Y276181D02*
Y274803D01*
G01Y281181D02*
Y279803D01*
G01Y286181D02*
Y284803D01*
G01Y291181D02*
Y289803D01*
G01X1411398Y261156D02*
Y261299D01*
G01Y266156D02*
Y266299D01*
G01Y271156D02*
Y271299D01*
G01Y276156D02*
Y276299D01*
G01Y281156D02*
Y281299D01*
G01Y286156D02*
Y286299D01*
G01Y291156D02*
Y291299D01*
G01Y289311D02*
Y291673D01*
G01Y284311D02*
Y286673D01*
G01Y279311D02*
Y281673D01*
G01Y274311D02*
Y276673D01*
G01Y269311D02*
Y271673D01*
G01Y264311D02*
Y266673D01*
G01X1410413D02*
Y264311D01*
G01Y271673D02*
Y269311D01*
G01Y276673D02*
Y274311D01*
G01Y281673D02*
Y279311D01*
G01Y286673D02*
Y284311D01*
G01Y291673D02*
Y289311D01*
G01X1409646Y306398D02*
Y297854D01*
G01X1407087Y302894D02*
Y301201D01*
G01X1404724D02*
Y302894D01*
G01X1402165Y297854D02*
Y306398D01*
G01X1395079Y316083D02*
Y300335D01*
G01X1404724Y302894D02*
X1402414Y307123D01*
G01X1407087Y301201D02*
X1408390Y299232D01*
G01X1400197Y295492D02*
X1401378Y294311D01*
G01X1395079Y300335D02*
X1398425Y296988D01*
G01X1416732Y307618D02*
X1395079D01*
G01X1403346Y307579D02*
X1408465D01*
G01X1404724Y302894D02*
X1407087D01*
G01X1404724Y301201D02*
X1407087D01*
G01X1398425Y299232D02*
X1412795D01*
G01X1398425Y297854D02*
X1402165D01*
G01X1412795D02*
X1409646D01*
G01X1398425Y296988D02*
X1413386D01*
G01X1400197Y295492D02*
X1408071D01*
G01X1401378Y294311D02*
X1406890D01*
G01X1411398Y291673D02*
X1410413D01*
G01X1410415Y291181D02*
X1415748D01*
G01Y291142D02*
X1411400D01*
G01X1415748Y289803D02*
X1410415D01*
G01X1410413Y289311D02*
X1411398D01*
G01Y286673D02*
X1410413D01*
G01X1410415Y286181D02*
X1415748D01*
G01Y286142D02*
X1411400D01*
G01X1415748Y284803D02*
X1410415D01*
G01X1410413Y284311D02*
X1411398D01*
G01Y281673D02*
X1410413D01*
G01X1410415Y281181D02*
X1415748D01*
G01Y281142D02*
X1411400D01*
G01X1415748Y279803D02*
X1410415D01*
G01X1410413Y279311D02*
X1411398D01*
G01Y276673D02*
X1410413D01*
G01X1410415Y276181D02*
X1415748D01*
G01Y276142D02*
X1411400D01*
G01X1415748Y274803D02*
X1410415D01*
G01X1410413Y274311D02*
X1411398D01*
G01Y271673D02*
X1410413D01*
G01X1410415Y271181D02*
X1415748D01*
G01Y271142D02*
X1411400D01*
G01X1415748Y269803D02*
X1410415D01*
G01X1410413Y269311D02*
X1411398D01*
G01Y266673D02*
X1410413D01*
G01X1410415Y266181D02*
X1415748D01*
G01Y266142D02*
X1411400D01*
G01X1415748Y264803D02*
X1410415D01*
G01X1410413Y264311D02*
X1411398D01*
G01Y261673D02*
X1410413D01*
G01X1410415Y261181D02*
X1415748D01*
G01Y261142D02*
X1411400D01*
G01X1410413Y291377D02*
X1411369Y291378D01*
G01X1411398Y289607D02*
X1410413Y289606D01*
G01Y286377D02*
X1411369Y286378D01*
G01X1411398Y284607D02*
X1410413Y284606D01*
G01Y281377D02*
X1411369Y281378D01*
G01X1411398Y279607D02*
X1410413Y279606D01*
G01Y276377D02*
X1411369Y276378D01*
G01X1411398Y274607D02*
X1410413Y274606D01*
G01Y271377D02*
X1411369Y271378D01*
G01X1411398Y269607D02*
X1410413Y269606D01*
G01Y266377D02*
X1411369Y266378D01*
G01X1411398Y264607D02*
X1410413Y264606D01*
G01Y261377D02*
X1411369Y261378D01*
G01X1409843Y316673D02*
G03X1409252Y317264I-591J0D01*
G01X1402559D02*
G03X1401969Y316673I0J-590D01*
G01X1404724Y315492D02*
G03Y313524I0J-984D01*
G01X1407087D02*
G03Y315492I0J984D01*
G01X1416732Y316083D02*
G03X1414764Y318051I-1968J0D01*
G01X1397047D02*
G03X1395079Y316083I0J-1968D01*
G01X1409843Y310571D02*
Y316673D01*
G01X1401969Y310571D02*
Y316673D01*
G01X1414764Y318051D02*
X1397047D01*
G01X1409252Y317264D02*
X1402559D01*
G01X1407087Y315492D02*
X1404724D01*
G01Y313524D02*
X1407087D01*
G01X1409843Y312146D02*
X1401969D01*
G01Y310571D02*
X1409843D01*
G01X1401969Y592067D02*
G03X1402559Y591476I591J0D01*
G01X1409252D02*
G03X1409843Y592067I0J591D01*
G01X1407087Y593248D02*
G03Y595217I0J985D01*
G01X1404724D02*
G03Y593248I0J-985D01*
G01X1395079Y592657D02*
G03X1397047Y590689I1968J0D01*
G01X1414764D02*
G03X1416732Y592657I0J1968D01*
G01D02*
Y608406D01*
G01X1409843Y598169D02*
Y592067D01*
G01X1401969Y598169D02*
Y592067D01*
G01X1395079Y608406D02*
Y592657D01*
G01X1409843Y598169D02*
X1401969D01*
G01Y596594D02*
X1409843D01*
G01X1407087Y595217D02*
X1404724D01*
G01Y593248D02*
X1407087D01*
G01X1409252Y591476D02*
X1402559D01*
G01X1414764Y590689D02*
X1397047D01*
G01X1411385Y618929D02*
X1411396Y618913D01*
G01X1411361Y618937D02*
X1411385Y618929D01*
G01Y623929D02*
X1411396Y623913D01*
G01X1411361Y623937D02*
X1411385Y623929D01*
G01Y628929D02*
X1411396Y628913D01*
G01X1411361Y628937D02*
X1411385Y628929D01*
G01Y633929D02*
X1411396Y633913D01*
G01X1411361Y633937D02*
X1411385Y633929D01*
G01Y638929D02*
X1411396Y638913D01*
G01X1411361Y638937D02*
X1411385Y638929D01*
G01Y643929D02*
X1411396Y643913D01*
G01X1411361Y643937D02*
X1411385Y643929D01*
G01X1411398Y618904D02*
Y618911D01*
G01X1411399Y618900D02*
X1411398Y618904D01*
G01X1411400Y618898D02*
X1411399Y618900D01*
G01X1411398Y623904D02*
Y623911D01*
G01X1411399Y623900D02*
X1411398Y623904D01*
G01X1411400Y623898D02*
X1411399Y623900D01*
G01X1411398Y628904D02*
Y628911D01*
G01X1411399Y628900D02*
X1411398Y628904D01*
G01X1411400Y628898D02*
X1411399Y628900D01*
G01X1411398Y633904D02*
Y633911D01*
G01X1411399Y633900D02*
X1411398Y633904D01*
G01X1411400Y633898D02*
X1411399Y633900D01*
G01X1411398Y638904D02*
Y638911D01*
G01X1411399Y638900D02*
X1411398Y638904D01*
G01X1411400Y638898D02*
X1411399Y638900D01*
G01X1411398Y643904D02*
Y643911D01*
G01X1411399Y643900D02*
X1411398Y643904D01*
G01X1411400Y643898D02*
X1411399Y643900D01*
G01X1410413Y618944D02*
Y618954D01*
G01X1410414Y618939D02*
X1410413Y618944D01*
G01X1410415Y618937D02*
X1410414Y618939D01*
G01X1410413Y623944D02*
Y623954D01*
G01X1410414Y623939D02*
X1410413Y623944D01*
G01X1410415Y623937D02*
X1410414Y623939D01*
G01X1410413Y628944D02*
Y628954D01*
G01X1410414Y628939D02*
X1410413Y628944D01*
G01X1410415Y628937D02*
X1410414Y628939D01*
G01X1410413Y633944D02*
Y633954D01*
G01X1410414Y633939D02*
X1410413Y633944D01*
G01X1410415Y633937D02*
X1410414Y633939D01*
G01X1410413Y638944D02*
Y638954D01*
G01X1410414Y638939D02*
X1410413Y638944D01*
G01X1410415Y638937D02*
X1410414Y638939D01*
G01X1410413Y643944D02*
Y643954D01*
G01X1410414Y643939D02*
X1410413Y643944D01*
G01X1410415Y643937D02*
X1410414Y643939D01*
G01X1411390Y619081D02*
X1411398Y619055D01*
G01X1411380Y619107D02*
X1411390Y619081D01*
G01X1411369Y619134D02*
X1411380Y619107D01*
G01X1411390Y624081D02*
X1411398Y624055D01*
G01X1411380Y624107D02*
X1411390Y624081D01*
G01X1411369Y624134D02*
X1411380Y624107D01*
G01X1411390Y629081D02*
X1411398Y629055D01*
G01X1411380Y629107D02*
X1411390Y629081D01*
G01X1411369Y629134D02*
X1411380Y629107D01*
G01X1411390Y634081D02*
X1411398Y634055D01*
G01X1411380Y634107D02*
X1411390Y634081D01*
G01X1411369Y634134D02*
X1411380Y634107D01*
G01X1411390Y639081D02*
X1411398Y639055D01*
G01X1411380Y639107D02*
X1411390Y639081D01*
G01X1411369Y639134D02*
X1411380Y639107D01*
G01X1411390Y644081D02*
X1411398Y644055D01*
G01X1411380Y644107D02*
X1411390Y644081D01*
G01X1411369Y644134D02*
X1411380Y644107D01*
G01X1411365Y619035D02*
X1411369Y619134D01*
G01X1411359Y618963D02*
X1411365Y619035D01*
G01X1411361Y618937D02*
X1411359Y618963D01*
G01X1411365Y624035D02*
X1411369Y624134D01*
G01X1411359Y623963D02*
X1411365Y624035D01*
G01X1411361Y623937D02*
X1411359Y623963D01*
G01X1411365Y629035D02*
X1411369Y629134D01*
G01X1411359Y628963D02*
X1411365Y629035D01*
G01X1411361Y628937D02*
X1411359Y628963D01*
G01X1411365Y634035D02*
X1411369Y634134D01*
G01X1411359Y633963D02*
X1411365Y634035D01*
G01X1411361Y633937D02*
X1411359Y633963D01*
G01X1411365Y639035D02*
X1411369Y639134D01*
G01X1411359Y638963D02*
X1411365Y639035D01*
G01X1411361Y638937D02*
X1411359Y638963D01*
G01X1411365Y644035D02*
X1411369Y644134D01*
G01X1411359Y643963D02*
X1411365Y644035D01*
G01X1411361Y643937D02*
X1411359Y643963D01*
G01X1410414Y647557D02*
X1410415Y647559D01*
G01X1410413Y647552D02*
X1410414Y647557D01*
G01X1410413Y647543D02*
Y647552D01*
G01X1410414Y642557D02*
X1410415Y642559D01*
G01X1410413Y642552D02*
X1410414Y642557D01*
G01X1410413Y642543D02*
Y642552D01*
G01X1410414Y637557D02*
X1410415Y637559D01*
G01X1410413Y637552D02*
X1410414Y637557D01*
G01X1410413Y637543D02*
Y637552D01*
G01X1410414Y632557D02*
X1410415Y632559D01*
G01X1410413Y632552D02*
X1410414Y632557D01*
G01X1410413Y632543D02*
Y632552D01*
G01X1410414Y627557D02*
X1410415Y627559D01*
G01X1410413Y627552D02*
X1410414Y627557D01*
G01X1410413Y627543D02*
Y627552D01*
G01X1410414Y622557D02*
X1410415Y622559D01*
G01X1410413Y622552D02*
X1410414Y622557D01*
G01X1410413Y622543D02*
Y622552D01*
G01X1410414Y617557D02*
X1410415Y617559D01*
G01X1410413Y617552D02*
X1410414Y617557D01*
G01X1410413Y617543D02*
Y617552D01*
G01X1411398Y647552D02*
Y647543D01*
G01X1411399Y647557D02*
X1411398Y647552D01*
G01X1411400Y647559D02*
X1411399Y647557D01*
G01X1411398Y642552D02*
Y642543D01*
G01X1411399Y642557D02*
X1411398Y642552D01*
G01X1411400Y642559D02*
X1411399Y642557D01*
G01X1411398Y637552D02*
Y637543D01*
G01X1411399Y637557D02*
X1411398Y637552D01*
G01X1411400Y637559D02*
X1411399Y637557D01*
G01X1411398Y632552D02*
Y632543D01*
G01X1411399Y632557D02*
X1411398Y632552D01*
G01X1411400Y632559D02*
X1411399Y632557D01*
G01X1411398Y627552D02*
Y627543D01*
G01X1411399Y627557D02*
X1411398Y627552D01*
G01X1411400Y627559D02*
X1411399Y627557D01*
G01X1411398Y622552D02*
Y622543D01*
G01X1411399Y622557D02*
X1411398Y622552D01*
G01X1411400Y622559D02*
X1411399Y622557D01*
G01X1411398Y617552D02*
Y617543D01*
G01X1411399Y617557D02*
X1411398Y617552D01*
G01X1411400Y617559D02*
X1411399Y617557D01*
G01X1411380Y618932D02*
X1411361Y618937D01*
G01X1411395Y618918D02*
X1411380Y618932D01*
G01X1411400Y618898D02*
X1411395Y618918D01*
G01X1411380Y623932D02*
X1411361Y623937D01*
G01X1411395Y623918D02*
X1411380Y623932D01*
G01X1411400Y623898D02*
X1411395Y623918D01*
G01X1411380Y628932D02*
X1411361Y628937D01*
G01X1411395Y628918D02*
X1411380Y628932D01*
G01X1411400Y628898D02*
X1411395Y628918D01*
G01X1411380Y633932D02*
X1411361Y633937D01*
G01X1411395Y633918D02*
X1411380Y633932D01*
G01X1411400Y633898D02*
X1411395Y633918D01*
G01X1411380Y638932D02*
X1411361Y638937D01*
G01X1411395Y638918D02*
X1411380Y638932D01*
G01X1411400Y638898D02*
X1411395Y638918D01*
G01X1411380Y643932D02*
X1411361Y643937D01*
G01X1411395Y643918D02*
X1411380Y643932D01*
G01X1411400Y643898D02*
X1411395Y643918D01*
G01X1407008Y606437D02*
G03I-1102J0D01*
G01X1408465Y601161D02*
G03X1409646Y602343I0J1181D01*
G01X1402165D02*
G03X1403346Y601161I1181J-1D01*
G01X1407480Y606437D02*
G03I-1574J0D01*
G01X1408390Y609508D02*
X1407087Y607539D01*
G01X1402414Y601617D02*
X1404724Y605846D01*
G01X1401378Y614429D02*
X1400197Y613248D01*
G01X1398425Y611752D02*
X1395079Y608406D01*
G01X1411398Y618911D02*
Y618920D01*
G01Y623911D02*
Y623920D01*
G01Y628911D02*
Y628920D01*
G01Y633911D02*
Y633920D01*
G01Y638911D02*
Y638920D01*
G01Y643911D02*
Y643920D01*
G01X1415748Y647559D02*
Y648937D01*
G01Y642559D02*
Y643937D01*
G01Y637559D02*
Y638937D01*
G01Y632559D02*
Y633937D01*
G01Y627559D02*
Y628937D01*
G01Y622559D02*
Y623937D01*
G01Y617559D02*
Y618937D01*
G01X1413386Y749744D02*
Y611752D01*
G01X1412795Y751988D02*
Y609508D01*
G01X1412579Y618937D02*
Y617559D01*
G01Y623937D02*
Y622559D01*
G01Y628937D02*
Y627559D01*
G01Y633937D02*
Y632559D01*
G01Y638937D02*
Y637559D01*
G01Y643937D02*
Y642559D01*
G01Y648937D02*
Y647559D01*
G01X1411398Y647067D02*
Y649429D01*
G01Y642067D02*
Y644429D01*
G01Y637067D02*
Y639429D01*
G01Y632067D02*
Y634429D01*
G01Y627067D02*
Y629429D01*
G01Y622067D02*
Y624429D01*
G01Y617067D02*
Y619429D01*
G01X1410413D02*
Y617067D01*
G01Y624429D02*
Y622067D01*
G01Y629429D02*
Y627067D01*
G01Y634429D02*
Y632067D01*
G01Y639429D02*
Y637067D01*
G01Y644429D02*
Y642067D01*
G01Y649429D02*
Y647067D01*
G01X1409646Y610886D02*
Y602343D01*
G01X1408071Y649705D02*
Y613248D01*
G01X1407087Y607539D02*
Y605846D01*
G01X1406890Y650886D02*
Y614429D01*
G01X1404724Y605846D02*
Y607539D01*
G01X1402165Y602343D02*
Y610886D01*
G01X1401378Y614429D02*
Y747067D01*
G01X1400197Y613248D02*
Y748248D01*
G01X1398425Y648543D02*
Y609508D01*
G01X1407087Y605846D02*
X1409397Y601617D01*
G01X1404724Y607539D02*
X1403421Y609508D01*
G01X1413386Y611752D02*
X1416732Y608406D01*
G01X1406890Y614429D02*
X1408071Y613248D01*
G01X1415748Y647559D02*
X1410415D01*
G01X1410413Y647067D02*
X1411398D01*
G01Y644429D02*
X1410413D01*
G01X1410415Y643937D02*
X1415748D01*
G01Y643898D02*
X1411400D01*
G01X1415748Y642559D02*
X1410415D01*
G01X1410413Y642067D02*
X1411398D01*
G01Y639429D02*
X1410413D01*
G01X1410415Y638937D02*
X1415748D01*
G01Y638898D02*
X1411400D01*
G01X1415748Y637559D02*
X1410415D01*
G01X1410413Y637067D02*
X1411398D01*
G01Y634429D02*
X1410413D01*
G01X1410415Y633937D02*
X1415748D01*
G01Y633898D02*
X1411400D01*
G01X1415748Y632559D02*
X1410415D01*
G01X1410413Y632067D02*
X1411398D01*
G01Y629429D02*
X1410413D01*
G01X1410415Y628937D02*
X1415748D01*
G01Y628898D02*
X1411400D01*
G01X1415748Y627559D02*
X1410415D01*
G01X1410413Y627067D02*
X1411398D01*
G01Y624429D02*
X1410413D01*
G01X1410415Y623937D02*
X1415748D01*
G01Y623898D02*
X1411400D01*
G01X1415748Y622559D02*
X1410415D01*
G01X1410413Y622067D02*
X1411398D01*
G01Y619429D02*
X1410413D01*
G01X1410415Y618937D02*
X1415748D01*
G01Y618898D02*
X1411400D01*
G01X1415748Y617559D02*
X1410415D01*
G01X1410413Y617067D02*
X1411398D01*
G01Y647363D02*
X1410413Y647362D01*
G01Y644133D02*
X1411369Y644134D01*
G01X1411398Y642363D02*
X1410413Y642362D01*
G01Y639133D02*
X1411369Y639134D01*
G01X1411398Y637363D02*
X1410413Y637362D01*
G01Y634133D02*
X1411369Y634134D01*
G01X1411398Y632363D02*
X1410413Y632362D01*
G01Y629133D02*
X1411369Y629134D01*
G01X1411398Y627363D02*
X1410413Y627362D01*
G01Y624133D02*
X1411369Y624134D01*
G01X1411398Y622363D02*
X1410413Y622362D01*
G01Y619133D02*
X1411369Y619134D01*
G01X1411398Y617363D02*
X1410413Y617362D01*
G01X1406890Y614429D02*
X1401378D01*
G01X1408071Y613248D02*
X1400197D01*
G01X1413386Y611752D02*
X1398425D01*
G01X1409646Y610886D02*
X1412795D01*
G01X1402165D02*
X1398425D01*
G01Y609508D02*
X1412795D01*
G01X1407087Y607539D02*
X1404724D01*
G01X1407087Y605846D02*
X1404724D01*
G01X1408465Y601161D02*
X1403346D01*
G01X1416732Y601122D02*
X1395079D01*
G01X1396991Y651870D02*
X1396986Y651850D01*
G01X1397006Y651885D02*
X1396991Y651870D01*
G01X1397025Y651890D02*
X1397006Y651885D01*
G01X1396991Y655020D02*
X1396986Y655000D01*
G01X1397006Y655034D02*
X1396991Y655020D01*
G01X1397025Y655039D02*
X1397006Y655034D01*
G01X1396991Y658169D02*
X1396986Y658150D01*
G01X1397006Y658184D02*
X1396991Y658169D01*
G01X1397025Y658189D02*
X1397006Y658184D01*
G01X1396991Y661319D02*
X1396986Y661299D01*
G01X1397006Y661333D02*
X1396991Y661319D01*
G01X1397025Y661339D02*
X1397006Y661333D01*
G01X1396991Y664469D02*
X1396986Y664449D01*
G01X1397006Y664483D02*
X1396991Y664469D01*
G01X1397025Y664488D02*
X1397006Y664483D01*
G01X1396991Y667618D02*
X1396986Y667598D01*
G01X1397006Y667633D02*
X1396991Y667618D01*
G01X1397025Y667638D02*
X1397006Y667633D01*
G01X1396991Y670768D02*
X1396986Y670748D01*
G01X1397006Y670782D02*
X1396991Y670768D01*
G01X1397025Y670787D02*
X1397006Y670782D01*
G01X1397966Y650728D02*
X1397971Y650748D01*
G01X1397951Y650714D02*
X1397966Y650728D01*
G01X1397931Y650709D02*
X1397951Y650714D01*
G01X1397966Y653878D02*
X1397971Y653898D01*
G01X1397951Y653864D02*
X1397966Y653878D01*
G01X1397931Y653858D02*
X1397951Y653864D01*
G01X1397966Y657028D02*
X1397971Y657047D01*
G01X1397951Y657013D02*
X1397966Y657028D01*
G01X1397931Y657008D02*
X1397951Y657013D01*
G01X1397966Y660177D02*
X1397971Y660197D01*
G01X1397951Y660163D02*
X1397966Y660177D01*
G01X1397931Y660157D02*
X1397951Y660163D01*
G01X1397966Y663327D02*
X1397971Y663346D01*
G01X1397951Y663313D02*
X1397966Y663327D01*
G01X1397931Y663307D02*
X1397951Y663313D01*
G01X1397966Y666476D02*
X1397971Y666496D01*
G01X1397951Y666462D02*
X1397966Y666476D01*
G01X1397931Y666457D02*
X1397951Y666462D01*
G01X1397966Y669626D02*
X1397971Y669646D01*
G01X1397951Y669612D02*
X1397966Y669626D01*
G01X1397931Y669606D02*
X1397951Y669612D01*
G01X1397972Y666475D02*
Y666483D01*
G01X1397969Y666469D02*
X1397972Y666475D01*
G01X1397966Y666462D02*
X1397969Y666469D01*
G01X1397961Y666456D02*
X1397966Y666462D01*
G01X1397955Y666452D02*
X1397961Y666456D01*
G01X1397948Y666448D02*
X1397955Y666452D01*
G01X1397941Y666446D02*
X1397948Y666448D01*
G01X1397933Y666446D02*
X1397941D01*
G01X1397950Y650701D02*
X1397953Y650703D01*
G01X1397947Y650700D02*
X1397950Y650701D01*
G01X1397944Y650699D02*
X1397947Y650700D01*
G01X1397940Y650698D02*
X1397944Y650699D01*
G01X1397937Y650698D02*
X1397940D01*
G01X1397933D02*
X1397937D01*
G01X1397011Y651898D02*
X1397007Y651896D01*
G01X1397014Y651899D02*
X1397011Y651898D01*
G01X1397017Y651900D02*
X1397014Y651899D01*
G01X1397020Y651900D02*
X1397017D01*
G01X1397024Y651901D02*
X1397020Y651900D01*
G01X1397028Y651901D02*
X1397024D01*
G01X1397950Y653851D02*
X1397953Y653852D01*
G01X1397947Y653850D02*
X1397950Y653851D01*
G01X1397944Y653848D02*
X1397947Y653850D01*
G01X1397940Y653848D02*
X1397944D01*
G01X1397937Y653847D02*
X1397940Y653848D01*
G01X1397933Y653847D02*
X1397937D01*
G01X1397011Y655047D02*
X1397007Y655046D01*
G01X1397014Y655048D02*
X1397011Y655047D01*
G01X1397017Y655050D02*
X1397014Y655048D01*
G01X1397020Y655050D02*
X1397017D01*
G01X1397024Y655051D02*
X1397020Y655050D01*
G01X1397028Y655051D02*
X1397024D01*
G01X1397950Y657000D02*
X1397953Y657002D01*
G01X1397947Y656999D02*
X1397950Y657000D01*
G01X1397944Y656998D02*
X1397947Y656999D01*
G01X1397940Y656997D02*
X1397944Y656998D01*
G01X1397937Y656997D02*
X1397940D01*
G01X1397933D02*
X1397937D01*
G01X1397011Y658197D02*
X1397007Y658195D01*
G01X1397014Y658198D02*
X1397011Y658197D01*
G01X1397017Y658199D02*
X1397014Y658198D01*
G01X1397020Y658200D02*
X1397017Y658199D01*
G01X1397024Y658200D02*
X1397020D01*
G01X1397028D02*
X1397024D01*
G01X1397950Y660150D02*
X1397953Y660152D01*
G01X1397947Y660149D02*
X1397950Y660150D01*
G01X1397944Y660148D02*
X1397947Y660149D01*
G01X1397940Y660147D02*
X1397944Y660148D01*
G01X1397937Y660146D02*
X1397940Y660147D01*
G01X1397933Y660146D02*
X1397937D01*
G01X1397011Y661346D02*
X1397007Y661345D01*
G01X1397014Y661348D02*
X1397011Y661346D01*
G01X1397017Y661349D02*
X1397014Y661348D01*
G01X1397020Y661349D02*
X1397017D01*
G01X1397024Y661350D02*
X1397020Y661349D01*
G01X1397028Y661350D02*
X1397024D01*
G01X1397950Y663300D02*
X1397953Y663301D01*
G01X1397947Y663298D02*
X1397950Y663300D01*
G01X1397944Y663297D02*
X1397947Y663298D01*
G01X1397940Y663296D02*
X1397944Y663297D01*
G01X1397937Y663296D02*
X1397940D01*
G01X1397933D02*
X1397937D01*
G01X1397011Y664496D02*
X1397007Y664494D01*
G01X1397014Y664497D02*
X1397011Y664496D01*
G01X1397017Y664498D02*
X1397014Y664497D01*
G01X1397020Y664499D02*
X1397017Y664498D01*
G01X1397024Y664500D02*
X1397020Y664499D01*
G01X1397028Y664500D02*
X1397024D01*
G01X1397011Y667646D02*
X1397007Y667644D01*
G01X1397014Y667647D02*
X1397011Y667646D01*
G01X1397017Y667648D02*
X1397014Y667647D01*
G01X1397020Y667648D02*
X1397017D01*
G01X1397024Y667649D02*
X1397020Y667648D01*
G01X1397028Y667649D02*
X1397024D01*
G01X1397950Y669599D02*
X1397953Y669600D01*
G01X1397947Y669598D02*
X1397950Y669599D01*
G01X1397944Y669596D02*
X1397947Y669598D01*
G01X1397940Y669596D02*
X1397944D01*
G01X1397937Y669595D02*
X1397940Y669596D01*
G01X1397933Y669595D02*
X1397937D01*
G01X1397011Y670795D02*
X1397007Y670794D01*
G01X1397014Y670796D02*
X1397011Y670795D01*
G01X1397017Y670798D02*
X1397014Y670796D01*
G01X1397020Y670798D02*
X1397017D01*
G01X1397024Y670799D02*
X1397020Y670798D01*
G01X1397028Y670799D02*
X1397024D01*
G01X1397963Y651888D02*
X1397967Y651883D01*
G01X1397958Y651893D02*
X1397963Y651888D01*
G01X1397952Y651896D02*
X1397958Y651893D01*
G01X1397946Y651899D02*
X1397952Y651896D01*
G01X1397940Y651901D02*
X1397946Y651899D01*
G01X1397933Y651901D02*
X1397940D01*
G01X1397963Y655038D02*
X1397967Y655033D01*
G01X1397958Y655042D02*
X1397963Y655038D01*
G01X1397952Y655046D02*
X1397958Y655042D01*
G01X1397946Y655048D02*
X1397952Y655046D01*
G01X1397940Y655050D02*
X1397946Y655048D01*
G01X1397933Y655051D02*
X1397940Y655050D01*
G01X1397963Y658187D02*
X1397967Y658182D01*
G01X1397958Y658192D02*
X1397963Y658187D01*
G01X1397952Y658196D02*
X1397958Y658192D01*
G01X1397946Y658198D02*
X1397952Y658196D01*
G01X1397940Y658200D02*
X1397946Y658198D01*
G01X1397933Y658200D02*
X1397940D01*
G01X1397963Y661337D02*
X1397967Y661332D01*
G01X1397958Y661341D02*
X1397963Y661337D01*
G01X1397952Y661345D02*
X1397958Y661341D01*
G01X1397946Y661348D02*
X1397952Y661345D01*
G01X1397940Y661350D02*
X1397946Y661348D01*
G01X1397933Y661350D02*
X1397940D01*
G01X1397963Y664487D02*
X1397967Y664481D01*
G01X1397958Y664491D02*
X1397963Y664487D01*
G01X1397952Y664495D02*
X1397958Y664491D01*
G01X1397946Y664497D02*
X1397952Y664495D01*
G01X1397940Y664499D02*
X1397946Y664497D01*
G01X1397933Y664500D02*
X1397940Y664499D01*
G01X1397963Y667636D02*
X1397967Y667631D01*
G01X1397958Y667641D02*
X1397963Y667636D01*
G01X1397952Y667644D02*
X1397958Y667641D01*
G01X1397946Y667647D02*
X1397952Y667644D01*
G01X1397940Y667649D02*
X1397946Y667647D01*
G01X1397933Y667649D02*
X1397940D01*
G01X1396989Y650727D02*
X1396988Y650735D01*
G01X1396991Y650720D02*
X1396989Y650727D01*
G01X1396995Y650714D02*
X1396991Y650720D01*
G01X1397000Y650708D02*
X1396995Y650714D01*
G01X1397006Y650704D02*
X1397000Y650708D01*
G01X1397013Y650700D02*
X1397006Y650704D01*
G01X1397020Y650698D02*
X1397013Y650700D01*
G01X1397028Y650698D02*
X1397020D01*
G01X1396989Y653877D02*
X1396988Y653884D01*
G01X1396991Y653870D02*
X1396989Y653877D01*
G01X1396995Y653864D02*
X1396991Y653870D01*
G01X1397000Y653858D02*
X1396995Y653864D01*
G01X1397006Y653853D02*
X1397000Y653858D01*
G01X1397013Y653850D02*
X1397006Y653853D01*
G01X1397020Y653848D02*
X1397013Y653850D01*
G01X1397028Y653847D02*
X1397020Y653848D01*
G01X1396989Y657026D02*
X1396988Y657034D01*
G01X1396991Y657020D02*
X1396989Y657026D01*
G01X1396995Y657013D02*
X1396991Y657020D01*
G01X1397000Y657007D02*
X1396995Y657013D01*
G01X1397006Y657003D02*
X1397000Y657007D01*
G01X1397013Y657000D02*
X1397006Y657003D01*
G01X1397020Y656998D02*
X1397013Y657000D01*
G01X1397028Y656997D02*
X1397020Y656998D01*
G01X1396989Y660176D02*
X1396988Y660183D01*
G01X1396991Y660169D02*
X1396989Y660176D01*
G01X1396995Y660163D02*
X1396991Y660169D01*
G01X1397000Y660157D02*
X1396995Y660163D01*
G01X1397006Y660152D02*
X1397000Y660157D01*
G01X1397013Y660149D02*
X1397006Y660152D01*
G01X1397020Y660147D02*
X1397013Y660149D01*
G01X1397028Y660146D02*
X1397020Y660147D01*
G01X1396989Y663326D02*
X1396988Y663333D01*
G01X1396991Y663319D02*
X1396989Y663326D01*
G01X1396995Y663313D02*
X1396991Y663319D01*
G01X1397000Y663307D02*
X1396995Y663313D01*
G01X1397006Y663302D02*
X1397000Y663307D01*
G01X1397013Y663299D02*
X1397006Y663302D01*
G01X1397020Y663297D02*
X1397013Y663299D01*
G01X1397028Y663296D02*
X1397020Y663297D01*
G01X1397963Y670786D02*
X1397967Y670781D01*
G01X1397958Y670790D02*
X1397963Y670786D01*
G01X1397952Y670794D02*
X1397958Y670790D01*
G01X1397946Y670796D02*
X1397952Y670794D01*
G01X1397940Y670798D02*
X1397946Y670796D01*
G01X1397933Y670799D02*
X1397940Y670798D01*
G01X1396989Y666475D02*
X1396988Y666483D01*
G01X1396991Y666469D02*
X1396989Y666475D01*
G01X1396995Y666462D02*
X1396991Y666469D01*
G01X1397000Y666456D02*
X1396995Y666462D01*
G01X1397006Y666452D02*
X1397000Y666456D01*
G01X1397013Y666448D02*
X1397006Y666452D01*
G01X1397020Y666446D02*
X1397013Y666448D01*
G01X1397028Y666446D02*
X1397020D01*
G01X1396989Y669625D02*
X1396988Y669632D01*
G01X1396991Y669618D02*
X1396989Y669625D01*
G01X1396995Y669612D02*
X1396991Y669618D01*
G01X1397000Y669606D02*
X1396995Y669612D01*
G01X1397006Y669601D02*
X1397000Y669606D01*
G01X1397013Y669598D02*
X1397006Y669601D01*
G01X1397020Y669596D02*
X1397013Y669598D01*
G01X1397028Y669595D02*
X1397020Y669596D01*
G01X1397942Y651889D02*
X1397952Y651884D01*
G01X1397931Y651890D02*
X1397942Y651889D01*
G01Y655038D02*
X1397952Y655034D01*
G01X1397931Y655039D02*
X1397942Y655038D01*
G01Y658188D02*
X1397952Y658183D01*
G01X1397931Y658189D02*
X1397942Y658188D01*
G01Y661337D02*
X1397952Y661333D01*
G01X1397931Y661339D02*
X1397942Y661337D01*
G01Y664487D02*
X1397952Y664483D01*
G01X1397931Y664488D02*
X1397942Y664487D01*
G01Y667637D02*
X1397952Y667632D01*
G01X1397931Y667638D02*
X1397942Y667637D01*
G01Y670786D02*
X1397952Y670782D01*
G01X1397931Y670787D02*
X1397942Y670786D01*
G01X1396988Y653888D02*
Y653884D01*
G01X1396990Y653882D02*
X1396988Y653888D01*
G01X1397002Y653867D02*
X1396990Y653882D01*
G01X1397026Y653858D02*
X1397002Y653867D01*
G01X1396988Y657038D02*
Y657034D01*
G01X1396990Y657031D02*
X1396988Y657038D01*
G01X1397001Y657016D02*
X1396990Y657031D01*
G01X1397026Y657008D02*
X1397001Y657016D01*
G01X1396988Y663337D02*
Y663333D01*
G01X1396990Y663331D02*
X1396988Y663337D01*
G01X1397001Y663315D02*
X1396990Y663331D01*
G01X1397026Y663307D02*
X1397001Y663315D01*
G01X1396988Y666487D02*
Y666483D01*
G01X1396990Y666480D02*
X1396988Y666487D01*
G01X1397001Y666465D02*
X1396990Y666480D01*
G01X1397026Y666457D02*
X1397001Y666465D01*
G01X1396988Y650739D02*
Y650735D01*
G01X1396990Y650732D02*
X1396988Y650739D01*
G01X1397001Y650717D02*
X1396990Y650732D01*
G01X1397026Y650709D02*
X1397001Y650717D01*
G01X1396988Y669636D02*
Y669632D01*
G01X1396990Y669630D02*
X1396988Y669636D01*
G01X1397001Y669615D02*
X1396990Y669630D01*
G01X1397026Y669606D02*
X1397001Y669615D01*
G01X1411385Y648929D02*
X1411396Y648913D01*
G01X1411361Y648937D02*
X1411385Y648929D01*
G01Y673929D02*
X1411396Y673913D01*
G01X1411361Y673937D02*
X1411385Y673929D01*
G01Y678929D02*
X1411396Y678913D01*
G01X1411361Y678937D02*
X1411385Y678929D01*
G01Y683929D02*
X1411396Y683913D01*
G01X1411361Y683937D02*
X1411385Y683929D01*
G01Y688929D02*
X1411396Y688913D01*
G01X1411361Y688937D02*
X1411385Y688929D01*
G01Y693929D02*
X1411396Y693913D01*
G01X1411361Y693937D02*
X1411385Y693929D01*
G01X1396988Y660187D02*
Y660183D01*
G01X1396989Y660182D02*
X1396988Y660187D01*
G01X1397000Y660167D02*
X1396989Y660182D01*
G01X1397023Y660158D02*
X1397000Y660167D01*
G01X1397941Y658188D02*
X1397931Y658189D01*
G01X1397950Y658185D02*
X1397941Y658188D01*
G01X1397957Y658180D02*
X1397950Y658185D01*
G01X1397941Y651889D02*
X1397931Y651890D01*
G01X1397950Y651885D02*
X1397941Y651889D01*
G01X1397957Y651880D02*
X1397950Y651885D01*
G01X1397941Y655038D02*
X1397931Y655039D01*
G01X1397950Y655035D02*
X1397941Y655038D01*
G01X1397957Y655030D02*
X1397950Y655035D01*
G01X1397941Y661337D02*
X1397931Y661339D01*
G01X1397950Y661334D02*
X1397941Y661337D01*
G01X1397957Y661329D02*
X1397950Y661334D01*
G01X1397941Y664487D02*
X1397931Y664488D01*
G01X1397950Y664484D02*
X1397941Y664487D01*
G01X1397957Y664479D02*
X1397950Y664484D01*
G01X1397941Y667637D02*
X1397931Y667638D01*
G01X1397950Y667633D02*
X1397941Y667637D01*
G01X1397957Y667628D02*
X1397950Y667633D01*
G01X1397941Y670786D02*
X1397931Y670787D01*
G01X1397950Y670783D02*
X1397941Y670786D01*
G01X1397957Y670778D02*
X1397950Y670783D01*
G01X1397027Y650704D02*
X1397028Y650698D01*
G01X1397026Y650707D02*
X1397027Y650704D01*
G01X1397025Y650709D02*
X1397026Y650707D01*
G01X1397027Y653854D02*
X1397028Y653847D01*
G01X1397026Y653857D02*
X1397027Y653854D01*
G01X1397025Y653858D02*
X1397026Y653857D01*
G01X1397027Y657003D02*
X1397028Y656997D01*
G01X1397026Y657007D02*
X1397027Y657003D01*
G01X1397025Y657008D02*
X1397026Y657007D01*
G01X1397027Y660153D02*
X1397028Y660146D01*
G01X1397026Y660156D02*
X1397027Y660153D01*
G01X1397025Y660157D02*
X1397026Y660156D01*
G01X1397027Y663302D02*
X1397028Y663296D01*
G01X1397026Y663306D02*
X1397027Y663302D01*
G01X1397025Y663307D02*
X1397026Y663306D01*
G01X1397027Y666452D02*
X1397028Y666446D01*
G01X1397026Y666456D02*
X1397027Y666452D01*
G01X1397025Y666457D02*
X1397026Y666456D01*
G01X1397027Y669602D02*
X1397028Y669595D01*
G01X1397026Y669605D02*
X1397027Y669602D01*
G01X1397025Y669606D02*
X1397026Y669605D01*
G01X1411398Y648904D02*
Y648911D01*
G01X1411399Y648900D02*
X1411398Y648904D01*
G01X1411400Y648898D02*
X1411399Y648900D01*
G01X1397970Y669620D02*
X1397972Y669632D01*
G01X1397963Y669609D02*
X1397970Y669620D01*
G01X1397953Y669600D02*
X1397963Y669609D01*
G01X1397970Y663320D02*
X1397972Y663333D01*
G01X1397963Y663309D02*
X1397970Y663320D01*
G01X1397953Y663301D02*
X1397963Y663309D01*
G01X1397970Y660171D02*
X1397972Y660183D01*
G01X1397963Y660160D02*
X1397970Y660171D01*
G01X1397953Y660152D02*
X1397963Y660160D01*
G01X1397970Y657021D02*
X1397972Y657034D01*
G01X1397963Y657010D02*
X1397970Y657021D01*
G01X1397953Y657002D02*
X1397963Y657010D01*
G01X1397970Y653872D02*
X1397972Y653884D01*
G01X1397963Y653861D02*
X1397970Y653872D01*
G01X1397953Y653852D02*
X1397963Y653861D01*
G01X1397027Y670793D02*
Y670799D01*
G01Y670789D02*
Y670793D01*
G01X1397025Y670787D02*
X1397027Y670789D01*
G01Y667643D02*
Y667649D01*
G01Y667639D02*
Y667643D01*
G01X1397025Y667638D02*
X1397027Y667639D01*
G01Y664493D02*
Y664500D01*
G01Y664489D02*
Y664493D01*
G01X1397025Y664488D02*
X1397027Y664489D01*
G01Y661344D02*
Y661350D01*
G01Y661340D02*
Y661344D01*
G01X1397025Y661339D02*
X1397027Y661340D01*
G01Y658194D02*
Y658200D01*
G01Y658190D02*
Y658194D01*
G01X1397025Y658189D02*
X1397027Y658190D01*
G01Y655044D02*
Y655051D01*
G01Y655041D02*
Y655044D01*
G01X1397025Y655039D02*
X1397027Y655041D01*
G01Y651895D02*
Y651901D01*
G01Y651891D02*
Y651895D01*
G01X1397025Y651890D02*
X1397027Y651891D01*
G01X1396989Y670768D02*
X1396988Y670762D01*
G01X1396991Y670774D02*
X1396989Y670768D01*
G01X1396993Y670780D02*
X1396991Y670774D01*
G01X1396997Y670785D02*
X1396993Y670780D01*
G01X1397002Y670790D02*
X1396997Y670785D01*
G01X1397007Y670794D02*
X1397002Y670790D01*
G01X1396989Y667619D02*
X1396988Y667612D01*
G01X1396991Y667625D02*
X1396989Y667619D01*
G01X1396993Y667630D02*
X1396991Y667625D01*
G01X1396997Y667636D02*
X1396993Y667630D01*
G01X1397002Y667640D02*
X1396997Y667636D01*
G01X1397007Y667644D02*
X1397002Y667640D01*
G01X1396989Y664469D02*
X1396988Y664463D01*
G01X1396991Y664475D02*
X1396989Y664469D01*
G01X1396993Y664481D02*
X1396991Y664475D01*
G01X1396997Y664486D02*
X1396993Y664481D01*
G01X1397002Y664491D02*
X1396997Y664486D01*
G01X1397007Y664494D02*
X1397002Y664491D01*
G01X1396989Y661319D02*
X1396988Y661313D01*
G01X1396991Y661326D02*
X1396989Y661319D01*
G01X1396993Y661331D02*
X1396991Y661326D01*
G01X1396997Y661337D02*
X1396993Y661331D01*
G01X1397002Y661341D02*
X1396997Y661337D01*
G01X1397007Y661345D02*
X1397002Y661341D01*
G01X1396989Y658170D02*
X1396988Y658163D01*
G01X1396991Y658176D02*
X1396989Y658170D01*
G01X1396993Y658181D02*
X1396991Y658176D01*
G01X1396997Y658187D02*
X1396993Y658181D01*
G01X1397002Y658191D02*
X1396997Y658187D01*
G01X1397007Y658195D02*
X1397002Y658191D01*
G01X1396989Y655020D02*
X1396988Y655014D01*
G01X1396991Y655026D02*
X1396989Y655020D01*
G01X1396993Y655032D02*
X1396991Y655026D01*
G01X1396997Y655037D02*
X1396993Y655032D01*
G01X1397002Y655042D02*
X1396997Y655037D01*
G01X1397007Y655046D02*
X1397002Y655042D01*
G01X1396989Y651870D02*
X1396988Y651864D01*
G01X1396991Y651877D02*
X1396989Y651870D01*
G01X1396993Y651882D02*
X1396991Y651877D01*
G01X1396997Y651888D02*
X1396993Y651882D01*
G01X1397002Y651892D02*
X1396997Y651888D01*
G01X1397007Y651896D02*
X1397002Y651892D01*
G01X1397944Y669608D02*
X1397931Y669606D01*
G01X1397954Y669613D02*
X1397944Y669608D01*
G01Y666459D02*
X1397931Y666457D01*
G01X1397954Y666464D02*
X1397944Y666459D01*
G01Y663309D02*
X1397931Y663307D01*
G01X1397954Y663314D02*
X1397944Y663309D01*
G01Y660159D02*
X1397931Y660157D01*
G01X1397954Y660165D02*
X1397944Y660159D01*
G01Y657010D02*
X1397931Y657008D01*
G01X1397954Y657015D02*
X1397944Y657010D01*
G01Y653860D02*
X1397931Y653858D01*
G01X1397954Y653865D02*
X1397944Y653860D01*
G01Y650711D02*
X1397931Y650709D01*
G01X1397954Y650716D02*
X1397944Y650711D01*
G01X1411398Y673904D02*
Y673911D01*
G01X1411399Y673900D02*
X1411398Y673904D01*
G01X1411400Y673898D02*
X1411399Y673900D01*
G01X1411398Y678904D02*
Y678911D01*
G01X1411399Y678900D02*
X1411398Y678904D01*
G01X1411400Y678898D02*
X1411399Y678900D01*
G01X1411398Y683904D02*
Y683911D01*
G01X1411399Y683900D02*
X1411398Y683904D01*
G01X1411400Y683898D02*
X1411399Y683900D01*
G01X1411398Y688904D02*
Y688911D01*
G01X1411399Y688900D02*
X1411398Y688904D01*
G01X1411400Y688898D02*
X1411399Y688900D01*
G01X1411398Y693904D02*
Y693911D01*
G01X1411399Y693900D02*
X1411398Y693904D01*
G01X1411400Y693898D02*
X1411399Y693900D01*
G01X1397011Y653861D02*
X1397025Y653858D01*
G01X1397000Y653868D02*
X1397011Y653861D01*
G01X1396987Y653887D02*
X1397000Y653868D01*
G01X1397011Y663310D02*
X1397025Y663307D01*
G01X1396999Y663317D02*
X1397011Y663310D01*
G01X1396987Y663335D02*
X1396999Y663317D01*
G01X1397011Y657011D02*
X1397025Y657008D01*
G01X1396998Y657019D02*
X1397011Y657011D01*
G01X1396987Y657039D02*
X1396998Y657019D01*
G01X1397011Y666459D02*
X1397025Y666457D01*
G01X1396998Y666467D02*
X1397011Y666459D01*
G01X1396987Y666487D02*
X1396998Y666467D01*
G01X1397972Y650742D02*
Y650735D01*
G01Y650747D02*
Y650742D01*
G01X1397971Y650748D02*
X1397972Y650747D01*
G01Y653892D02*
Y653884D01*
G01Y653896D02*
Y653892D01*
G01X1397971Y653898D02*
X1397972Y653896D01*
G01Y657041D02*
Y657034D01*
G01Y657046D02*
Y657041D01*
G01X1397971Y657047D02*
X1397972Y657046D01*
G01Y660191D02*
Y660183D01*
G01Y660196D02*
Y660191D01*
G01X1397971Y660197D02*
X1397972Y660196D01*
G01Y663341D02*
Y663333D01*
G01Y663345D02*
Y663341D01*
G01X1397971Y663346D02*
X1397972Y663345D01*
G01Y666490D02*
Y666483D01*
G01Y666495D02*
Y666490D01*
G01X1397971Y666496D02*
X1397972Y666495D01*
G01Y669640D02*
Y669632D01*
G01Y669644D02*
Y669640D01*
G01X1397971Y669646D02*
X1397972Y669644D01*
G01X1397011Y669609D02*
X1397025Y669606D01*
G01X1396998Y669617D02*
X1397011Y669609D01*
G01X1396987Y669637D02*
X1396998Y669617D01*
G01X1397010Y650712D02*
X1397025Y650709D01*
G01X1396997Y650720D02*
X1397010Y650712D01*
G01X1396987Y650741D02*
X1396997Y650720D01*
G01X1397972Y651871D02*
Y651864D01*
G01X1397970Y651877D02*
X1397972Y651871D01*
G01X1397967Y651883D02*
X1397970Y651877D01*
G01X1397972Y655020D02*
Y655014D01*
G01X1397970Y655027D02*
X1397972Y655020D01*
G01X1397967Y655033D02*
X1397970Y655027D01*
G01X1397972Y658170D02*
Y658163D01*
G01X1397970Y658176D02*
X1397972Y658170D01*
G01X1397967Y658182D02*
X1397970Y658176D01*
G01X1397972Y661320D02*
Y661313D01*
G01X1397970Y661326D02*
X1397972Y661320D01*
G01X1397967Y661332D02*
X1397970Y661326D01*
G01X1397972Y664469D02*
Y664463D01*
G01X1397970Y664476D02*
X1397972Y664469D01*
G01X1397967Y664481D02*
X1397970Y664476D01*
G01X1397972Y667619D02*
Y667612D01*
G01X1397970Y667625D02*
X1397972Y667619D01*
G01X1397967Y667631D02*
X1397970Y667625D01*
G01X1397972Y670769D02*
Y670762D01*
G01X1397970Y670775D02*
X1397972Y670769D01*
G01X1397967Y670781D02*
X1397970Y670775D01*
G01X1397933Y650704D02*
X1397934Y650698D01*
G01X1397932Y650707D02*
X1397933Y650704D01*
G01X1397931Y650709D02*
X1397932Y650707D01*
G01X1397933Y653853D02*
X1397934Y653847D01*
G01X1397932Y653857D02*
X1397933Y653853D01*
G01X1397931Y653858D02*
X1397932Y653857D01*
G01X1397933Y657003D02*
X1397934Y656997D01*
G01X1397932Y657007D02*
X1397933Y657003D01*
G01X1397931Y657008D02*
X1397932Y657007D01*
G01X1397933Y660152D02*
X1397934Y660146D01*
G01X1397932Y660156D02*
X1397933Y660152D01*
G01X1397931Y660157D02*
X1397932Y660156D01*
G01X1397933Y663302D02*
X1397934Y663296D01*
G01X1397932Y663306D02*
X1397933Y663302D01*
G01X1397931Y663307D02*
X1397932Y663306D01*
G01X1397933Y669601D02*
X1397934Y669595D01*
G01X1397932Y669605D02*
X1397933Y669601D01*
G01X1397931Y669606D02*
X1397932Y669605D01*
G01X1410413Y648944D02*
Y648954D01*
G01X1410414Y648939D02*
X1410413Y648944D01*
G01X1410415Y648937D02*
X1410414Y648939D01*
G01X1410413Y673944D02*
Y673954D01*
G01X1410414Y673939D02*
X1410413Y673944D01*
G01X1410415Y673937D02*
X1410414Y673939D01*
G01X1410413Y678944D02*
Y678954D01*
G01X1410414Y678939D02*
X1410413Y678944D01*
G01X1410415Y678937D02*
X1410414Y678939D01*
G01X1410413Y683944D02*
Y683954D01*
G01X1410414Y683939D02*
X1410413Y683944D01*
G01X1410415Y683937D02*
X1410414Y683939D01*
G01X1410413Y688944D02*
Y688954D01*
G01X1410414Y688939D02*
X1410413Y688944D01*
G01X1410415Y688937D02*
X1410414Y688939D01*
G01X1410413Y693944D02*
Y693954D01*
G01X1410414Y693939D02*
X1410413Y693944D01*
G01X1410415Y693937D02*
X1410414Y693939D01*
G01X1411390Y649081D02*
X1411398Y649055D01*
G01X1411380Y649107D02*
X1411390Y649081D01*
G01X1411369Y649134D02*
X1411380Y649107D01*
G01X1411390Y674081D02*
X1411398Y674055D01*
G01X1411380Y674107D02*
X1411390Y674081D01*
G01X1411369Y674134D02*
X1411380Y674107D01*
G01X1411390Y679081D02*
X1411398Y679055D01*
G01X1411380Y679107D02*
X1411390Y679081D01*
G01X1411369Y679134D02*
X1411380Y679107D01*
G01X1411390Y684081D02*
X1411398Y684055D01*
G01X1411380Y684107D02*
X1411390Y684081D01*
G01X1411369Y684134D02*
X1411380Y684107D01*
G01X1411390Y689081D02*
X1411398Y689055D01*
G01X1411380Y689107D02*
X1411390Y689081D01*
G01X1411369Y689134D02*
X1411380Y689107D01*
G01X1397006Y660163D02*
X1397025Y660157D01*
G01X1396993Y660175D02*
X1397006Y660163D01*
G01X1396986Y660193D02*
X1396993Y660175D01*
G01X1411365Y649035D02*
X1411369Y649134D01*
G01X1411359Y648963D02*
X1411365Y649035D01*
G01X1411361Y648937D02*
X1411359Y648963D01*
G01X1411365Y674035D02*
X1411369Y674134D01*
G01X1411359Y673963D02*
X1411365Y674035D01*
G01X1411361Y673937D02*
X1411359Y673963D01*
G01X1411365Y679035D02*
X1411369Y679134D01*
G01X1411359Y678963D02*
X1411365Y679035D01*
G01X1411361Y678937D02*
X1411359Y678963D01*
G01X1411365Y684035D02*
X1411369Y684134D01*
G01X1411359Y683963D02*
X1411365Y684035D01*
G01X1411361Y683937D02*
X1411359Y683963D01*
G01X1411365Y689035D02*
X1411369Y689134D01*
G01X1411359Y688963D02*
X1411365Y689035D01*
G01X1411361Y688937D02*
X1411359Y688963D01*
G01X1411365Y694035D02*
X1411369Y694134D01*
G01X1411359Y693963D02*
X1411365Y694035D01*
G01X1411361Y693937D02*
X1411359Y693963D01*
G01X1396988Y663341D02*
Y663333D01*
G01X1396987Y663345D02*
X1396988Y663341D01*
G01X1396987Y663336D02*
Y663345D01*
G01X1397028Y670972D02*
Y670984D01*
G01X1397025Y670959D02*
X1397028Y670972D01*
G01X1397025Y670945D02*
Y670959D01*
G01X1397028Y667822D02*
Y667835D01*
G01X1397025Y667809D02*
X1397028Y667822D01*
G01X1397025Y667796D02*
Y667809D01*
G01X1397028Y664673D02*
Y664685D01*
G01X1397025Y664660D02*
X1397028Y664673D01*
G01X1397025Y664646D02*
Y664660D01*
G01X1397028Y661523D02*
Y661535D01*
G01X1397025Y661510D02*
X1397028Y661523D01*
G01X1397025Y661496D02*
Y661510D01*
G01X1397028Y658374D02*
Y658386D01*
G01X1397025Y658361D02*
X1397028Y658374D01*
G01X1397025Y658347D02*
Y658361D01*
G01X1397028Y655224D02*
Y655236D01*
G01X1397025Y655211D02*
X1397028Y655224D01*
G01X1397025Y655197D02*
Y655211D01*
G01X1397028Y652074D02*
Y652087D01*
G01X1397025Y652061D02*
X1397028Y652074D01*
G01X1397025Y652048D02*
Y652061D01*
G01X1410414Y692557D02*
X1410415Y692559D01*
G01X1410413Y692552D02*
X1410414Y692557D01*
G01X1410413Y692543D02*
Y692552D01*
G01X1410414Y687557D02*
X1410415Y687559D01*
G01X1410413Y687552D02*
X1410414Y687557D01*
G01X1410413Y687543D02*
Y687552D01*
G01X1410414Y682557D02*
X1410415Y682559D01*
G01X1410413Y682552D02*
X1410414Y682557D01*
G01X1410413Y682543D02*
Y682552D01*
G01X1410414Y677557D02*
X1410415Y677559D01*
G01X1410413Y677552D02*
X1410414Y677557D01*
G01X1410413Y677543D02*
Y677552D01*
G01X1410414Y672557D02*
X1410415Y672559D01*
G01X1410413Y672552D02*
X1410414Y672557D01*
G01X1410413Y672543D02*
Y672552D01*
G01X1396988Y669640D02*
Y669632D01*
G01X1396987Y669644D02*
X1396988Y669640D01*
G01X1396987Y669637D02*
Y669644D01*
G01X1397025Y669435D02*
X1397024Y669448D01*
G01X1397028Y669422D02*
X1397025Y669435D01*
G01X1397028Y669409D02*
Y669422D01*
G01X1397025Y666285D02*
X1397024Y666299D01*
G01X1397028Y666272D02*
X1397025Y666285D01*
G01X1397028Y666260D02*
Y666272D01*
G01X1397025Y663136D02*
X1397024Y663149D01*
G01X1397028Y663123D02*
X1397025Y663136D01*
G01X1397028Y663110D02*
Y663123D01*
G01X1397025Y659986D02*
X1397024Y660000D01*
G01X1397028Y659973D02*
X1397025Y659986D01*
G01X1397028Y659961D02*
Y659973D01*
G01X1397025Y656837D02*
X1397024Y656850D01*
G01X1397028Y656824D02*
X1397025Y656837D01*
G01X1397028Y656811D02*
Y656824D01*
G01X1397025Y653687D02*
X1397024Y653700D01*
G01X1397028Y653674D02*
X1397025Y653687D01*
G01X1397028Y653661D02*
Y653674D01*
G01X1397025Y650537D02*
X1397024Y650551D01*
G01X1397028Y650524D02*
X1397025Y650537D01*
G01X1397028Y650512D02*
Y650524D01*
G01X1397935Y670959D02*
X1397937Y670945D01*
G01X1397932Y670972D02*
X1397935Y670959D01*
G01X1397933Y670984D02*
X1397932Y670972D01*
G01X1397935Y667809D02*
X1397937Y667796D01*
G01X1397932Y667822D02*
X1397935Y667809D01*
G01X1397933Y667835D02*
X1397932Y667822D01*
G01X1397935Y664659D02*
X1397937Y664646D01*
G01X1397932Y664672D02*
X1397935Y664659D01*
G01X1397933Y664685D02*
X1397932Y664672D01*
G01X1397935Y661510D02*
X1397937Y661496D01*
G01X1397932Y661523D02*
X1397935Y661510D01*
G01X1397933Y661535D02*
X1397932Y661523D01*
G01X1397935Y658360D02*
X1397937Y658347D01*
G01X1397932Y658373D02*
X1397935Y658360D01*
G01X1397933Y658386D02*
X1397932Y658373D01*
G01X1397935Y655211D02*
X1397937Y655197D01*
G01X1397932Y655224D02*
X1397935Y655211D01*
G01X1397933Y655236D02*
X1397932Y655224D01*
G01X1397935Y652061D02*
X1397937Y652048D01*
G01X1397932Y652074D02*
X1397935Y652061D01*
G01X1397933Y652087D02*
X1397932Y652074D01*
G01X1396988Y657041D02*
Y657034D01*
G01X1396987Y657046D02*
X1396988Y657041D01*
G01X1396987Y657039D02*
Y657046D01*
G01X1396988Y666490D02*
Y666483D01*
G01X1396987Y666495D02*
X1396988Y666490D01*
G01X1396987Y666488D02*
Y666495D01*
G01X1397932Y669422D02*
X1397933Y669409D01*
G01X1397935Y669435D02*
X1397932Y669422D01*
G01X1397936Y669448D02*
X1397935Y669435D01*
G01X1397932Y666272D02*
X1397933Y666260D01*
G01X1397935Y666285D02*
X1397932Y666272D01*
G01X1397936Y666299D02*
X1397935Y666285D01*
G01X1397932Y663123D02*
X1397933Y663110D01*
G01X1397935Y663136D02*
X1397932Y663123D01*
G01X1397936Y663149D02*
X1397935Y663136D01*
G01X1397932Y659973D02*
X1397933Y659961D01*
G01X1397935Y659986D02*
X1397932Y659973D01*
G01X1397936Y660000D02*
X1397935Y659986D01*
G01X1397932Y656824D02*
X1397933Y656811D01*
G01X1397935Y656837D02*
X1397932Y656824D01*
G01X1397936Y656850D02*
X1397935Y656837D01*
G01X1397932Y653674D02*
X1397933Y653661D01*
G01X1397935Y653687D02*
X1397932Y653674D01*
G01X1397936Y653700D02*
X1397935Y653687D01*
G01X1397932Y650524D02*
X1397933Y650512D01*
G01X1397935Y650537D02*
X1397932Y650524D01*
G01X1397936Y650551D02*
X1397935Y650537D01*
G01X1396988Y650743D02*
Y650735D01*
G01X1396987Y650747D02*
X1396988Y650743D01*
G01X1396987Y650741D02*
Y650747D01*
G01X1397001Y670779D02*
X1397025Y670787D01*
G01X1396990Y670765D02*
X1397001Y670779D01*
G01X1396988Y670758D02*
X1396990Y670765D01*
G01X1397001Y667630D02*
X1397025Y667638D01*
G01X1396990Y667615D02*
X1397001Y667630D01*
G01X1396988Y667608D02*
X1396990Y667615D01*
G01X1397001Y664480D02*
X1397025Y664488D01*
G01X1396990Y664465D02*
X1397001Y664480D01*
G01X1396988Y664459D02*
X1396990Y664465D01*
G01X1397001Y661330D02*
X1397025Y661339D01*
G01X1396990Y661316D02*
X1397001Y661330D01*
G01X1396988Y661309D02*
X1396990Y661316D01*
G01X1397001Y658181D02*
X1397025Y658189D01*
G01X1396990Y658166D02*
X1397001Y658181D01*
G01X1396988Y658159D02*
X1396990Y658166D01*
G01X1397001Y655031D02*
X1397025Y655039D01*
G01X1396990Y655017D02*
X1397001Y655031D01*
G01X1396988Y655010D02*
X1396990Y655017D01*
G01X1397001Y651881D02*
X1397025Y651890D01*
G01X1396990Y651867D02*
X1397001Y651881D01*
G01X1396988Y651860D02*
X1396990Y651867D01*
G01X1397972Y670754D02*
Y670761D01*
G01Y670750D02*
Y670754D01*
G01X1397971Y670748D02*
X1397972Y670750D01*
G01Y667605D02*
Y667612D01*
G01Y667600D02*
Y667605D01*
G01X1397971Y667598D02*
X1397972Y667600D01*
G01Y664455D02*
Y664462D01*
G01Y664451D02*
Y664455D01*
G01X1397971Y664449D02*
X1397972Y664451D01*
G01Y661306D02*
Y661313D01*
G01Y661301D02*
Y661306D01*
G01X1397971Y661299D02*
X1397972Y661301D01*
G01Y658156D02*
Y658163D01*
G01Y658152D02*
Y658156D01*
G01X1397971Y658150D02*
X1397972Y658152D01*
G01Y655006D02*
Y655013D01*
G01Y655002D02*
Y655006D01*
G01X1397971Y655000D02*
X1397972Y655002D01*
G01Y651857D02*
Y651864D01*
G01Y651852D02*
Y651857D01*
G01X1397971Y651850D02*
X1397972Y651852D01*
G01X1396988Y660191D02*
Y660183D01*
G01X1396987Y660196D02*
X1396988Y660191D01*
G01X1396986Y660193D02*
X1396987Y660196D01*
G01X1396988Y653892D02*
Y653884D01*
G01X1396987Y653896D02*
X1396988Y653892D01*
G01X1396986Y653894D02*
X1396987Y653896D01*
G01X1397933Y670793D02*
Y670799D01*
G01X1397932Y670789D02*
X1397933Y670793D01*
G01X1397931Y670787D02*
X1397932Y670789D01*
G01X1397933Y667643D02*
Y667649D01*
G01X1397932Y667639D02*
X1397933Y667643D01*
G01X1397931Y667638D02*
X1397932Y667639D01*
G01X1397933Y664493D02*
Y664500D01*
G01X1397932Y664490D02*
X1397933Y664493D01*
G01X1397931Y664488D02*
X1397932Y664490D01*
G01X1397933Y661344D02*
Y661350D01*
G01X1397932Y661340D02*
X1397933Y661344D01*
G01X1397931Y661339D02*
X1397932Y661340D01*
G01X1397933Y658194D02*
Y658200D01*
G01X1397932Y658191D02*
X1397933Y658194D01*
G01X1397931Y658189D02*
X1397932Y658191D01*
G01X1397933Y655044D02*
Y655051D01*
G01X1397932Y655041D02*
X1397933Y655044D01*
G01X1397931Y655039D02*
X1397932Y655041D01*
G01X1397933Y651895D02*
Y651901D01*
G01X1397932Y651891D02*
X1397933Y651895D01*
G01X1397931Y651890D02*
X1397932Y651891D01*
G01X1411398Y692552D02*
Y692543D01*
G01X1411399Y692557D02*
X1411398Y692552D01*
G01X1411400Y692559D02*
X1411399Y692557D01*
G01X1411398Y687552D02*
Y687543D01*
G01X1411399Y687557D02*
X1411398Y687552D01*
G01X1411400Y687559D02*
X1411399Y687557D01*
G01X1411398Y682552D02*
Y682543D01*
G01X1411399Y682557D02*
X1411398Y682552D01*
G01X1411400Y682559D02*
X1411399Y682557D01*
G01X1411398Y677552D02*
Y677543D01*
G01X1411399Y677557D02*
X1411398Y677552D01*
G01X1411400Y677559D02*
X1411399Y677557D01*
G01X1411398Y672552D02*
Y672543D01*
G01X1411399Y672557D02*
X1411398Y672552D01*
G01X1411400Y672559D02*
X1411399Y672557D01*
G01X1396988Y670754D02*
Y670762D01*
G01X1396987Y670750D02*
X1396988Y670754D01*
G01X1396986Y670748D02*
X1396987Y670750D01*
G01X1396988Y667605D02*
Y667612D01*
G01X1396987Y667600D02*
X1396988Y667605D01*
G01X1396986Y667598D02*
X1396987Y667600D01*
G01X1396988Y664455D02*
Y664463D01*
G01X1396987Y664450D02*
X1396988Y664455D01*
G01X1396986Y664449D02*
X1396987Y664450D01*
G01X1396988Y661306D02*
Y661313D01*
G01X1396987Y661301D02*
X1396988Y661306D01*
G01X1396986Y661299D02*
X1396987Y661301D01*
G01X1396988Y658156D02*
Y658163D01*
G01X1396987Y658151D02*
X1396988Y658156D01*
G01X1396986Y658150D02*
X1396987Y658151D01*
G01X1396988Y655006D02*
Y655014D01*
G01X1396987Y655002D02*
X1396988Y655006D01*
G01X1396986Y655000D02*
X1396987Y655002D01*
G01X1396988Y651857D02*
Y651864D01*
G01X1396987Y651852D02*
X1396988Y651857D01*
G01X1396986Y651850D02*
X1396987Y651852D01*
G01X1397970Y650722D02*
X1397972Y650735D01*
G01X1397963Y650711D02*
X1397970Y650722D01*
G01X1397953Y650703D02*
X1397963Y650711D01*
G01X1411390Y694081D02*
X1411398Y694055D01*
G01X1411380Y694107D02*
X1411390Y694081D01*
G01X1411369Y694134D02*
X1411380Y694107D01*
G01Y648932D02*
X1411361Y648937D01*
G01X1411395Y648918D02*
X1411380Y648932D01*
G01X1411400Y648898D02*
X1411395Y648918D01*
G01X1411380Y673932D02*
X1411361Y673937D01*
G01X1411395Y673918D02*
X1411380Y673932D01*
G01X1411400Y673898D02*
X1411395Y673918D01*
G01X1411380Y678932D02*
X1411361Y678937D01*
G01X1411395Y678918D02*
X1411380Y678932D01*
G01X1411400Y678898D02*
X1411395Y678918D01*
G01X1411380Y683932D02*
X1411361Y683937D01*
G01X1411395Y683918D02*
X1411380Y683932D01*
G01X1411400Y683898D02*
X1411395Y683918D01*
G01X1411380Y688932D02*
X1411361Y688937D01*
G01X1411395Y688918D02*
X1411380Y688932D01*
G01X1411400Y688898D02*
X1411395Y688918D01*
G01X1411380Y693932D02*
X1411361Y693937D01*
G01X1411395Y693918D02*
X1411380Y693932D01*
G01X1411400Y693898D02*
X1411395Y693918D01*
G01X1397965Y658171D02*
X1397957Y658180D01*
G01X1397969Y658161D02*
X1397965Y658171D01*
G01X1397971Y658150D02*
X1397969Y658161D01*
G01X1397965Y651872D02*
X1397957Y651880D01*
G01X1397970Y651861D02*
X1397965Y651872D01*
G01X1397971Y651850D02*
X1397970Y651861D01*
G01X1397965Y655021D02*
X1397957Y655030D01*
G01X1397970Y655011D02*
X1397965Y655021D01*
G01X1397971Y655000D02*
X1397970Y655011D01*
G01X1397965Y661320D02*
X1397957Y661329D01*
G01X1397970Y661310D02*
X1397965Y661320D01*
G01X1397971Y661299D02*
X1397970Y661310D01*
G01X1397965Y664470D02*
X1397957Y664479D01*
G01X1397970Y664460D02*
X1397965Y664470D01*
G01X1397971Y664449D02*
X1397970Y664460D01*
G01X1397965Y667620D02*
X1397957Y667628D01*
G01X1397970Y667609D02*
X1397965Y667620D01*
G01X1397971Y667598D02*
X1397970Y667609D01*
G01X1397965Y670769D02*
X1397957Y670778D01*
G01X1397970Y670759D02*
X1397965Y670769D01*
G01X1397971Y670748D02*
X1397970Y670759D01*
G01X1397931Y666457D02*
X1397935Y666446D01*
G01X1410827Y670610D02*
X1412008Y671791D01*
G01X1406890Y670610D02*
X1408071Y671791D01*
G01X1397972Y651853D02*
Y651864D01*
G01Y655002D02*
Y655013D01*
G01Y658152D02*
Y658163D01*
G01Y661302D02*
Y661313D01*
G01Y664451D02*
Y664462D01*
G01Y667601D02*
Y667612D01*
G01Y670750D02*
Y670761D01*
G01X1411398Y648911D02*
Y648920D01*
G01Y673911D02*
Y673920D01*
G01Y678911D02*
Y678920D01*
G01Y683911D02*
Y683920D01*
G01Y688911D02*
Y688920D01*
G01Y693911D02*
Y693920D01*
G01X1415748Y692559D02*
Y693937D01*
G01Y687559D02*
Y688937D01*
G01Y682559D02*
Y683937D01*
G01Y677559D02*
Y678937D01*
G01Y672559D02*
Y673937D01*
G01X1412579D02*
Y672559D01*
G01Y678937D02*
Y677559D01*
G01Y683937D02*
Y682559D01*
G01Y688937D02*
Y687559D01*
G01Y693937D02*
Y692559D01*
G01X1412008Y671791D02*
Y649705D01*
G01X1411398Y692067D02*
Y694429D01*
G01Y687067D02*
Y689429D01*
G01Y682067D02*
Y684429D01*
G01Y677067D02*
Y679429D01*
G01Y672067D02*
Y674429D01*
G01X1410827Y670610D02*
Y650886D01*
G01X1410413Y674429D02*
Y672067D01*
G01Y679429D02*
Y677067D01*
G01Y684429D02*
Y682067D01*
G01Y689429D02*
Y687067D01*
G01Y694429D02*
Y692067D01*
G01X1408071Y748248D02*
Y671791D01*
G01X1406890Y747067D02*
Y670610D01*
G01X1398425Y751988D02*
Y672953D01*
G01X1397972Y669449D02*
Y670945D01*
G01Y666299D02*
Y667795D01*
G01Y663150D02*
Y664646D01*
G01Y660000D02*
Y661496D01*
G01Y656850D02*
Y658346D01*
G01Y653701D02*
Y655197D01*
G01Y650551D02*
Y652047D01*
G01X1397933Y650698D02*
Y650551D01*
G01Y652048D02*
Y651901D01*
G01Y656997D02*
Y656850D01*
G01Y653847D02*
Y653700D01*
G01Y655197D02*
Y655051D01*
G01Y660146D02*
Y660000D01*
G01Y661496D02*
Y661350D01*
G01Y658347D02*
Y658200D01*
G01Y666446D02*
Y666299D01*
G01Y663296D02*
Y663149D01*
G01Y664646D02*
Y664500D01*
G01Y669595D02*
Y669448D01*
G01Y670945D02*
Y670799D01*
G01Y667796D02*
Y667649D01*
G01X1397028Y669448D02*
Y669595D01*
G01Y670799D02*
Y670946D01*
G01Y667649D02*
Y667796D01*
G01Y666298D02*
Y666446D01*
G01Y663149D02*
Y663296D01*
G01Y664500D02*
Y664646D01*
G01Y659999D02*
Y660146D01*
G01Y661350D02*
Y661497D01*
G01Y658200D02*
Y658347D01*
G01Y656850D02*
Y656997D01*
G01Y653700D02*
Y653847D01*
G01Y655051D02*
Y655198D01*
G01Y650550D02*
Y650698D01*
G01Y651901D02*
Y652048D01*
G01X1396988Y652047D02*
Y650551D01*
G01Y655197D02*
Y653701D01*
G01Y661496D02*
Y660000D01*
G01Y658346D02*
Y656850D01*
G01Y664646D02*
Y663150D01*
G01Y670945D02*
Y669449D01*
G01Y667795D02*
Y666299D01*
G01X1395807Y651890D02*
Y650709D01*
G01Y658189D02*
Y657008D01*
G01Y655039D02*
Y653858D01*
G01Y661339D02*
Y660157D01*
G01Y667638D02*
Y666457D01*
G01Y664488D02*
Y663307D01*
G01Y670787D02*
Y669606D01*
G01X1395472Y672953D02*
Y648543D01*
G01X1395079D02*
Y672953D01*
G01X1392047Y669606D02*
Y670787D01*
G01Y666457D02*
Y667638D01*
G01Y663307D02*
Y664488D01*
G01Y660157D02*
Y661339D01*
G01Y657008D02*
Y658189D01*
G01Y653858D02*
Y655039D01*
G01Y650709D02*
Y651890D01*
G01X1397972Y669632D02*
Y669643D01*
G01Y666483D02*
Y666494D01*
G01Y663333D02*
Y663344D01*
G01Y660183D02*
Y660194D01*
G01Y657034D02*
Y657045D01*
G01Y653884D02*
Y653895D01*
G01Y650735D02*
Y650746D01*
G01X1410827Y650886D02*
X1412008Y649705D01*
G01X1406890Y650886D02*
X1408071Y649705D01*
G01X1396875Y669646D02*
X1396987Y669637D01*
G01X1396986Y660193D02*
X1396875Y660197D01*
G01X1396986Y653894D02*
X1396875Y653898D01*
G01X1396986Y663343D02*
X1396875Y663346D01*
G01X1411398Y694429D02*
X1410413D01*
G01X1410415Y693937D02*
X1415748D01*
G01Y693898D02*
X1411400D01*
G01X1415748Y692559D02*
X1410415D01*
G01X1410413Y692067D02*
X1411398D01*
G01Y689429D02*
X1410413D01*
G01X1410415Y688937D02*
X1415748D01*
G01Y688898D02*
X1411400D01*
G01X1415748Y687559D02*
X1410415D01*
G01X1410413Y687067D02*
X1411398D01*
G01Y684429D02*
X1410413D01*
G01X1410415Y683937D02*
X1415748D01*
G01Y683898D02*
X1411400D01*
G01X1415748Y682559D02*
X1410415D01*
G01X1410413Y682067D02*
X1411398D01*
G01Y679429D02*
X1410413D01*
G01X1410415Y678937D02*
X1415748D01*
G01Y678898D02*
X1411400D01*
G01X1415748Y677559D02*
X1410415D01*
G01X1410413Y677067D02*
X1411398D01*
G01Y674429D02*
X1410413D01*
G01X1410415Y673937D02*
X1415748D01*
G01Y673898D02*
X1411400D01*
G01X1398425Y672953D02*
X1395079D01*
G01X1415748Y672559D02*
X1410415D01*
G01X1410413Y672067D02*
X1411398D01*
G01X1408071Y671791D02*
X1412008D01*
G01X1397933Y670984D02*
X1397028D01*
G01X1397972Y670945D02*
X1396988D01*
G01X1397931Y670787D02*
X1392047D01*
G01Y670748D02*
X1397971D01*
G01X1406890Y670610D02*
X1410827D01*
G01X1397971Y669646D02*
X1392047D01*
G01X1397931Y669606D02*
X1392047D01*
G01X1396988Y669449D02*
X1397972D01*
G01X1397028Y669409D02*
X1397933D01*
G01Y667835D02*
X1397028D01*
G01X1397972Y667795D02*
X1396988D01*
G01X1397931Y667638D02*
X1392047D01*
G01Y667598D02*
X1397971D01*
G01Y666496D02*
X1392047D01*
G01X1397931Y666457D02*
X1392047D01*
G01X1396988Y666299D02*
X1397972D01*
G01X1397028Y666260D02*
X1397933D01*
G01Y664685D02*
X1397028D01*
G01X1397972Y664646D02*
X1396988D01*
G01X1397931Y664488D02*
X1392047D01*
G01Y664449D02*
X1397971D01*
G01X1396241Y663346D02*
X1395807D01*
G01X1397971D02*
X1392047D01*
G01X1397931Y663307D02*
X1392047D01*
G01X1396988Y663150D02*
X1397972D01*
G01X1397028Y663110D02*
X1397933D01*
G01Y661535D02*
X1397028D01*
G01X1397972Y661496D02*
X1396988D01*
G01X1397931Y661339D02*
X1392047D01*
G01Y661299D02*
X1397971D01*
G01X1396241Y660197D02*
X1395807D01*
G01X1397971D02*
X1392047D01*
G01X1397931Y660157D02*
X1392047D01*
G01X1396988Y660000D02*
X1397972D01*
G01X1397028Y659961D02*
X1397933D01*
G01Y658386D02*
X1397028D01*
G01X1397972Y658346D02*
X1396988D01*
G01X1397931Y658189D02*
X1392047D01*
G01Y658150D02*
X1397971D01*
G01Y657047D02*
X1392047D01*
G01X1397931Y657008D02*
X1392047D01*
G01X1396988Y656850D02*
X1397972D01*
G01X1397028Y656811D02*
X1397933D01*
G01Y655236D02*
X1397028D01*
G01X1397972Y655197D02*
X1396988D01*
G01X1397931Y655039D02*
X1392047D01*
G01Y655000D02*
X1397971D01*
G01X1396241Y653898D02*
X1395807D01*
G01X1397971D02*
X1392047D01*
G01X1397931Y653858D02*
X1392047D01*
G01X1396988Y653701D02*
X1397972D01*
G01X1397028Y653661D02*
X1397933D01*
G01Y652087D02*
X1397028D01*
G01X1397972Y652047D02*
X1396988D01*
G01X1397931Y651890D02*
X1392047D01*
G01Y651850D02*
X1397971D01*
G01X1410827Y650886D02*
X1406890D01*
G01X1397971Y650748D02*
X1392047D01*
G01X1397931Y650709D02*
X1392047D01*
G01X1396988Y650551D02*
X1397972D01*
G01X1397028Y650512D02*
X1397933D01*
G01X1412008Y649705D02*
X1408071D01*
G01X1411398Y649429D02*
X1410413D01*
G01X1410415Y648937D02*
X1415748D01*
G01Y648898D02*
X1411400D01*
G01X1398425Y648543D02*
X1395079D01*
G01X1410413Y694133D02*
X1411369Y694134D01*
G01X1411398Y692363D02*
X1410413Y692362D01*
G01Y689133D02*
X1411369Y689134D01*
G01X1411398Y687363D02*
X1410413Y687362D01*
G01Y684133D02*
X1411369Y684134D01*
G01X1411398Y682363D02*
X1410413Y682362D01*
G01Y679133D02*
X1411369Y679134D01*
G01X1411398Y677363D02*
X1410413Y677362D01*
G01Y674133D02*
X1411369Y674134D01*
G01X1411398Y672363D02*
X1410413Y672362D01*
G01Y649133D02*
X1411369Y649134D01*
G01X1411385Y698929D02*
X1411396Y698913D01*
G01X1411361Y698937D02*
X1411385Y698929D01*
G01Y703929D02*
X1411396Y703913D01*
G01X1411361Y703937D02*
X1411385Y703929D01*
G01Y708929D02*
X1411396Y708913D01*
G01X1411361Y708937D02*
X1411385Y708929D01*
G01Y713929D02*
X1411396Y713913D01*
G01X1411361Y713937D02*
X1411385Y713929D01*
G01Y718929D02*
X1411396Y718913D01*
G01X1411361Y718937D02*
X1411385Y718929D01*
G01Y723929D02*
X1411396Y723913D01*
G01X1411361Y723937D02*
X1411385Y723929D01*
G01Y728929D02*
X1411396Y728913D01*
G01X1411361Y728937D02*
X1411385Y728929D01*
G01Y733929D02*
X1411396Y733913D01*
G01X1411361Y733937D02*
X1411385Y733929D01*
G01Y738929D02*
X1411396Y738913D01*
G01X1411361Y738937D02*
X1411385Y738929D01*
G01Y743929D02*
X1411396Y743913D01*
G01X1411361Y743937D02*
X1411385Y743929D01*
G01X1411398Y698904D02*
Y698911D01*
G01X1411399Y698900D02*
X1411398Y698904D01*
G01X1411400Y698898D02*
X1411399Y698900D01*
G01X1411398Y703904D02*
Y703911D01*
G01X1411399Y703900D02*
X1411398Y703904D01*
G01X1411400Y703898D02*
X1411399Y703900D01*
G01X1411398Y708904D02*
Y708911D01*
G01X1411399Y708900D02*
X1411398Y708904D01*
G01X1411400Y708898D02*
X1411399Y708900D01*
G01X1411398Y713904D02*
Y713911D01*
G01X1411399Y713900D02*
X1411398Y713904D01*
G01X1411400Y713898D02*
X1411399Y713900D01*
G01X1411398Y718904D02*
Y718911D01*
G01X1411399Y718900D02*
X1411398Y718904D01*
G01X1411400Y718898D02*
X1411399Y718900D01*
G01X1411398Y723904D02*
Y723911D01*
G01X1411399Y723900D02*
X1411398Y723904D01*
G01X1411400Y723898D02*
X1411399Y723900D01*
G01X1411398Y728904D02*
Y728911D01*
G01X1411399Y728900D02*
X1411398Y728904D01*
G01X1411400Y728898D02*
X1411399Y728900D01*
G01X1411398Y733904D02*
Y733911D01*
G01X1411399Y733900D02*
X1411398Y733904D01*
G01X1411400Y733898D02*
X1411399Y733900D01*
G01X1411398Y738904D02*
Y738911D01*
G01X1411399Y738900D02*
X1411398Y738904D01*
G01X1411400Y738898D02*
X1411399Y738900D01*
G01X1411398Y743904D02*
Y743911D01*
G01X1411399Y743900D02*
X1411398Y743904D01*
G01X1411400Y743898D02*
X1411399Y743900D01*
G01X1411365Y699035D02*
X1411369Y699134D01*
G01X1411359Y698963D02*
X1411365Y699035D01*
G01X1411361Y698937D02*
X1411359Y698963D01*
G01X1411365Y704035D02*
X1411369Y704134D01*
G01X1411359Y703963D02*
X1411365Y704035D01*
G01X1411361Y703937D02*
X1411359Y703963D01*
G01X1411365Y709035D02*
X1411369Y709134D01*
G01X1411359Y708963D02*
X1411365Y709035D01*
G01X1411361Y708937D02*
X1411359Y708963D01*
G01X1411365Y714035D02*
X1411369Y714134D01*
G01X1411359Y713963D02*
X1411365Y714035D01*
G01X1411361Y713937D02*
X1411359Y713963D01*
G01X1411365Y719035D02*
X1411369Y719134D01*
G01X1411359Y718963D02*
X1411365Y719035D01*
G01X1411361Y718937D02*
X1411359Y718963D01*
G01X1411365Y724035D02*
X1411369Y724134D01*
G01X1411359Y723963D02*
X1411365Y724035D01*
G01X1411361Y723937D02*
X1411359Y723963D01*
G01X1411365Y729035D02*
X1411369Y729134D01*
G01X1411359Y728963D02*
X1411365Y729035D01*
G01X1411361Y728937D02*
X1411359Y728963D01*
G01X1411365Y734035D02*
X1411369Y734134D01*
G01X1411359Y733963D02*
X1411365Y734035D01*
G01X1411361Y733937D02*
X1411359Y733963D01*
G01X1411365Y739035D02*
X1411369Y739134D01*
G01X1411359Y738963D02*
X1411365Y739035D01*
G01X1411361Y738937D02*
X1411359Y738963D01*
G01X1411365Y744035D02*
X1411369Y744134D01*
G01X1411359Y743963D02*
X1411365Y744035D01*
G01X1411361Y743937D02*
X1411359Y743963D01*
G01X1410414Y742557D02*
X1410415Y742559D01*
G01X1410413Y742552D02*
X1410414Y742557D01*
G01X1410413Y742543D02*
Y742552D01*
G01X1410414Y737557D02*
X1410415Y737559D01*
G01X1410413Y737552D02*
X1410414Y737557D01*
G01X1410413Y737543D02*
Y737552D01*
G01X1410414Y732557D02*
X1410415Y732559D01*
G01X1410413Y732552D02*
X1410414Y732557D01*
G01X1410413Y732543D02*
Y732552D01*
G01X1410414Y727557D02*
X1410415Y727559D01*
G01X1410413Y727552D02*
X1410414Y727557D01*
G01X1410413Y727543D02*
Y727552D01*
G01X1410414Y722557D02*
X1410415Y722559D01*
G01X1410413Y722552D02*
X1410414Y722557D01*
G01X1410413Y722543D02*
Y722552D01*
G01X1410414Y717557D02*
X1410415Y717559D01*
G01X1410413Y717552D02*
X1410414Y717557D01*
G01X1410413Y717543D02*
Y717552D01*
G01X1410414Y712557D02*
X1410415Y712559D01*
G01X1410413Y712552D02*
X1410414Y712557D01*
G01X1410413Y712543D02*
Y712552D01*
G01X1410414Y707557D02*
X1410415Y707559D01*
G01X1410413Y707552D02*
X1410414Y707557D01*
G01X1410413Y707543D02*
Y707552D01*
G01X1410414Y702557D02*
X1410415Y702559D01*
G01X1410413Y702552D02*
X1410414Y702557D01*
G01X1410413Y702543D02*
Y702552D01*
G01X1410414Y697557D02*
X1410415Y697559D01*
G01X1410413Y697552D02*
X1410414Y697557D01*
G01X1410413Y697543D02*
Y697552D01*
G01X1411398Y742552D02*
Y742543D01*
G01X1411399Y742557D02*
X1411398Y742552D01*
G01X1411400Y742559D02*
X1411399Y742557D01*
G01X1411398Y737552D02*
Y737543D01*
G01X1411399Y737557D02*
X1411398Y737552D01*
G01X1411400Y737559D02*
X1411399Y737557D01*
G01X1411398Y732552D02*
Y732543D01*
G01X1411399Y732557D02*
X1411398Y732552D01*
G01X1411400Y732559D02*
X1411399Y732557D01*
G01X1411398Y727552D02*
Y727543D01*
G01X1411399Y727557D02*
X1411398Y727552D01*
G01X1411400Y727559D02*
X1411399Y727557D01*
G01X1411398Y722552D02*
Y722543D01*
G01X1411399Y722557D02*
X1411398Y722552D01*
G01X1411400Y722559D02*
X1411399Y722557D01*
G01X1411398Y717552D02*
Y717543D01*
G01X1411399Y717557D02*
X1411398Y717552D01*
G01X1411400Y717559D02*
X1411399Y717557D01*
G01X1411398Y712552D02*
Y712543D01*
G01X1411399Y712557D02*
X1411398Y712552D01*
G01X1411400Y712559D02*
X1411399Y712557D01*
G01X1411398Y707552D02*
Y707543D01*
G01X1411399Y707557D02*
X1411398Y707552D01*
G01X1411400Y707559D02*
X1411399Y707557D01*
G01X1411398Y702552D02*
Y702543D01*
G01X1411399Y702557D02*
X1411398Y702552D01*
G01X1411400Y702559D02*
X1411399Y702557D01*
G01X1411398Y697552D02*
Y697543D01*
G01X1411399Y697557D02*
X1411398Y697552D01*
G01X1411400Y697559D02*
X1411399Y697557D01*
G01X1410413Y698944D02*
Y698954D01*
G01X1410414Y698939D02*
X1410413Y698944D01*
G01X1410415Y698937D02*
X1410414Y698939D01*
G01X1410413Y703944D02*
Y703954D01*
G01X1410414Y703939D02*
X1410413Y703944D01*
G01X1410415Y703937D02*
X1410414Y703939D01*
G01X1410413Y708944D02*
Y708954D01*
G01X1410414Y708939D02*
X1410413Y708944D01*
G01X1410415Y708937D02*
X1410414Y708939D01*
G01X1410413Y713944D02*
Y713954D01*
G01X1410414Y713939D02*
X1410413Y713944D01*
G01X1410415Y713937D02*
X1410414Y713939D01*
G01X1410413Y718944D02*
Y718954D01*
G01X1410414Y718939D02*
X1410413Y718944D01*
G01X1410415Y718937D02*
X1410414Y718939D01*
G01X1410413Y723944D02*
Y723954D01*
G01X1410414Y723939D02*
X1410413Y723944D01*
G01X1410415Y723937D02*
X1410414Y723939D01*
G01X1410413Y728944D02*
Y728954D01*
G01X1410414Y728939D02*
X1410413Y728944D01*
G01X1410415Y728937D02*
X1410414Y728939D01*
G01X1410413Y733944D02*
Y733954D01*
G01X1410414Y733939D02*
X1410413Y733944D01*
G01X1410415Y733937D02*
X1410414Y733939D01*
G01X1410413Y738944D02*
Y738954D01*
G01X1410414Y738939D02*
X1410413Y738944D01*
G01X1410415Y738937D02*
X1410414Y738939D01*
G01X1410413Y743944D02*
Y743954D01*
G01X1410414Y743939D02*
X1410413Y743944D01*
G01X1410415Y743937D02*
X1410414Y743939D01*
G01X1411390Y699081D02*
X1411398Y699055D01*
G01X1411380Y699107D02*
X1411390Y699081D01*
G01X1411369Y699134D02*
X1411380Y699107D01*
G01X1411390Y704081D02*
X1411398Y704055D01*
G01X1411380Y704107D02*
X1411390Y704081D01*
G01X1411369Y704134D02*
X1411380Y704107D01*
G01X1411390Y709081D02*
X1411398Y709055D01*
G01X1411380Y709107D02*
X1411390Y709081D01*
G01X1411369Y709134D02*
X1411380Y709107D01*
G01X1411390Y714081D02*
X1411398Y714055D01*
G01X1411380Y714107D02*
X1411390Y714081D01*
G01X1411369Y714134D02*
X1411380Y714107D01*
G01X1411390Y719081D02*
X1411398Y719055D01*
G01X1411380Y719107D02*
X1411390Y719081D01*
G01X1411369Y719134D02*
X1411380Y719107D01*
G01X1411390Y724081D02*
X1411398Y724055D01*
G01X1411380Y724107D02*
X1411390Y724081D01*
G01X1411369Y724134D02*
X1411380Y724107D01*
G01X1411390Y729081D02*
X1411398Y729055D01*
G01X1411380Y729107D02*
X1411390Y729081D01*
G01X1411369Y729134D02*
X1411380Y729107D01*
G01X1411390Y734081D02*
X1411398Y734055D01*
G01X1411380Y734107D02*
X1411390Y734081D01*
G01X1411369Y734134D02*
X1411380Y734107D01*
G01X1411390Y739081D02*
X1411398Y739055D01*
G01X1411380Y739107D02*
X1411390Y739081D01*
G01X1411369Y739134D02*
X1411380Y739107D01*
G01X1411390Y744081D02*
X1411398Y744055D01*
G01X1411380Y744107D02*
X1411390Y744081D01*
G01X1411369Y744134D02*
X1411380Y744107D01*
G01Y698932D02*
X1411361Y698937D01*
G01X1411395Y698918D02*
X1411380Y698932D01*
G01X1411400Y698898D02*
X1411395Y698918D01*
G01X1411380Y703932D02*
X1411361Y703937D01*
G01X1411395Y703918D02*
X1411380Y703932D01*
G01X1411400Y703898D02*
X1411395Y703918D01*
G01X1411380Y708932D02*
X1411361Y708937D01*
G01X1411395Y708918D02*
X1411380Y708932D01*
G01X1411400Y708898D02*
X1411395Y708918D01*
G01X1411380Y713932D02*
X1411361Y713937D01*
G01X1411395Y713918D02*
X1411380Y713932D01*
G01X1411400Y713898D02*
X1411395Y713918D01*
G01X1411380Y718932D02*
X1411361Y718937D01*
G01X1411395Y718918D02*
X1411380Y718932D01*
G01X1411400Y718898D02*
X1411395Y718918D01*
G01X1411380Y723932D02*
X1411361Y723937D01*
G01X1411395Y723918D02*
X1411380Y723932D01*
G01X1411400Y723898D02*
X1411395Y723918D01*
G01X1411380Y728932D02*
X1411361Y728937D01*
G01X1411395Y728918D02*
X1411380Y728932D01*
G01X1411400Y728898D02*
X1411395Y728918D01*
G01X1411380Y733932D02*
X1411361Y733937D01*
G01X1411395Y733918D02*
X1411380Y733932D01*
G01X1411400Y733898D02*
X1411395Y733918D01*
G01X1411380Y738932D02*
X1411361Y738937D01*
G01X1411395Y738918D02*
X1411380Y738932D01*
G01X1411400Y738898D02*
X1411395Y738918D01*
G01X1411380Y743932D02*
X1411361Y743937D01*
G01X1411395Y743918D02*
X1411380Y743932D01*
G01X1411400Y743898D02*
X1411395Y743918D01*
G01X1411398Y698911D02*
Y698920D01*
G01Y703911D02*
Y703920D01*
G01Y708911D02*
Y708920D01*
G01Y713911D02*
Y713920D01*
G01Y718911D02*
Y718920D01*
G01Y723911D02*
Y723920D01*
G01Y728911D02*
Y728920D01*
G01Y733911D02*
Y733920D01*
G01Y738911D02*
Y738920D01*
G01Y743911D02*
Y743920D01*
G01X1415748Y742559D02*
Y743937D01*
G01Y737559D02*
Y738937D01*
G01Y732559D02*
Y733937D01*
G01Y727559D02*
Y728937D01*
G01Y722559D02*
Y723937D01*
G01Y717559D02*
Y718937D01*
G01Y712559D02*
Y713937D01*
G01Y707559D02*
Y708937D01*
G01Y702559D02*
Y703937D01*
G01Y697559D02*
Y698937D01*
G01X1412579D02*
Y697559D01*
G01Y703937D02*
Y702559D01*
G01Y708937D02*
Y707559D01*
G01Y713937D02*
Y712559D01*
G01Y718937D02*
Y717559D01*
G01Y723937D02*
Y722559D01*
G01Y728937D02*
Y727559D01*
G01Y733937D02*
Y732559D01*
G01Y738937D02*
Y737559D01*
G01Y743937D02*
Y742559D01*
G01X1411398Y742067D02*
Y744429D01*
G01Y737067D02*
Y739429D01*
G01Y732067D02*
Y734429D01*
G01Y727067D02*
Y729429D01*
G01Y722067D02*
Y724429D01*
G01Y717067D02*
Y719429D01*
G01Y712067D02*
Y714429D01*
G01Y707067D02*
Y709429D01*
G01Y702067D02*
Y704429D01*
G01Y697067D02*
Y699429D01*
G01X1410413D02*
Y697067D01*
G01Y704429D02*
Y702067D01*
G01Y709429D02*
Y707067D01*
G01Y714429D02*
Y712067D01*
G01Y719429D02*
Y717067D01*
G01Y724429D02*
Y722067D01*
G01Y729429D02*
Y727067D01*
G01Y734429D02*
Y732067D01*
G01Y739429D02*
Y737067D01*
G01Y744429D02*
Y742067D01*
G01X1411398Y744429D02*
X1410413D01*
G01X1410415Y743937D02*
X1415748D01*
G01Y743898D02*
X1411400D01*
G01X1415748Y742559D02*
X1410415D01*
G01X1410413Y742067D02*
X1411398D01*
G01Y739429D02*
X1410413D01*
G01X1410415Y738937D02*
X1415748D01*
G01Y738898D02*
X1411400D01*
G01X1415748Y737559D02*
X1410415D01*
G01X1410413Y737067D02*
X1411398D01*
G01Y734429D02*
X1410413D01*
G01X1410415Y733937D02*
X1415748D01*
G01Y733898D02*
X1411400D01*
G01X1415748Y732559D02*
X1410415D01*
G01X1410413Y732067D02*
X1411398D01*
G01Y729429D02*
X1410413D01*
G01X1410415Y728937D02*
X1415748D01*
G01Y728898D02*
X1411400D01*
G01X1415748Y727559D02*
X1410415D01*
G01X1410413Y727067D02*
X1411398D01*
G01Y724429D02*
X1410413D01*
G01X1410415Y723937D02*
X1415748D01*
G01Y723898D02*
X1411400D01*
G01X1415748Y722559D02*
X1410415D01*
G01X1410413Y722067D02*
X1411398D01*
G01Y719429D02*
X1410413D01*
G01X1410415Y718937D02*
X1415748D01*
G01Y718898D02*
X1411400D01*
G01X1415748Y717559D02*
X1410415D01*
G01X1410413Y717067D02*
X1411398D01*
G01Y714429D02*
X1410413D01*
G01X1410415Y713937D02*
X1415748D01*
G01Y713898D02*
X1411400D01*
G01X1415748Y712559D02*
X1410415D01*
G01X1410413Y712067D02*
X1411398D01*
G01Y709429D02*
X1410413D01*
G01X1410415Y708937D02*
X1415748D01*
G01Y708898D02*
X1411400D01*
G01X1415748Y707559D02*
X1410415D01*
G01X1410413Y707067D02*
X1411398D01*
G01X1410413Y744133D02*
X1411369Y744134D01*
G01X1411398Y742363D02*
X1410413Y742362D01*
G01Y739133D02*
X1411369Y739134D01*
G01X1411398Y737363D02*
X1410413Y737362D01*
G01Y734133D02*
X1411369Y734134D01*
G01X1411398Y732363D02*
X1410413Y732362D01*
G01Y729133D02*
X1411369Y729134D01*
G01X1411398Y727363D02*
X1410413Y727362D01*
G01Y724133D02*
X1411369Y724134D01*
G01X1411398Y722363D02*
X1410413Y722362D01*
G01Y719133D02*
X1411369Y719134D01*
G01X1411398Y717363D02*
X1410413Y717362D01*
G01Y714133D02*
X1411369Y714134D01*
G01X1411398Y712363D02*
X1410413Y712362D01*
G01Y709133D02*
X1411369Y709134D01*
G01X1411398Y707363D02*
X1410413Y707362D01*
G01X1411398Y704429D02*
X1410413D01*
G01X1410415Y703937D02*
X1415748D01*
G01Y703898D02*
X1411400D01*
G01X1415748Y702559D02*
X1410415D01*
G01X1410413Y702067D02*
X1411398D01*
G01Y699429D02*
X1410413D01*
G01X1410415Y698937D02*
X1415748D01*
G01Y698898D02*
X1411400D01*
G01X1415748Y697559D02*
X1410415D01*
G01X1410413Y697067D02*
X1411398D01*
G01X1410413Y704133D02*
X1411369Y704134D01*
G01X1411398Y702363D02*
X1410413Y702362D01*
G01Y699133D02*
X1411369Y699134D01*
G01X1411398Y697363D02*
X1410413Y697362D01*
G01X1409843Y769429D02*
G03X1409252Y770020I-591J0D01*
G01X1402559D02*
G03X1401969Y769429I0J-590D01*
G01X1404724Y768248D02*
G03Y766280I0J-984D01*
G01X1407087D02*
G03Y768248I0J984D01*
G01X1416732Y768839D02*
G03X1414764Y770807I-1968J0D01*
G01X1397047D02*
G03X1395079Y768839I0J-1968D01*
G01X1403346Y760335D02*
G03X1402165Y759154I0J-1181D01*
G01X1409646D02*
G03X1408465Y760335I-1181J0D01*
G01X1407795Y755059D02*
G03I-1889J0D01*
G01X1408268D02*
G03I-2362J0D01*
G01X1403421Y751988D02*
X1404724Y753957D01*
G01X1409397Y759879D02*
X1407087Y755650D01*
G01X1416732Y753091D02*
Y768839D01*
G01X1409843Y763327D02*
Y769429D01*
G01X1409646Y759154D02*
Y750610D01*
G01X1407087Y755650D02*
Y753957D01*
G01X1404724D02*
Y755650D01*
G01X1402165Y750610D02*
Y759154D01*
G01X1401969Y763327D02*
Y769429D01*
G01X1395079Y768839D02*
Y753091D01*
G01X1404724Y755650D02*
X1402414Y759879D01*
G01X1407087Y753957D02*
X1408390Y751988D01*
G01X1400197Y748248D02*
X1401378Y747067D01*
G01X1395079Y753091D02*
X1398425Y749744D01*
G01X1416732Y753091D02*
X1413386Y749744D01*
G01X1406890Y747067D02*
X1408071Y748248D01*
G01X1414764Y770807D02*
X1397047D01*
G01X1409252Y770020D02*
X1402559D01*
G01X1407087Y768248D02*
X1404724D01*
G01Y766280D02*
X1407087D01*
G01X1409843Y764902D02*
X1401969D01*
G01Y763327D02*
X1409843D01*
G01X1416732Y760374D02*
X1395079D01*
G01X1403346Y760335D02*
X1408465D01*
G01X1404724Y755650D02*
X1407087D01*
G01X1404724Y753957D02*
X1407087D01*
G01X1398425Y751988D02*
X1412795D01*
G01X1398425Y750610D02*
X1402165D01*
G01X1412795D02*
X1409646D01*
G01X1398425Y749744D02*
X1413386D01*
G01X1400197Y748248D02*
X1408071D01*
G01X1401378Y747067D02*
X1406890D01*
G01X1411398Y1080308D02*
Y1080299D01*
G01X1411399Y1080313D02*
X1411398Y1080308D01*
G01X1411400Y1080315D02*
X1411399Y1080313D01*
G01X1411398Y1075308D02*
Y1075299D01*
G01X1411399Y1075313D02*
X1411398Y1075308D01*
G01X1411400Y1075315D02*
X1411399Y1075313D01*
G01X1411398Y1070308D02*
Y1070299D01*
G01X1411399Y1070313D02*
X1411398Y1070308D01*
G01X1411400Y1070315D02*
X1411399Y1070313D01*
G01X1410414Y1080313D02*
X1410415Y1080315D01*
G01X1410413Y1080308D02*
X1410414Y1080313D01*
G01X1410413Y1080299D02*
Y1080308D01*
G01X1410414Y1075313D02*
X1410415Y1075315D01*
G01X1410413Y1075308D02*
X1410414Y1075313D01*
G01X1410413Y1075299D02*
Y1075308D01*
G01X1410414Y1070313D02*
X1410415Y1070315D01*
G01X1410413Y1070308D02*
X1410414Y1070313D01*
G01X1410413Y1070299D02*
Y1070308D01*
G01X1411385Y1071685D02*
X1411396Y1071669D01*
G01X1411361Y1071693D02*
X1411385Y1071685D01*
G01Y1076685D02*
X1411396Y1076669D01*
G01X1411361Y1076693D02*
X1411385Y1076685D01*
G01Y1081685D02*
X1411396Y1081669D01*
G01X1411361Y1081693D02*
X1411385Y1081685D01*
G01X1411365Y1071791D02*
X1411369Y1071890D01*
G01X1411359Y1071719D02*
X1411365Y1071791D01*
G01X1411361Y1071693D02*
X1411359Y1071719D01*
G01X1411365Y1076791D02*
X1411369Y1076890D01*
G01X1411359Y1076719D02*
X1411365Y1076791D01*
G01X1411361Y1076693D02*
X1411359Y1076719D01*
G01X1411365Y1081791D02*
X1411369Y1081890D01*
G01X1411359Y1081719D02*
X1411365Y1081791D01*
G01X1411361Y1081693D02*
X1411359Y1081719D01*
G01X1411398Y1071660D02*
Y1071667D01*
G01X1411399Y1071656D02*
X1411398Y1071660D01*
G01X1411400Y1071654D02*
X1411399Y1071656D01*
G01X1411398Y1076660D02*
Y1076667D01*
G01X1411399Y1076656D02*
X1411398Y1076660D01*
G01X1411400Y1076654D02*
X1411399Y1076656D01*
G01X1411398Y1081660D02*
Y1081667D01*
G01X1411399Y1081656D02*
X1411398Y1081660D01*
G01X1411400Y1081654D02*
X1411399Y1081656D01*
G01X1410413Y1071700D02*
Y1071709D01*
G01X1410414Y1071695D02*
X1410413Y1071700D01*
G01X1410415Y1071693D02*
X1410414Y1071695D01*
G01X1410413Y1076700D02*
Y1076709D01*
G01X1410414Y1076695D02*
X1410413Y1076700D01*
G01X1410415Y1076693D02*
X1410414Y1076695D01*
G01X1410413Y1081700D02*
Y1081709D01*
G01X1410414Y1081695D02*
X1410413Y1081700D01*
G01X1410415Y1081693D02*
X1410414Y1081695D01*
G01X1411390Y1071837D02*
X1411398Y1071811D01*
G01X1411380Y1071863D02*
X1411390Y1071837D01*
G01X1411369Y1071890D02*
X1411380Y1071863D01*
G01X1411390Y1076837D02*
X1411398Y1076811D01*
G01X1411380Y1076863D02*
X1411390Y1076837D01*
G01X1411369Y1076890D02*
X1411380Y1076863D01*
G01X1411390Y1081837D02*
X1411398Y1081811D01*
G01X1411380Y1081863D02*
X1411390Y1081837D01*
G01X1411369Y1081890D02*
X1411380Y1081863D01*
G01Y1071688D02*
X1411361Y1071693D01*
G01X1411395Y1071674D02*
X1411380Y1071688D01*
G01X1411400Y1071654D02*
X1411395Y1071674D01*
G01X1411380Y1076688D02*
X1411361Y1076693D01*
G01X1411395Y1076674D02*
X1411380Y1076688D01*
G01X1411400Y1076654D02*
X1411395Y1076674D01*
G01X1411380Y1081688D02*
X1411361Y1081693D01*
G01X1411395Y1081674D02*
X1411380Y1081688D01*
G01X1411400Y1081654D02*
X1411395Y1081674D01*
G01X1401969Y1044823D02*
G03X1402559Y1044232I591J0D01*
G01X1409252D02*
G03X1409843Y1044823I0J591D01*
G01X1407087Y1046004D02*
G03Y1047972I0J984D01*
G01X1404724D02*
G03Y1046004I0J-984D01*
G01X1407008Y1059193D02*
G03I-1102J0D01*
G01X1408465Y1053917D02*
G03X1409646Y1055098I0J1181D01*
G01X1402165D02*
G03X1403346Y1053917I1181J0D01*
G01X1407480Y1059193D02*
G03I-1574J0D01*
G01X1395079Y1045413D02*
G03X1397047Y1043445I1968J0D01*
G01X1414764D02*
G03X1416732Y1045413I0J1968D01*
G01X1407087Y1058602D02*
X1409397Y1054373D01*
G01X1404724Y1060295D02*
X1403421Y1062264D01*
G01X1413386Y1064508D02*
X1416732Y1061161D01*
G01X1406890Y1067185D02*
X1408071Y1066004D01*
G01X1411398Y1071667D02*
Y1071676D01*
G01Y1076667D02*
Y1076676D01*
G01Y1081667D02*
Y1081676D01*
G01X1416732Y1045413D02*
Y1061161D01*
G01X1415748Y1080315D02*
Y1081693D01*
G01Y1075315D02*
Y1076693D01*
G01Y1070315D02*
Y1071693D01*
G01X1413386Y1202500D02*
Y1064508D01*
G01X1412795Y1204744D02*
Y1062264D01*
G01X1412579Y1071693D02*
Y1070315D01*
G01Y1076693D02*
Y1075315D01*
G01Y1081693D02*
Y1080315D01*
G01X1411398Y1079823D02*
Y1082185D01*
G01Y1074823D02*
Y1077185D01*
G01Y1069823D02*
Y1072185D01*
G01Y1071667D02*
Y1071811D01*
G01Y1076667D02*
Y1076811D01*
G01Y1081667D02*
Y1081811D01*
G01X1410413Y1072185D02*
Y1069823D01*
G01Y1077185D02*
Y1074823D01*
G01Y1082185D02*
Y1079823D01*
G01X1409843Y1050925D02*
Y1044823D01*
G01X1409646Y1063642D02*
Y1055098D01*
G01X1408071Y1102461D02*
Y1066004D01*
G01X1407087Y1060295D02*
Y1058602D01*
G01X1406890Y1103642D02*
Y1067185D01*
G01X1404724Y1058602D02*
Y1060295D01*
G01X1402165Y1055098D02*
Y1063642D01*
G01X1401969Y1050925D02*
Y1044823D01*
G01X1401378Y1067185D02*
Y1199823D01*
G01X1400197Y1066004D02*
Y1201004D01*
G01X1398425Y1101299D02*
Y1062264D01*
G01X1395079Y1061161D02*
Y1045413D01*
G01X1411398Y1082185D02*
X1410413D01*
G01X1410415Y1081693D02*
X1415748D01*
G01Y1081654D02*
X1411400D01*
G01X1415748Y1080315D02*
X1410415D01*
G01X1410413Y1079823D02*
X1411398D01*
G01Y1077185D02*
X1410413D01*
G01X1410415Y1076693D02*
X1415748D01*
G01Y1076654D02*
X1411400D01*
G01X1415748Y1075315D02*
X1410415D01*
G01X1410413Y1074823D02*
X1411398D01*
G01Y1072185D02*
X1410413D01*
G01X1410415Y1071693D02*
X1415748D01*
G01Y1071654D02*
X1411400D01*
G01X1415748Y1070315D02*
X1410415D01*
G01X1410413Y1069823D02*
X1411398D01*
G01X1406890Y1067185D02*
X1401378D01*
G01X1408071Y1066004D02*
X1400197D01*
G01X1413386Y1064508D02*
X1398425D01*
G01X1410413Y1081889D02*
X1411369Y1081890D01*
G01X1411398Y1080119D02*
X1410413Y1080118D01*
G01Y1076889D02*
X1411369Y1076890D01*
G01X1411398Y1075119D02*
X1410413Y1075118D01*
G01Y1071889D02*
X1411369Y1071890D01*
G01X1411398Y1070119D02*
X1410413Y1070118D01*
G01X1409646Y1063642D02*
X1412795D01*
G01X1402165D02*
X1398425D01*
G01Y1062264D02*
X1412795D01*
G01X1407087Y1060295D02*
X1404724D01*
G01X1407087Y1058602D02*
X1404724D01*
G01X1408465Y1053917D02*
X1403346D01*
G01X1416732Y1053878D02*
X1395079D01*
G01X1409843Y1050925D02*
X1401969D01*
G01Y1049350D02*
X1409843D01*
G01X1407087Y1047972D02*
X1404724D01*
G01Y1046004D02*
X1407087D01*
G01X1409252Y1044232D02*
X1402559D01*
G01X1414764Y1043445D02*
X1397047D01*
G01X1408390Y1062264D02*
X1407087Y1060295D01*
G01X1402414Y1054373D02*
X1404724Y1058602D01*
G01X1401378Y1067185D02*
X1400197Y1066004D01*
G01X1398425Y1064508D02*
X1395079Y1061161D01*
G01X1397944Y1122364D02*
X1397931Y1122362D01*
G01X1397954Y1122369D02*
X1397944Y1122364D01*
G01Y1119215D02*
X1397931Y1119213D01*
G01X1397954Y1119220D02*
X1397944Y1119215D01*
G01Y1116065D02*
X1397931Y1116063D01*
G01X1397954Y1116070D02*
X1397944Y1116065D01*
G01Y1112915D02*
X1397931Y1112913D01*
G01X1397954Y1112920D02*
X1397944Y1112915D01*
G01Y1109766D02*
X1397931Y1109764D01*
G01X1397954Y1109771D02*
X1397944Y1109766D01*
G01Y1106616D02*
X1397931Y1106614D01*
G01X1397954Y1106621D02*
X1397944Y1106616D01*
G01Y1103467D02*
X1397931Y1103465D01*
G01X1397954Y1103472D02*
X1397944Y1103467D01*
G01X1397970Y1122376D02*
X1397972Y1122388D01*
G01X1397963Y1122365D02*
X1397970Y1122376D01*
G01X1397953Y1122356D02*
X1397963Y1122365D01*
G01X1397970Y1116076D02*
X1397972Y1116089D01*
G01X1397963Y1116065D02*
X1397970Y1116076D01*
G01X1397953Y1116057D02*
X1397963Y1116065D01*
G01X1397027Y1123548D02*
Y1123555D01*
G01Y1123544D02*
Y1123548D01*
G01X1397025Y1123543D02*
X1397027Y1123544D01*
G01Y1120399D02*
Y1120405D01*
G01Y1120395D02*
Y1120399D01*
G01X1397025Y1120394D02*
X1397027Y1120395D01*
G01Y1117249D02*
Y1117256D01*
G01Y1117245D02*
Y1117249D01*
G01X1397025Y1117244D02*
X1397027Y1117245D01*
G01Y1114100D02*
Y1114106D01*
G01Y1114096D02*
Y1114100D01*
G01X1397025Y1114094D02*
X1397027Y1114096D01*
G01Y1110950D02*
Y1110956D01*
G01Y1110946D02*
Y1110950D01*
G01X1397025Y1110945D02*
X1397027Y1110946D01*
G01Y1107800D02*
Y1107807D01*
G01Y1107796D02*
Y1107800D01*
G01X1397025Y1107795D02*
X1397027Y1107796D01*
G01Y1104651D02*
Y1104657D01*
G01Y1104647D02*
Y1104651D01*
G01X1397025Y1104646D02*
X1397027Y1104647D01*
G01X1396989Y1123524D02*
X1396988Y1123518D01*
G01X1396991Y1123530D02*
X1396989Y1123524D01*
G01X1396993Y1123536D02*
X1396991Y1123530D01*
G01X1396997Y1123541D02*
X1396993Y1123536D01*
G01X1397002Y1123546D02*
X1396997Y1123541D01*
G01X1397007Y1123550D02*
X1397002Y1123546D01*
G01X1396989Y1120374D02*
X1396988Y1120368D01*
G01X1396991Y1120381D02*
X1396989Y1120374D01*
G01X1396993Y1120386D02*
X1396991Y1120381D01*
G01X1396997Y1120392D02*
X1396993Y1120386D01*
G01X1397002Y1120396D02*
X1396997Y1120392D01*
G01X1397007Y1120400D02*
X1397002Y1120396D01*
G01X1396989Y1117225D02*
X1396988Y1117219D01*
G01X1396991Y1117231D02*
X1396989Y1117225D01*
G01X1396993Y1117237D02*
X1396991Y1117231D01*
G01X1396997Y1117242D02*
X1396993Y1117237D01*
G01X1397002Y1117246D02*
X1396997Y1117242D01*
G01X1397007Y1117250D02*
X1397002Y1117246D01*
G01X1396989Y1114075D02*
X1396988Y1114069D01*
G01X1396991Y1114081D02*
X1396989Y1114075D01*
G01X1396993Y1114087D02*
X1396991Y1114081D01*
G01X1396997Y1114093D02*
X1396993Y1114087D01*
G01X1397002Y1114097D02*
X1396997Y1114093D01*
G01X1397007Y1114101D02*
X1397002Y1114097D01*
G01X1396989Y1110926D02*
X1396988Y1110919D01*
G01X1396991Y1110932D02*
X1396989Y1110926D01*
G01X1396993Y1110937D02*
X1396991Y1110932D01*
G01X1396997Y1110943D02*
X1396993Y1110937D01*
G01X1397002Y1110947D02*
X1396997Y1110943D01*
G01X1397007Y1110951D02*
X1397002Y1110947D01*
G01X1396989Y1107776D02*
X1396988Y1107770D01*
G01X1396991Y1107782D02*
X1396989Y1107776D01*
G01X1396993Y1107788D02*
X1396991Y1107782D01*
G01X1396997Y1107793D02*
X1396993Y1107788D01*
G01X1397002Y1107798D02*
X1396997Y1107793D01*
G01X1397007Y1107802D02*
X1397002Y1107798D01*
G01X1396989Y1104626D02*
X1396988Y1104620D01*
G01X1396991Y1104633D02*
X1396989Y1104626D01*
G01X1396993Y1104638D02*
X1396991Y1104633D01*
G01X1396997Y1104644D02*
X1396993Y1104638D01*
G01X1397002Y1104648D02*
X1396997Y1104644D01*
G01X1397007Y1104652D02*
X1397002Y1104648D01*
G01X1396988Y1123510D02*
Y1123518D01*
G01X1396987Y1123506D02*
X1396988Y1123510D01*
G01X1396986Y1123504D02*
X1396987Y1123506D01*
G01X1396988Y1120361D02*
Y1120368D01*
G01X1396987Y1120356D02*
X1396988Y1120361D01*
G01X1396986Y1120354D02*
X1396987Y1120356D01*
G01X1396988Y1117211D02*
Y1117219D01*
G01X1396987Y1117206D02*
X1396988Y1117211D01*
G01X1396986Y1117205D02*
X1396987Y1117206D01*
G01X1396988Y1114061D02*
Y1114069D01*
G01X1396987Y1114057D02*
X1396988Y1114061D01*
G01X1396986Y1114055D02*
X1396987Y1114057D01*
G01X1396988Y1110912D02*
Y1110919D01*
G01X1396987Y1110907D02*
X1396988Y1110912D01*
G01X1396986Y1110906D02*
X1396987Y1110907D01*
G01X1396988Y1107762D02*
Y1107770D01*
G01X1396987Y1107757D02*
X1396988Y1107762D01*
G01X1396986Y1107756D02*
X1396987Y1107757D01*
G01X1396988Y1104613D02*
Y1104620D01*
G01X1396987Y1104608D02*
X1396988Y1104613D01*
G01X1396986Y1104606D02*
X1396987Y1104608D01*
G01X1397970Y1112927D02*
X1397972Y1112939D01*
G01X1397963Y1112916D02*
X1397970Y1112927D01*
G01X1397953Y1112907D02*
X1397963Y1112916D01*
G01X1397970Y1109777D02*
X1397972Y1109790D01*
G01X1397963Y1109766D02*
X1397970Y1109777D01*
G01X1397953Y1109758D02*
X1397963Y1109766D01*
G01X1397970Y1106628D02*
X1397972Y1106640D01*
G01X1397963Y1106617D02*
X1397970Y1106628D01*
G01X1397953Y1106608D02*
X1397963Y1106617D01*
G01X1397970Y1103478D02*
X1397972Y1103491D01*
G01X1397963Y1103467D02*
X1397970Y1103478D01*
G01X1397953Y1103459D02*
X1397963Y1103467D01*
G01X1397933Y1123548D02*
Y1123555D01*
G01X1397932Y1123545D02*
X1397933Y1123548D01*
G01X1397931Y1123543D02*
X1397932Y1123545D01*
G01X1397933Y1120399D02*
Y1120405D01*
G01X1397932Y1120395D02*
X1397933Y1120399D01*
G01X1397931Y1120394D02*
X1397932Y1120395D01*
G01X1397933Y1117249D02*
Y1117256D01*
G01X1397932Y1117246D02*
X1397933Y1117249D01*
G01X1397931Y1117244D02*
X1397932Y1117246D01*
G01X1397933Y1114100D02*
Y1114106D01*
G01X1397932Y1114096D02*
X1397933Y1114100D01*
G01X1397931Y1114094D02*
X1397932Y1114096D01*
G01X1397933Y1110950D02*
Y1110956D01*
G01X1397932Y1110946D02*
X1397933Y1110950D01*
G01X1397931Y1110945D02*
X1397932Y1110946D01*
G01X1397933Y1107800D02*
Y1107807D01*
G01X1397932Y1107797D02*
X1397933Y1107800D01*
G01X1397931Y1107795D02*
X1397932Y1107797D01*
G01X1397933Y1104651D02*
Y1104657D01*
G01X1397932Y1104647D02*
X1397933Y1104651D01*
G01X1397931Y1104646D02*
X1397932Y1104647D01*
G01X1411398Y1130308D02*
Y1130299D01*
G01X1411399Y1130313D02*
X1411398Y1130308D01*
G01X1411400Y1130315D02*
X1411399Y1130313D01*
G01X1411398Y1125308D02*
Y1125299D01*
G01X1411399Y1125313D02*
X1411398Y1125308D01*
G01X1411400Y1125315D02*
X1411399Y1125313D01*
G01X1411398Y1100308D02*
Y1100299D01*
G01X1411399Y1100313D02*
X1411398Y1100308D01*
G01X1411400Y1100315D02*
X1411399Y1100313D01*
G01X1411398Y1095308D02*
Y1095299D01*
G01X1411399Y1095313D02*
X1411398Y1095308D01*
G01X1411400Y1095315D02*
X1411399Y1095313D01*
G01X1411398Y1090308D02*
Y1090299D01*
G01X1411399Y1090313D02*
X1411398Y1090308D01*
G01X1411400Y1090315D02*
X1411399Y1090313D01*
G01X1411398Y1085308D02*
Y1085299D01*
G01X1411399Y1085313D02*
X1411398Y1085308D01*
G01X1411400Y1085315D02*
X1411399Y1085313D01*
G01X1397972Y1123510D02*
Y1123517D01*
G01Y1123506D02*
Y1123510D01*
G01X1397971Y1123504D02*
X1397972Y1123506D01*
G01Y1120361D02*
Y1120368D01*
G01Y1120356D02*
Y1120361D01*
G01X1397971Y1120354D02*
X1397972Y1120356D01*
G01Y1117211D02*
Y1117218D01*
G01Y1117207D02*
Y1117211D01*
G01X1397971Y1117205D02*
X1397972Y1117207D01*
G01Y1114061D02*
Y1114069D01*
G01Y1114057D02*
Y1114061D01*
G01X1397971Y1114055D02*
X1397972Y1114057D01*
G01Y1110912D02*
Y1110919D01*
G01Y1110907D02*
Y1110912D01*
G01X1397971Y1110906D02*
X1397972Y1110907D01*
G01Y1107762D02*
Y1107769D01*
G01Y1107758D02*
Y1107762D01*
G01X1397971Y1107756D02*
X1397972Y1107758D01*
G01Y1104613D02*
Y1104620D01*
G01Y1104608D02*
Y1104613D01*
G01X1397971Y1104606D02*
X1397972Y1104608D01*
G01X1396988Y1112947D02*
Y1112939D01*
G01X1396987Y1112952D02*
X1396988Y1112947D01*
G01X1396986Y1112949D02*
X1396987Y1112952D01*
G01X1396988Y1106648D02*
Y1106640D01*
G01X1396987Y1106652D02*
X1396988Y1106648D01*
G01X1396986Y1106650D02*
X1396987Y1106652D01*
G01X1396991Y1104626D02*
X1396986Y1104606D01*
G01X1397006Y1104641D02*
X1396991Y1104626D01*
G01X1397025Y1104646D02*
X1397006Y1104641D01*
G01X1396991Y1107776D02*
X1396986Y1107756D01*
G01X1397006Y1107790D02*
X1396991Y1107776D01*
G01X1397025Y1107795D02*
X1397006Y1107790D01*
G01X1396991Y1110925D02*
X1396986Y1110906D01*
G01X1397006Y1110940D02*
X1396991Y1110925D01*
G01X1397025Y1110945D02*
X1397006Y1110940D01*
G01X1396991Y1114075D02*
X1396986Y1114055D01*
G01X1397006Y1114089D02*
X1396991Y1114075D01*
G01X1397025Y1114094D02*
X1397006Y1114089D01*
G01X1396991Y1117224D02*
X1396986Y1117205D01*
G01X1397006Y1117239D02*
X1396991Y1117224D01*
G01X1397025Y1117244D02*
X1397006Y1117239D01*
G01X1396991Y1120374D02*
X1396986Y1120354D01*
G01X1397006Y1120389D02*
X1396991Y1120374D01*
G01X1397025Y1120394D02*
X1397006Y1120389D01*
G01X1396991Y1123524D02*
X1396986Y1123504D01*
G01X1397006Y1123538D02*
X1396991Y1123524D01*
G01X1397025Y1123543D02*
X1397006Y1123538D01*
G01X1397966Y1103484D02*
X1397971Y1103504D01*
G01X1397951Y1103470D02*
X1397966Y1103484D01*
G01X1397931Y1103465D02*
X1397951Y1103470D01*
G01X1397966Y1106634D02*
X1397971Y1106654D01*
G01X1397951Y1106620D02*
X1397966Y1106634D01*
G01X1397931Y1106614D02*
X1397951Y1106620D01*
G01X1397966Y1109783D02*
X1397971Y1109803D01*
G01X1397951Y1109769D02*
X1397966Y1109783D01*
G01X1397931Y1109764D02*
X1397951Y1109769D01*
G01X1397966Y1112933D02*
X1397971Y1112953D01*
G01X1397951Y1112919D02*
X1397966Y1112933D01*
G01X1397931Y1112913D02*
X1397951Y1112919D01*
G01X1397966Y1116083D02*
X1397971Y1116102D01*
G01X1397951Y1116069D02*
X1397966Y1116083D01*
G01X1397931Y1116063D02*
X1397951Y1116069D01*
G01X1397966Y1119232D02*
X1397971Y1119252D01*
G01X1397951Y1119218D02*
X1397966Y1119232D01*
G01X1397931Y1119213D02*
X1397951Y1119218D01*
G01X1397966Y1122382D02*
X1397971Y1122402D01*
G01X1397951Y1122368D02*
X1397966Y1122382D01*
G01X1397931Y1122362D02*
X1397951Y1122368D01*
G01X1397001Y1123535D02*
X1397025Y1123543D01*
G01X1396990Y1123520D02*
X1397001Y1123535D01*
G01X1396988Y1123514D02*
X1396990Y1123520D01*
G01X1397001Y1120385D02*
X1397025Y1120394D01*
G01X1396990Y1120371D02*
X1397001Y1120385D01*
G01X1396988Y1120364D02*
X1396990Y1120371D01*
G01X1397001Y1117236D02*
X1397025Y1117244D01*
G01X1396990Y1117221D02*
X1397001Y1117236D01*
G01X1396988Y1117215D02*
X1396990Y1117221D01*
G01X1397001Y1114086D02*
X1397025Y1114094D01*
G01X1396990Y1114072D02*
X1397001Y1114086D01*
G01X1396988Y1114065D02*
X1396990Y1114072D01*
G01X1397001Y1110937D02*
X1397025Y1110945D01*
G01X1396990Y1110922D02*
X1397001Y1110937D01*
G01X1396988Y1110915D02*
X1396990Y1110922D01*
G01X1397001Y1107787D02*
X1397025Y1107795D01*
G01X1396990Y1107772D02*
X1397001Y1107787D01*
G01X1396988Y1107766D02*
X1396990Y1107772D01*
G01X1397001Y1104637D02*
X1397025Y1104646D01*
G01X1396990Y1104623D02*
X1397001Y1104637D01*
G01X1396988Y1104616D02*
X1396990Y1104623D01*
G01X1397972Y1119231D02*
Y1119239D01*
G01X1397969Y1119224D02*
X1397972Y1119231D01*
G01X1397966Y1119218D02*
X1397969Y1119224D01*
G01X1397961Y1119212D02*
X1397966Y1119218D01*
G01X1397955Y1119207D02*
X1397961Y1119212D01*
G01X1397948Y1119204D02*
X1397955Y1119207D01*
G01X1397941Y1119202D02*
X1397948Y1119204D01*
G01X1397933Y1119202D02*
X1397941D01*
G01X1397950Y1103457D02*
X1397953Y1103459D01*
G01X1397947Y1103456D02*
X1397950Y1103457D01*
G01X1397944Y1103455D02*
X1397947Y1103456D01*
G01X1397940Y1103454D02*
X1397944Y1103455D01*
G01X1397937Y1103454D02*
X1397940D01*
G01X1397933D02*
X1397937D01*
G01X1397011Y1104654D02*
X1397007Y1104652D01*
G01X1397014Y1104655D02*
X1397011Y1104654D01*
G01X1397017Y1104656D02*
X1397014Y1104655D01*
G01X1397020Y1104656D02*
X1397017D01*
G01X1397024Y1104657D02*
X1397020Y1104656D01*
G01X1397028Y1104657D02*
X1397024D01*
G01X1397950Y1106607D02*
X1397953Y1106608D01*
G01X1397947Y1106606D02*
X1397950Y1106607D01*
G01X1397944Y1106604D02*
X1397947Y1106606D01*
G01X1397940Y1106604D02*
X1397944D01*
G01X1397937Y1106603D02*
X1397940Y1106604D01*
G01X1397933Y1106603D02*
X1397937D01*
G01X1397011Y1107803D02*
X1397007Y1107802D01*
G01X1397014Y1107804D02*
X1397011Y1107803D01*
G01X1397017Y1107806D02*
X1397014Y1107804D01*
G01X1397020Y1107806D02*
X1397017D01*
G01X1397024Y1107807D02*
X1397020Y1107806D01*
G01X1397028Y1107807D02*
X1397024D01*
G01X1397950Y1109756D02*
X1397953Y1109758D01*
G01X1397947Y1109755D02*
X1397950Y1109756D01*
G01X1397944Y1109754D02*
X1397947Y1109755D01*
G01X1397940Y1109753D02*
X1397944Y1109754D01*
G01X1397937Y1109753D02*
X1397940D01*
G01X1397933D02*
X1397937D01*
G01X1397011Y1110953D02*
X1397007Y1110951D01*
G01X1397014Y1110954D02*
X1397011Y1110953D01*
G01X1397017Y1110955D02*
X1397014Y1110954D01*
G01X1397020Y1110956D02*
X1397017Y1110955D01*
G01X1397024Y1110956D02*
X1397020D01*
G01X1397028D02*
X1397024D01*
G01X1397950Y1112906D02*
X1397953Y1112907D01*
G01X1397947Y1112905D02*
X1397950Y1112906D01*
G01X1397944Y1112904D02*
X1397947Y1112905D01*
G01X1397940Y1112903D02*
X1397944Y1112904D01*
G01X1397937Y1112902D02*
X1397940Y1112903D01*
G01X1397933Y1112902D02*
X1397937D01*
G01X1397011Y1114102D02*
X1397007Y1114101D01*
G01X1397014Y1114104D02*
X1397011Y1114102D01*
G01X1397017Y1114105D02*
X1397014Y1114104D01*
G01X1397020Y1114105D02*
X1397017D01*
G01X1397024Y1114106D02*
X1397020Y1114105D01*
G01X1397028Y1114106D02*
X1397024D01*
G01X1397950Y1116056D02*
X1397953Y1116057D01*
G01X1397947Y1116054D02*
X1397950Y1116056D01*
G01X1397944Y1116053D02*
X1397947Y1116054D01*
G01X1397940Y1116052D02*
X1397944Y1116053D01*
G01X1397937Y1116052D02*
X1397940D01*
G01X1397933D02*
X1397937D01*
G01X1397011Y1117252D02*
X1397007Y1117250D01*
G01X1397014Y1117253D02*
X1397011Y1117252D01*
G01X1397017Y1117254D02*
X1397014Y1117253D01*
G01X1397020Y1117255D02*
X1397017Y1117254D01*
G01X1397024Y1117256D02*
X1397020Y1117255D01*
G01X1397028Y1117256D02*
X1397024D01*
G01X1397011Y1120402D02*
X1397007Y1120400D01*
G01X1397014Y1120403D02*
X1397011Y1120402D01*
G01X1397017Y1120404D02*
X1397014Y1120403D01*
G01X1397020Y1120404D02*
X1397017D01*
G01X1397024Y1120405D02*
X1397020Y1120404D01*
G01X1397028Y1120405D02*
X1397024D01*
G01X1397950Y1122355D02*
X1397953Y1122356D01*
G01X1397947Y1122354D02*
X1397950Y1122355D01*
G01X1397944Y1122352D02*
X1397947Y1122354D01*
G01X1397940Y1122352D02*
X1397944D01*
G01X1397937Y1122351D02*
X1397940Y1122352D01*
G01X1397933Y1122351D02*
X1397937D01*
G01X1397011Y1123551D02*
X1397007Y1123550D01*
G01X1397014Y1123552D02*
X1397011Y1123551D01*
G01X1397017Y1123554D02*
X1397014Y1123552D01*
G01X1397020Y1123554D02*
X1397017D01*
G01X1397024Y1123555D02*
X1397020Y1123554D01*
G01X1397028Y1123555D02*
X1397024D01*
G01X1397963Y1104644D02*
X1397967Y1104639D01*
G01X1397958Y1104648D02*
X1397963Y1104644D01*
G01X1397952Y1104652D02*
X1397958Y1104648D01*
G01X1397946Y1104655D02*
X1397952Y1104652D01*
G01X1397940Y1104657D02*
X1397946Y1104655D01*
G01X1397933Y1104657D02*
X1397940D01*
G01X1397963Y1107794D02*
X1397967Y1107789D01*
G01X1397958Y1107798D02*
X1397963Y1107794D01*
G01X1397952Y1107802D02*
X1397958Y1107798D01*
G01X1397946Y1107804D02*
X1397952Y1107802D01*
G01X1397940Y1107806D02*
X1397946Y1107804D01*
G01X1397933Y1107807D02*
X1397940Y1107806D01*
G01X1397963Y1110943D02*
X1397967Y1110938D01*
G01X1397958Y1110948D02*
X1397963Y1110943D01*
G01X1397952Y1110952D02*
X1397958Y1110948D01*
G01X1397946Y1110954D02*
X1397952Y1110952D01*
G01X1397940Y1110956D02*
X1397946Y1110954D01*
G01X1397933Y1110956D02*
X1397940D01*
G01X1397963Y1114093D02*
X1397967Y1114088D01*
G01X1397958Y1114097D02*
X1397963Y1114093D01*
G01X1397952Y1114101D02*
X1397958Y1114097D01*
G01X1397946Y1114104D02*
X1397952Y1114101D01*
G01X1397940Y1114106D02*
X1397946Y1114104D01*
G01X1397933Y1114106D02*
X1397940D01*
G01X1397963Y1117243D02*
X1397967Y1117237D01*
G01X1397958Y1117247D02*
X1397963Y1117243D01*
G01X1397952Y1117251D02*
X1397958Y1117247D01*
G01X1397946Y1117253D02*
X1397952Y1117251D01*
G01X1397940Y1117255D02*
X1397946Y1117253D01*
G01X1397933Y1117256D02*
X1397940Y1117255D01*
G01X1396989Y1103483D02*
X1396988Y1103491D01*
G01X1396991Y1103476D02*
X1396989Y1103483D01*
G01X1396995Y1103470D02*
X1396991Y1103476D01*
G01X1397000Y1103464D02*
X1396995Y1103470D01*
G01X1397006Y1103459D02*
X1397000Y1103464D01*
G01X1397013Y1103456D02*
X1397006Y1103459D01*
G01X1397020Y1103454D02*
X1397013Y1103456D01*
G01X1397028Y1103454D02*
X1397020D01*
G01X1396989Y1106633D02*
X1396988Y1106640D01*
G01X1396991Y1106626D02*
X1396989Y1106633D01*
G01X1396995Y1106620D02*
X1396991Y1106626D01*
G01X1397000Y1106614D02*
X1396995Y1106620D01*
G01X1397006Y1106609D02*
X1397000Y1106614D01*
G01X1397013Y1106606D02*
X1397006Y1106609D01*
G01X1397020Y1106604D02*
X1397013Y1106606D01*
G01X1397028Y1106603D02*
X1397020Y1106604D01*
G01X1396989Y1109782D02*
X1396988Y1109790D01*
G01X1396991Y1109776D02*
X1396989Y1109782D01*
G01X1396995Y1109769D02*
X1396991Y1109776D01*
G01X1397000Y1109763D02*
X1396995Y1109769D01*
G01X1397006Y1109759D02*
X1397000Y1109763D01*
G01X1397013Y1109756D02*
X1397006Y1109759D01*
G01X1397020Y1109754D02*
X1397013Y1109756D01*
G01X1397028Y1109753D02*
X1397020Y1109754D01*
G01X1396989Y1112932D02*
X1396988Y1112939D01*
G01X1396991Y1112925D02*
X1396989Y1112932D01*
G01X1396995Y1112919D02*
X1396991Y1112925D01*
G01X1397000Y1112913D02*
X1396995Y1112919D01*
G01X1397006Y1112908D02*
X1397000Y1112913D01*
G01X1397013Y1112905D02*
X1397006Y1112908D01*
G01X1397020Y1112903D02*
X1397013Y1112905D01*
G01X1397028Y1112902D02*
X1397020Y1112903D01*
G01X1396988Y1116096D02*
Y1116089D01*
G01X1396987Y1116101D02*
X1396988Y1116096D01*
G01X1396987Y1116092D02*
Y1116101D01*
G01X1397028Y1123728D02*
Y1123740D01*
G01X1397025Y1123715D02*
X1397028Y1123728D01*
G01X1397025Y1123701D02*
Y1123715D01*
G01X1397028Y1120578D02*
Y1120591D01*
G01X1397025Y1120565D02*
X1397028Y1120578D01*
G01X1397025Y1120552D02*
Y1120565D01*
G01X1397028Y1117429D02*
Y1117441D01*
G01X1397025Y1117416D02*
X1397028Y1117429D01*
G01X1397025Y1117402D02*
Y1117416D01*
G01X1397028Y1114279D02*
Y1114291D01*
G01X1397025Y1114266D02*
X1397028Y1114279D01*
G01X1397025Y1114252D02*
Y1114266D01*
G01X1397028Y1111130D02*
Y1111142D01*
G01X1397025Y1111117D02*
X1397028Y1111130D01*
G01X1397025Y1111103D02*
Y1111117D01*
G01X1397028Y1107980D02*
Y1107992D01*
G01X1397025Y1107967D02*
X1397028Y1107980D01*
G01X1397025Y1107953D02*
Y1107967D01*
G01X1397028Y1104830D02*
Y1104843D01*
G01X1397025Y1104817D02*
X1397028Y1104830D01*
G01X1397025Y1104804D02*
Y1104817D01*
G01X1410414Y1130313D02*
X1410415Y1130315D01*
G01X1410413Y1130308D02*
X1410414Y1130313D01*
G01X1410413Y1130299D02*
Y1130308D01*
G01X1410414Y1125313D02*
X1410415Y1125315D01*
G01X1410413Y1125308D02*
X1410414Y1125313D01*
G01X1410413Y1125299D02*
Y1125308D01*
G01X1410414Y1100313D02*
X1410415Y1100315D01*
G01X1410413Y1100308D02*
X1410414Y1100313D01*
G01X1410413Y1100299D02*
Y1100308D01*
G01X1410414Y1095313D02*
X1410415Y1095315D01*
G01X1410413Y1095308D02*
X1410414Y1095313D01*
G01X1410413Y1095299D02*
Y1095308D01*
G01X1410414Y1090313D02*
X1410415Y1090315D01*
G01X1410413Y1090308D02*
X1410414Y1090313D01*
G01X1410413Y1090299D02*
Y1090308D01*
G01X1410414Y1085313D02*
X1410415Y1085315D01*
G01X1410413Y1085308D02*
X1410414Y1085313D01*
G01X1410413Y1085299D02*
Y1085308D01*
G01X1396988Y1122396D02*
Y1122388D01*
G01X1396987Y1122400D02*
X1396988Y1122396D01*
G01X1396987Y1122393D02*
Y1122400D01*
G01X1397025Y1122191D02*
X1397024Y1122204D01*
G01X1397028Y1122178D02*
X1397025Y1122191D01*
G01X1397028Y1122165D02*
Y1122178D01*
G01X1397025Y1119041D02*
X1397024Y1119055D01*
G01X1397028Y1119028D02*
X1397025Y1119041D01*
G01X1397028Y1119016D02*
Y1119028D01*
G01X1397025Y1115892D02*
X1397024Y1115905D01*
G01X1397028Y1115879D02*
X1397025Y1115892D01*
G01X1397028Y1115866D02*
Y1115879D01*
G01X1397025Y1112742D02*
X1397024Y1112756D01*
G01X1397028Y1112729D02*
X1397025Y1112742D01*
G01X1397028Y1112717D02*
Y1112729D01*
G01X1397025Y1109593D02*
X1397024Y1109606D01*
G01X1397028Y1109580D02*
X1397025Y1109593D01*
G01X1397028Y1109567D02*
Y1109580D01*
G01X1397025Y1106443D02*
X1397024Y1106456D01*
G01X1397028Y1106430D02*
X1397025Y1106443D01*
G01X1397028Y1106417D02*
Y1106430D01*
G01X1397025Y1103293D02*
X1397024Y1103307D01*
G01X1397028Y1103280D02*
X1397025Y1103293D01*
G01X1397028Y1103268D02*
Y1103280D01*
G01X1397935Y1123715D02*
X1397937Y1123701D01*
G01X1397932Y1123728D02*
X1397935Y1123715D01*
G01X1397933Y1123740D02*
X1397932Y1123728D01*
G01X1397935Y1120565D02*
X1397937Y1120552D01*
G01X1397932Y1120578D02*
X1397935Y1120565D01*
G01X1397933Y1120591D02*
X1397932Y1120578D01*
G01X1397935Y1117415D02*
X1397937Y1117402D01*
G01X1397932Y1117428D02*
X1397935Y1117415D01*
G01X1397933Y1117441D02*
X1397932Y1117428D01*
G01X1397935Y1114266D02*
X1397937Y1114252D01*
G01X1397932Y1114279D02*
X1397935Y1114266D01*
G01X1397933Y1114291D02*
X1397932Y1114279D01*
G01X1397935Y1111116D02*
X1397937Y1111103D01*
G01X1397932Y1111129D02*
X1397935Y1111116D01*
G01X1397933Y1111142D02*
X1397932Y1111129D01*
G01X1397935Y1107967D02*
X1397937Y1107953D01*
G01X1397932Y1107980D02*
X1397935Y1107967D01*
G01X1397933Y1107992D02*
X1397932Y1107980D01*
G01X1397935Y1104817D02*
X1397937Y1104804D01*
G01X1397932Y1104830D02*
X1397935Y1104817D01*
G01X1397933Y1104843D02*
X1397932Y1104830D01*
G01X1396988Y1109797D02*
Y1109790D01*
G01X1396987Y1109802D02*
X1396988Y1109797D01*
G01X1396987Y1109795D02*
Y1109802D01*
G01X1396988Y1119246D02*
Y1119239D01*
G01X1396987Y1119251D02*
X1396988Y1119246D01*
G01X1396987Y1119244D02*
Y1119251D01*
G01X1397932Y1122178D02*
X1397933Y1122165D01*
G01X1397935Y1122191D02*
X1397932Y1122178D01*
G01X1397936Y1122204D02*
X1397935Y1122191D01*
G01X1397932Y1119028D02*
X1397933Y1119016D01*
G01X1397935Y1119041D02*
X1397932Y1119028D01*
G01X1397936Y1119055D02*
X1397935Y1119041D01*
G01X1397932Y1115879D02*
X1397933Y1115866D01*
G01X1397935Y1115892D02*
X1397932Y1115879D01*
G01X1397936Y1115905D02*
X1397935Y1115892D01*
G01X1397932Y1112729D02*
X1397933Y1112717D01*
G01X1397935Y1112742D02*
X1397932Y1112729D01*
G01X1397936Y1112756D02*
X1397935Y1112742D01*
G01X1397932Y1109580D02*
X1397933Y1109567D01*
G01X1397935Y1109593D02*
X1397932Y1109580D01*
G01X1397936Y1109606D02*
X1397935Y1109593D01*
G01X1397932Y1106430D02*
X1397933Y1106417D01*
G01X1397935Y1106443D02*
X1397932Y1106430D01*
G01X1397936Y1106456D02*
X1397935Y1106443D01*
G01X1397932Y1103280D02*
X1397933Y1103268D01*
G01X1397935Y1103293D02*
X1397932Y1103280D01*
G01X1397936Y1103307D02*
X1397935Y1103293D01*
G01X1396988Y1103498D02*
Y1103491D01*
G01X1396987Y1103503D02*
X1396988Y1103498D01*
G01X1396987Y1103496D02*
Y1103503D01*
G01X1397963Y1120392D02*
X1397967Y1120387D01*
G01X1397958Y1120396D02*
X1397963Y1120392D01*
G01X1397952Y1120400D02*
X1397958Y1120396D01*
G01X1397946Y1120403D02*
X1397952Y1120400D01*
G01X1397940Y1120405D02*
X1397946Y1120403D01*
G01X1397933Y1120405D02*
X1397940D01*
G01X1397963Y1123542D02*
X1397967Y1123537D01*
G01X1397958Y1123546D02*
X1397963Y1123542D01*
G01X1397952Y1123550D02*
X1397958Y1123546D01*
G01X1397946Y1123552D02*
X1397952Y1123550D01*
G01X1397940Y1123554D02*
X1397946Y1123552D01*
G01X1397933Y1123555D02*
X1397940Y1123554D01*
G01X1396989Y1116081D02*
X1396988Y1116089D01*
G01X1396991Y1116075D02*
X1396989Y1116081D01*
G01X1396995Y1116069D02*
X1396991Y1116075D01*
G01X1397000Y1116063D02*
X1396995Y1116069D01*
G01X1397006Y1116058D02*
X1397000Y1116063D01*
G01X1397013Y1116055D02*
X1397006Y1116058D01*
G01X1397020Y1116053D02*
X1397013Y1116055D01*
G01X1397028Y1116052D02*
X1397020Y1116053D01*
G01X1396989Y1119231D02*
X1396988Y1119239D01*
G01X1396991Y1119224D02*
X1396989Y1119231D01*
G01X1396995Y1119218D02*
X1396991Y1119224D01*
G01X1397000Y1119212D02*
X1396995Y1119218D01*
G01X1397006Y1119207D02*
X1397000Y1119212D01*
G01X1397013Y1119204D02*
X1397006Y1119207D01*
G01X1397020Y1119202D02*
X1397013Y1119204D01*
G01X1397028Y1119202D02*
X1397020D01*
G01X1396989Y1122381D02*
X1396988Y1122388D01*
G01X1396991Y1122374D02*
X1396989Y1122381D01*
G01X1396995Y1122368D02*
X1396991Y1122374D01*
G01X1397000Y1122362D02*
X1396995Y1122368D01*
G01X1397006Y1122357D02*
X1397000Y1122362D01*
G01X1397013Y1122354D02*
X1397006Y1122357D01*
G01X1397020Y1122352D02*
X1397013Y1122354D01*
G01X1397028Y1122351D02*
X1397020Y1122352D01*
G01X1397942Y1104644D02*
X1397952Y1104640D01*
G01X1397931Y1104646D02*
X1397942Y1104644D01*
G01Y1107794D02*
X1397952Y1107790D01*
G01X1397931Y1107795D02*
X1397942Y1107794D01*
G01Y1110944D02*
X1397952Y1110939D01*
G01X1397931Y1110945D02*
X1397942Y1110944D01*
G01Y1114093D02*
X1397952Y1114089D01*
G01X1397931Y1114094D02*
X1397942Y1114093D01*
G01Y1117243D02*
X1397952Y1117239D01*
G01X1397931Y1117244D02*
X1397942Y1117243D01*
G01Y1120393D02*
X1397952Y1120388D01*
G01X1397931Y1120394D02*
X1397942Y1120393D01*
G01Y1123542D02*
X1397952Y1123538D01*
G01X1397931Y1123543D02*
X1397942Y1123542D01*
G01X1396988Y1106644D02*
Y1106640D01*
G01X1396990Y1106638D02*
X1396988Y1106644D01*
G01X1397002Y1106622D02*
X1396990Y1106638D01*
G01X1397026Y1106614D02*
X1397002Y1106622D01*
G01X1396988Y1109794D02*
Y1109790D01*
G01X1396990Y1109787D02*
X1396988Y1109794D01*
G01X1397001Y1109772D02*
X1396990Y1109787D01*
G01X1397026Y1109764D02*
X1397001Y1109772D01*
G01X1396988Y1116093D02*
Y1116089D01*
G01X1396990Y1116087D02*
X1396988Y1116093D01*
G01X1397001Y1116071D02*
X1396990Y1116087D01*
G01X1397026Y1116063D02*
X1397001Y1116071D01*
G01X1396988Y1119243D02*
Y1119239D01*
G01X1396990Y1119236D02*
X1396988Y1119243D01*
G01X1397001Y1119221D02*
X1396990Y1119236D01*
G01X1397026Y1119213D02*
X1397001Y1119221D01*
G01X1396988Y1103494D02*
Y1103491D01*
G01X1396990Y1103488D02*
X1396988Y1103494D01*
G01X1397001Y1103473D02*
X1396990Y1103488D01*
G01X1397026Y1103465D02*
X1397001Y1103473D01*
G01X1396988Y1122392D02*
Y1122388D01*
G01X1396990Y1122386D02*
X1396988Y1122392D01*
G01X1397001Y1122370D02*
X1396990Y1122386D01*
G01X1397026Y1122362D02*
X1397001Y1122370D01*
G01X1411385Y1086685D02*
X1411396Y1086669D01*
G01X1411361Y1086693D02*
X1411385Y1086685D01*
G01Y1091685D02*
X1411396Y1091669D01*
G01X1411361Y1091693D02*
X1411385Y1091685D01*
G01Y1096685D02*
X1411396Y1096669D01*
G01X1411361Y1096693D02*
X1411385Y1096685D01*
G01Y1101685D02*
X1411396Y1101669D01*
G01X1411361Y1101693D02*
X1411385Y1101685D01*
G01X1411365Y1086791D02*
X1411369Y1086890D01*
G01X1411359Y1086719D02*
X1411365Y1086791D01*
G01X1411361Y1086693D02*
X1411359Y1086719D01*
G01X1411365Y1091791D02*
X1411369Y1091890D01*
G01X1411359Y1091719D02*
X1411365Y1091791D01*
G01X1411361Y1091693D02*
X1411359Y1091719D01*
G01X1411365Y1096791D02*
X1411369Y1096890D01*
G01X1411359Y1096719D02*
X1411365Y1096791D01*
G01X1411361Y1096693D02*
X1411359Y1096719D01*
G01X1411365Y1101791D02*
X1411369Y1101890D01*
G01X1411359Y1101719D02*
X1411365Y1101791D01*
G01X1411361Y1101693D02*
X1411359Y1101719D01*
G01X1411365Y1126791D02*
X1411369Y1126890D01*
G01X1411359Y1126719D02*
X1411365Y1126791D01*
G01X1411361Y1126693D02*
X1411359Y1126719D01*
G01X1411385Y1126685D02*
X1411396Y1126669D01*
G01X1411361Y1126693D02*
X1411385Y1126685D01*
G01X1396988Y1112943D02*
Y1112939D01*
G01X1396989Y1112938D02*
X1396988Y1112943D01*
G01X1397000Y1112923D02*
X1396989Y1112938D01*
G01X1397023Y1112914D02*
X1397000Y1112923D01*
G01X1397941Y1110944D02*
X1397931Y1110945D01*
G01X1397950Y1110941D02*
X1397941Y1110944D01*
G01X1397957Y1110935D02*
X1397950Y1110941D01*
G01X1397941Y1104644D02*
X1397931Y1104646D01*
G01X1397950Y1104641D02*
X1397941Y1104644D01*
G01X1397957Y1104636D02*
X1397950Y1104641D01*
G01X1397941Y1107794D02*
X1397931Y1107795D01*
G01X1397950Y1107791D02*
X1397941Y1107794D01*
G01X1397957Y1107786D02*
X1397950Y1107791D01*
G01X1397941Y1114093D02*
X1397931Y1114094D01*
G01X1397950Y1114090D02*
X1397941Y1114093D01*
G01X1397957Y1114085D02*
X1397950Y1114090D01*
G01X1397941Y1117243D02*
X1397931Y1117244D01*
G01X1397950Y1117240D02*
X1397941Y1117243D01*
G01X1397957Y1117235D02*
X1397950Y1117240D01*
G01X1397941Y1120393D02*
X1397931Y1120394D01*
G01X1397950Y1120389D02*
X1397941Y1120393D01*
G01X1397957Y1120384D02*
X1397950Y1120389D01*
G01X1397941Y1123542D02*
X1397931Y1123543D01*
G01X1397950Y1123539D02*
X1397941Y1123542D01*
G01X1397957Y1123534D02*
X1397950Y1123539D01*
G01X1397027Y1103460D02*
X1397028Y1103454D01*
G01X1397026Y1103463D02*
X1397027Y1103460D01*
G01X1397025Y1103465D02*
X1397026Y1103463D01*
G01X1397027Y1106609D02*
X1397028Y1106603D01*
G01X1397026Y1106613D02*
X1397027Y1106609D01*
G01X1397025Y1106614D02*
X1397026Y1106613D01*
G01X1397027Y1109759D02*
X1397028Y1109753D01*
G01X1397026Y1109763D02*
X1397027Y1109759D01*
G01X1397025Y1109764D02*
X1397026Y1109763D01*
G01X1397027Y1112909D02*
X1397028Y1112902D01*
G01X1397026Y1112912D02*
X1397027Y1112909D01*
G01X1397025Y1112913D02*
X1397026Y1112912D01*
G01X1397027Y1116058D02*
X1397028Y1116052D01*
G01X1397026Y1116062D02*
X1397027Y1116058D01*
G01X1397025Y1116063D02*
X1397026Y1116062D01*
G01X1397027Y1119208D02*
X1397028Y1119202D01*
G01X1397026Y1119211D02*
X1397027Y1119208D01*
G01X1397025Y1119213D02*
X1397026Y1119211D01*
G01X1397027Y1122357D02*
X1397028Y1122351D01*
G01X1397026Y1122361D02*
X1397027Y1122357D01*
G01X1397025Y1122362D02*
X1397026Y1122361D01*
G01X1411398Y1086660D02*
Y1086667D01*
G01X1411399Y1086656D02*
X1411398Y1086660D01*
G01X1411400Y1086654D02*
X1411399Y1086656D01*
G01X1411398Y1091660D02*
Y1091667D01*
G01X1411399Y1091656D02*
X1411398Y1091660D01*
G01X1411400Y1091654D02*
X1411399Y1091656D01*
G01X1411398Y1096660D02*
Y1096667D01*
G01X1411399Y1096656D02*
X1411398Y1096660D01*
G01X1411400Y1096654D02*
X1411399Y1096656D01*
G01X1411398Y1101660D02*
Y1101667D01*
G01X1411399Y1101656D02*
X1411398Y1101660D01*
G01X1411400Y1101654D02*
X1411399Y1101656D01*
G01X1397011Y1106617D02*
X1397025Y1106614D01*
G01X1397000Y1106624D02*
X1397011Y1106617D01*
G01X1396987Y1106643D02*
X1397000Y1106624D01*
G01X1397011Y1116066D02*
X1397025Y1116063D01*
G01X1396999Y1116073D02*
X1397011Y1116066D01*
G01X1396987Y1116091D02*
X1396999Y1116073D01*
G01X1397011Y1109767D02*
X1397025Y1109764D01*
G01X1396998Y1109774D02*
X1397011Y1109767D01*
G01X1396987Y1109794D02*
X1396998Y1109774D01*
G01X1397011Y1119215D02*
X1397025Y1119213D01*
G01X1396998Y1119223D02*
X1397011Y1119215D01*
G01X1396987Y1119243D02*
X1396998Y1119223D01*
G01X1397972Y1103498D02*
Y1103491D01*
G01Y1103503D02*
Y1103498D01*
G01X1397971Y1103504D02*
X1397972Y1103503D01*
G01Y1106648D02*
Y1106640D01*
G01Y1106652D02*
Y1106648D01*
G01X1397971Y1106654D02*
X1397972Y1106652D01*
G01Y1109797D02*
Y1109790D01*
G01Y1109802D02*
Y1109797D01*
G01X1397971Y1109803D02*
X1397972Y1109802D01*
G01Y1112947D02*
Y1112939D01*
G01Y1112952D02*
Y1112947D01*
G01X1397971Y1112953D02*
X1397972Y1112952D01*
G01Y1116096D02*
Y1116089D01*
G01Y1116101D02*
Y1116096D01*
G01X1397971Y1116102D02*
X1397972Y1116101D01*
G01Y1119246D02*
Y1119239D01*
G01Y1119251D02*
Y1119246D01*
G01X1397971Y1119252D02*
X1397972Y1119251D01*
G01Y1122396D02*
Y1122388D01*
G01Y1122400D02*
Y1122396D01*
G01X1397971Y1122402D02*
X1397972Y1122400D01*
G01X1397011Y1122365D02*
X1397025Y1122362D01*
G01X1396998Y1122373D02*
X1397011Y1122365D01*
G01X1396987Y1122393D02*
X1396998Y1122373D01*
G01X1397010Y1103468D02*
X1397025Y1103465D01*
G01X1396997Y1103476D02*
X1397010Y1103468D01*
G01X1396987Y1103496D02*
X1396997Y1103476D01*
G01X1397972Y1104627D02*
Y1104620D01*
G01X1397970Y1104633D02*
X1397972Y1104627D01*
G01X1397967Y1104639D02*
X1397970Y1104633D01*
G01X1397972Y1107776D02*
Y1107770D01*
G01X1397970Y1107783D02*
X1397972Y1107776D01*
G01X1397967Y1107789D02*
X1397970Y1107783D01*
G01X1397972Y1110926D02*
Y1110919D01*
G01X1397970Y1110932D02*
X1397972Y1110926D01*
G01X1397967Y1110938D02*
X1397970Y1110932D01*
G01X1397972Y1114076D02*
Y1114069D01*
G01X1397970Y1114082D02*
X1397972Y1114076D01*
G01X1397967Y1114088D02*
X1397970Y1114082D01*
G01X1397972Y1117225D02*
Y1117219D01*
G01X1397970Y1117231D02*
X1397972Y1117225D01*
G01X1397967Y1117237D02*
X1397970Y1117231D01*
G01X1397972Y1120375D02*
Y1120368D01*
G01X1397970Y1120381D02*
X1397972Y1120375D01*
G01X1397967Y1120387D02*
X1397970Y1120381D01*
G01X1397972Y1123524D02*
Y1123518D01*
G01X1397970Y1123531D02*
X1397972Y1123524D01*
G01X1397967Y1123537D02*
X1397970Y1123531D01*
G01X1397933Y1103459D02*
X1397934Y1103454D01*
G01X1397932Y1103463D02*
X1397933Y1103459D01*
G01X1397931Y1103465D02*
X1397932Y1103463D01*
G01X1397933Y1106609D02*
X1397934Y1106603D01*
G01X1397932Y1106613D02*
X1397933Y1106609D01*
G01X1397931Y1106614D02*
X1397932Y1106613D01*
G01X1397933Y1109759D02*
X1397934Y1109753D01*
G01X1397932Y1109763D02*
X1397933Y1109759D01*
G01X1397931Y1109764D02*
X1397932Y1109763D01*
G01X1397933Y1112908D02*
X1397934Y1112902D01*
G01X1397932Y1112912D02*
X1397933Y1112908D01*
G01X1397931Y1112913D02*
X1397932Y1112912D01*
G01X1397933Y1116058D02*
X1397934Y1116052D01*
G01X1397932Y1116062D02*
X1397933Y1116058D01*
G01X1397931Y1116063D02*
X1397932Y1116062D01*
G01X1397933Y1122357D02*
X1397934Y1122351D01*
G01X1397932Y1122361D02*
X1397933Y1122357D01*
G01X1397931Y1122362D02*
X1397932Y1122361D01*
G01X1410413Y1086700D02*
Y1086709D01*
G01X1410414Y1086695D02*
X1410413Y1086700D01*
G01X1410415Y1086693D02*
X1410414Y1086695D01*
G01X1410413Y1091700D02*
Y1091709D01*
G01X1410414Y1091695D02*
X1410413Y1091700D01*
G01X1410415Y1091693D02*
X1410414Y1091695D01*
G01X1410413Y1096700D02*
Y1096709D01*
G01X1410414Y1096695D02*
X1410413Y1096700D01*
G01X1410415Y1096693D02*
X1410414Y1096695D01*
G01X1410413Y1101700D02*
Y1101709D01*
G01X1410414Y1101695D02*
X1410413Y1101700D01*
G01X1410415Y1101693D02*
X1410414Y1101695D01*
G01X1410413Y1126700D02*
Y1126709D01*
G01X1410414Y1126695D02*
X1410413Y1126700D01*
G01X1410415Y1126693D02*
X1410414Y1126695D01*
G01X1411390Y1086837D02*
X1411398Y1086811D01*
G01X1411380Y1086863D02*
X1411390Y1086837D01*
G01X1411369Y1086890D02*
X1411380Y1086863D01*
G01X1411390Y1091837D02*
X1411398Y1091811D01*
G01X1411380Y1091863D02*
X1411390Y1091837D01*
G01X1411369Y1091890D02*
X1411380Y1091863D01*
G01X1411390Y1096837D02*
X1411398Y1096811D01*
G01X1411380Y1096863D02*
X1411390Y1096837D01*
G01X1411369Y1096890D02*
X1411380Y1096863D01*
G01X1411390Y1101837D02*
X1411398Y1101811D01*
G01X1411380Y1101863D02*
X1411390Y1101837D01*
G01X1411369Y1101890D02*
X1411380Y1101863D01*
G01X1411390Y1126837D02*
X1411398Y1126811D01*
G01X1411380Y1126863D02*
X1411390Y1126837D01*
G01X1411369Y1126890D02*
X1411380Y1126863D01*
G01X1397006Y1112919D02*
X1397025Y1112913D01*
G01X1396993Y1112931D02*
X1397006Y1112919D01*
G01X1396986Y1112949D02*
X1396993Y1112931D01*
G01X1411380Y1086688D02*
X1411361Y1086693D01*
G01X1411395Y1086674D02*
X1411380Y1086688D01*
G01X1411400Y1086654D02*
X1411395Y1086674D01*
G01X1411380Y1091688D02*
X1411361Y1091693D01*
G01X1411395Y1091674D02*
X1411380Y1091688D01*
G01X1411400Y1091654D02*
X1411395Y1091674D01*
G01X1411380Y1096688D02*
X1411361Y1096693D01*
G01X1411395Y1096674D02*
X1411380Y1096688D01*
G01X1411400Y1096654D02*
X1411395Y1096674D01*
G01X1411380Y1101688D02*
X1411361Y1101693D01*
G01X1411395Y1101674D02*
X1411380Y1101688D01*
G01X1411400Y1101654D02*
X1411395Y1101674D01*
G01X1411380Y1126688D02*
X1411361Y1126693D01*
G01X1411395Y1126674D02*
X1411380Y1126688D01*
G01X1411400Y1126654D02*
X1411395Y1126674D01*
G01X1397965Y1110927D02*
X1397957Y1110935D01*
G01X1397969Y1110917D02*
X1397965Y1110927D01*
G01X1397971Y1110906D02*
X1397969Y1110917D01*
G01X1397965Y1104628D02*
X1397957Y1104636D01*
G01X1397970Y1104617D02*
X1397965Y1104628D01*
G01X1397971Y1104606D02*
X1397970Y1104617D01*
G01X1397965Y1107777D02*
X1397957Y1107786D01*
G01X1397970Y1107767D02*
X1397965Y1107777D01*
G01X1397971Y1107756D02*
X1397970Y1107767D01*
G01X1397965Y1114076D02*
X1397957Y1114085D01*
G01X1397970Y1114066D02*
X1397965Y1114076D01*
G01X1397971Y1114055D02*
X1397970Y1114066D01*
G01X1397965Y1117226D02*
X1397957Y1117235D01*
G01X1397970Y1117216D02*
X1397965Y1117226D01*
G01X1397971Y1117205D02*
X1397970Y1117216D01*
G01X1397965Y1120376D02*
X1397957Y1120384D01*
G01X1397970Y1120365D02*
X1397965Y1120376D01*
G01X1397971Y1120354D02*
X1397970Y1120365D01*
G01X1397965Y1123525D02*
X1397957Y1123534D01*
G01X1397970Y1123515D02*
X1397965Y1123525D01*
G01X1397971Y1123504D02*
X1397970Y1123515D01*
G01X1411398Y1126660D02*
Y1126667D01*
G01X1411399Y1126656D02*
X1411398Y1126660D01*
G01X1411400Y1126654D02*
X1411399Y1126656D01*
G01X1397931Y1119213D02*
X1397935Y1119202D01*
G01X1410827Y1103642D02*
X1412008Y1102461D01*
G01X1406890Y1103642D02*
X1408071Y1102461D01*
G01X1396875Y1122402D02*
X1396987Y1122393D01*
G01X1397972Y1104609D02*
Y1104620D01*
G01Y1107758D02*
Y1107769D01*
G01Y1110908D02*
Y1110919D01*
G01Y1114057D02*
Y1114069D01*
G01Y1117207D02*
Y1117218D01*
G01Y1120357D02*
Y1120368D01*
G01Y1123506D02*
Y1123517D01*
G01X1411398Y1086667D02*
Y1086676D01*
G01Y1091667D02*
Y1091676D01*
G01Y1096667D02*
Y1096676D01*
G01Y1101667D02*
Y1101676D01*
G01Y1126667D02*
Y1126676D01*
G01X1415748Y1130315D02*
Y1131693D01*
G01Y1125315D02*
Y1126693D01*
G01Y1100315D02*
Y1101693D01*
G01Y1095315D02*
Y1096693D01*
G01Y1090315D02*
Y1091693D01*
G01Y1085315D02*
Y1086693D01*
G01X1412579D02*
Y1085315D01*
G01Y1091693D02*
Y1090315D01*
G01Y1096693D02*
Y1095315D01*
G01Y1101693D02*
Y1100315D01*
G01Y1126693D02*
Y1125315D01*
G01Y1131693D02*
Y1130315D01*
G01X1412008Y1124547D02*
Y1102461D01*
G01X1411398Y1129823D02*
Y1132185D01*
G01Y1124823D02*
Y1127185D01*
G01Y1099823D02*
Y1102185D01*
G01Y1094823D02*
Y1097185D01*
G01Y1089823D02*
Y1092185D01*
G01Y1084823D02*
Y1087185D01*
G01Y1086667D02*
Y1086811D01*
G01Y1091667D02*
Y1091811D01*
G01Y1096667D02*
Y1096811D01*
G01Y1101667D02*
Y1101811D01*
G01Y1126667D02*
Y1126811D01*
G01X1410827Y1123366D02*
Y1103642D01*
G01X1410413Y1087185D02*
Y1084823D01*
G01Y1092185D02*
Y1089823D01*
G01Y1097185D02*
Y1094823D01*
G01Y1102185D02*
Y1099823D01*
G01Y1127185D02*
Y1124823D01*
G01Y1132185D02*
Y1129823D01*
G01X1408071Y1201004D02*
Y1124547D01*
G01X1406890Y1199823D02*
Y1123366D01*
G01X1398425Y1204744D02*
Y1125709D01*
G01X1397972Y1122205D02*
Y1123701D01*
G01Y1119055D02*
Y1120551D01*
G01Y1115906D02*
Y1117402D01*
G01Y1112756D02*
Y1114252D01*
G01Y1109606D02*
Y1111102D01*
G01Y1106457D02*
Y1107953D01*
G01Y1103307D02*
Y1104803D01*
G01X1397933Y1106603D02*
Y1106456D01*
G01Y1103454D02*
Y1103307D01*
G01Y1104804D02*
Y1104657D01*
G01Y1109753D02*
Y1109606D01*
G01Y1111103D02*
Y1110956D01*
G01Y1107953D02*
Y1107807D01*
G01Y1116052D02*
Y1115905D01*
G01Y1112902D02*
Y1112756D01*
G01Y1114252D02*
Y1114106D01*
G01Y1119202D02*
Y1119055D01*
G01Y1120552D02*
Y1120405D01*
G01Y1117402D02*
Y1117256D01*
G01Y1122351D02*
Y1122204D01*
G01Y1123701D02*
Y1123555D01*
G01X1397028Y1122204D02*
Y1122351D01*
G01Y1123555D02*
Y1123702D01*
G01Y1119054D02*
Y1119202D01*
G01Y1120405D02*
Y1120552D01*
G01Y1117256D02*
Y1117402D01*
G01Y1115905D02*
Y1116052D01*
G01Y1112755D02*
Y1112902D01*
G01Y1114106D02*
Y1114253D01*
G01Y1109606D02*
Y1109753D01*
G01Y1110956D02*
Y1111103D01*
G01Y1107807D02*
Y1107954D01*
G01Y1106456D02*
Y1106603D01*
G01Y1103306D02*
Y1103454D01*
G01Y1104657D02*
Y1104804D01*
G01X1396988Y1104803D02*
Y1103307D01*
G01Y1111102D02*
Y1109606D01*
G01Y1107953D02*
Y1106457D01*
G01Y1114252D02*
Y1112756D01*
G01Y1120551D02*
Y1119055D01*
G01Y1117402D02*
Y1115906D01*
G01Y1123701D02*
Y1122205D01*
G01X1395807Y1107795D02*
Y1106614D01*
G01Y1104646D02*
Y1103465D01*
G01Y1110945D02*
Y1109764D01*
G01Y1117244D02*
Y1116063D01*
G01Y1114094D02*
Y1112913D01*
G01Y1120394D02*
Y1119213D01*
G01Y1123543D02*
Y1122362D01*
G01X1395472Y1125709D02*
Y1101299D01*
G01X1395079D02*
Y1125709D01*
G01X1392047Y1122362D02*
Y1123543D01*
G01Y1119213D02*
Y1120394D01*
G01Y1116063D02*
Y1117244D01*
G01Y1112913D02*
Y1114094D01*
G01Y1109764D02*
Y1110945D01*
G01Y1106614D02*
Y1107795D01*
G01Y1103465D02*
Y1104646D01*
G01X1397972Y1122388D02*
Y1122399D01*
G01Y1119239D02*
Y1119250D01*
G01Y1116089D02*
Y1116100D01*
G01Y1112939D02*
Y1112950D01*
G01Y1109790D02*
Y1109801D01*
G01Y1106640D02*
Y1106651D01*
G01Y1103491D02*
Y1103502D01*
G01X1396986Y1112949D02*
X1396875Y1112953D01*
G01X1396986Y1106650D02*
X1396875Y1106654D01*
G01X1396986Y1116099D02*
X1396875Y1116102D01*
G01X1415748Y1130315D02*
X1410415D01*
G01X1410413Y1129823D02*
X1411398D01*
G01Y1127185D02*
X1410413D01*
G01X1410415Y1126693D02*
X1415748D01*
G01Y1126654D02*
X1411400D01*
G01X1398425Y1125709D02*
X1395079D01*
G01X1415748Y1125315D02*
X1410415D01*
G01X1410413Y1124823D02*
X1411398D01*
G01X1408071Y1124547D02*
X1412008D01*
G01X1397933Y1123740D02*
X1397028D01*
G01X1397972Y1123701D02*
X1396988D01*
G01X1397931Y1123543D02*
X1392047D01*
G01Y1123504D02*
X1397971D01*
G01X1406890Y1123366D02*
X1410827D01*
G01X1397971Y1122402D02*
X1392047D01*
G01X1397931Y1122362D02*
X1392047D01*
G01X1396988Y1122205D02*
X1397972D01*
G01X1397028Y1122165D02*
X1397933D01*
G01Y1120591D02*
X1397028D01*
G01X1397972Y1120551D02*
X1396988D01*
G01X1397931Y1120394D02*
X1392047D01*
G01Y1120354D02*
X1397971D01*
G01Y1119252D02*
X1392047D01*
G01X1397931Y1119213D02*
X1392047D01*
G01X1396988Y1119055D02*
X1397972D01*
G01X1397028Y1119016D02*
X1397933D01*
G01Y1117441D02*
X1397028D01*
G01X1397972Y1117402D02*
X1396988D01*
G01X1397931Y1117244D02*
X1392047D01*
G01Y1117205D02*
X1397971D01*
G01X1396241Y1116102D02*
X1395807D01*
G01X1397971D02*
X1392047D01*
G01X1397931Y1116063D02*
X1392047D01*
G01X1396988Y1115906D02*
X1397972D01*
G01X1397028Y1115866D02*
X1397933D01*
G01Y1114291D02*
X1397028D01*
G01X1397972Y1114252D02*
X1396988D01*
G01X1397931Y1114094D02*
X1392047D01*
G01Y1114055D02*
X1397971D01*
G01X1396241Y1112953D02*
X1395807D01*
G01X1397971D02*
X1392047D01*
G01X1397931Y1112913D02*
X1392047D01*
G01X1396988Y1112756D02*
X1397972D01*
G01X1397028Y1112717D02*
X1397933D01*
G01Y1111142D02*
X1397028D01*
G01X1397972Y1111102D02*
X1396988D01*
G01X1397931Y1110945D02*
X1392047D01*
G01Y1110906D02*
X1397971D01*
G01Y1109803D02*
X1392047D01*
G01X1397931Y1109764D02*
X1392047D01*
G01X1396988Y1109606D02*
X1397972D01*
G01X1397028Y1109567D02*
X1397933D01*
G01Y1107992D02*
X1397028D01*
G01X1397972Y1107953D02*
X1396988D01*
G01X1397931Y1107795D02*
X1392047D01*
G01Y1107756D02*
X1397971D01*
G01X1396241Y1106654D02*
X1395807D01*
G01X1397971D02*
X1392047D01*
G01X1397931Y1106614D02*
X1392047D01*
G01X1396988Y1106457D02*
X1397972D01*
G01X1397028Y1106417D02*
X1397933D01*
G01Y1104843D02*
X1397028D01*
G01X1397972Y1104803D02*
X1396988D01*
G01X1397931Y1104646D02*
X1392047D01*
G01Y1104606D02*
X1397971D01*
G01X1410827Y1103642D02*
X1406890D01*
G01X1397971Y1103504D02*
X1392047D01*
G01X1397931Y1103465D02*
X1392047D01*
G01X1396988Y1103307D02*
X1397972D01*
G01X1397028Y1103268D02*
X1397933D01*
G01X1412008Y1102461D02*
X1408071D01*
G01X1411398Y1102185D02*
X1410413D01*
G01X1410415Y1101693D02*
X1415748D01*
G01Y1101654D02*
X1411400D01*
G01X1398425Y1101299D02*
X1395079D01*
G01X1415748Y1100315D02*
X1410415D01*
G01X1410413Y1099823D02*
X1411398D01*
G01Y1097185D02*
X1410413D01*
G01X1410415Y1096693D02*
X1415748D01*
G01Y1096654D02*
X1411400D01*
G01X1415748Y1095315D02*
X1410415D01*
G01X1410413Y1094823D02*
X1411398D01*
G01Y1092185D02*
X1410413D01*
G01X1410415Y1091693D02*
X1415748D01*
G01Y1091654D02*
X1411400D01*
G01X1415748Y1090315D02*
X1410415D01*
G01X1410413Y1089823D02*
X1411398D01*
G01Y1087185D02*
X1410413D01*
G01X1410415Y1086693D02*
X1415748D01*
G01Y1086654D02*
X1411400D01*
G01X1415748Y1085315D02*
X1410415D01*
G01X1410413Y1084823D02*
X1411398D01*
G01Y1130119D02*
X1410413Y1130118D01*
G01Y1126889D02*
X1411369Y1126890D01*
G01X1411398Y1125119D02*
X1410413Y1125118D01*
G01Y1101889D02*
X1411369Y1101890D01*
G01X1411398Y1100119D02*
X1410413Y1100118D01*
G01Y1096889D02*
X1411369Y1096890D01*
G01X1411398Y1095119D02*
X1410413Y1095118D01*
G01Y1091889D02*
X1411369Y1091890D01*
G01X1411398Y1090119D02*
X1410413Y1090118D01*
G01Y1086889D02*
X1411369Y1086890D01*
G01X1411398Y1085119D02*
X1410413Y1085118D01*
G01X1410827Y1123366D02*
X1412008Y1124547D01*
G01X1406890Y1123366D02*
X1408071Y1124547D01*
G01X1411398Y1175308D02*
Y1175299D01*
G01X1411399Y1175313D02*
X1411398Y1175308D01*
G01X1411400Y1175315D02*
X1411399Y1175313D01*
G01X1411398Y1170308D02*
Y1170299D01*
G01X1411399Y1170313D02*
X1411398Y1170308D01*
G01X1411400Y1170315D02*
X1411399Y1170313D01*
G01X1411398Y1165308D02*
Y1165299D01*
G01X1411399Y1165313D02*
X1411398Y1165308D01*
G01X1411400Y1165315D02*
X1411399Y1165313D01*
G01X1411398Y1160308D02*
Y1160299D01*
G01X1411399Y1160313D02*
X1411398Y1160308D01*
G01X1411400Y1160315D02*
X1411399Y1160313D01*
G01X1411398Y1155308D02*
Y1155299D01*
G01X1411399Y1155313D02*
X1411398Y1155308D01*
G01X1411400Y1155315D02*
X1411399Y1155313D01*
G01X1411398Y1150308D02*
Y1150299D01*
G01X1411399Y1150313D02*
X1411398Y1150308D01*
G01X1411400Y1150315D02*
X1411399Y1150313D01*
G01X1411398Y1145308D02*
Y1145299D01*
G01X1411399Y1145313D02*
X1411398Y1145308D01*
G01X1411400Y1145315D02*
X1411399Y1145313D01*
G01X1411398Y1140308D02*
Y1140299D01*
G01X1411399Y1140313D02*
X1411398Y1140308D01*
G01X1411400Y1140315D02*
X1411399Y1140313D01*
G01X1411398Y1135308D02*
Y1135299D01*
G01X1411399Y1135313D02*
X1411398Y1135308D01*
G01X1411400Y1135315D02*
X1411399Y1135313D01*
G01X1410414Y1175313D02*
X1410415Y1175315D01*
G01X1410413Y1175308D02*
X1410414Y1175313D01*
G01X1410413Y1175299D02*
Y1175308D01*
G01X1410414Y1170313D02*
X1410415Y1170315D01*
G01X1410413Y1170308D02*
X1410414Y1170313D01*
G01X1410413Y1170299D02*
Y1170308D01*
G01X1410414Y1165313D02*
X1410415Y1165315D01*
G01X1410413Y1165308D02*
X1410414Y1165313D01*
G01X1410413Y1165299D02*
Y1165308D01*
G01X1410414Y1160313D02*
X1410415Y1160315D01*
G01X1410413Y1160308D02*
X1410414Y1160313D01*
G01X1410413Y1160299D02*
Y1160308D01*
G01X1410414Y1155313D02*
X1410415Y1155315D01*
G01X1410413Y1155308D02*
X1410414Y1155313D01*
G01X1410413Y1155299D02*
Y1155308D01*
G01X1410414Y1150313D02*
X1410415Y1150315D01*
G01X1410413Y1150308D02*
X1410414Y1150313D01*
G01X1410413Y1150299D02*
Y1150308D01*
G01X1410414Y1145313D02*
X1410415Y1145315D01*
G01X1410413Y1145308D02*
X1410414Y1145313D01*
G01X1410413Y1145299D02*
Y1145308D01*
G01X1410414Y1140313D02*
X1410415Y1140315D01*
G01X1410413Y1140308D02*
X1410414Y1140313D01*
G01X1410413Y1140299D02*
Y1140308D01*
G01X1410414Y1135313D02*
X1410415Y1135315D01*
G01X1410413Y1135308D02*
X1410414Y1135313D01*
G01X1410413Y1135299D02*
Y1135308D01*
G01X1411365Y1131791D02*
X1411369Y1131890D01*
G01X1411359Y1131719D02*
X1411365Y1131791D01*
G01X1411361Y1131693D02*
X1411359Y1131719D01*
G01X1411365Y1136791D02*
X1411369Y1136890D01*
G01X1411359Y1136719D02*
X1411365Y1136791D01*
G01X1411361Y1136693D02*
X1411359Y1136719D01*
G01X1411365Y1141791D02*
X1411369Y1141890D01*
G01X1411359Y1141719D02*
X1411365Y1141791D01*
G01X1411361Y1141693D02*
X1411359Y1141719D01*
G01X1411365Y1146791D02*
X1411369Y1146890D01*
G01X1411359Y1146719D02*
X1411365Y1146791D01*
G01X1411361Y1146693D02*
X1411359Y1146719D01*
G01X1411365Y1151791D02*
X1411369Y1151890D01*
G01X1411359Y1151719D02*
X1411365Y1151791D01*
G01X1411361Y1151693D02*
X1411359Y1151719D01*
G01X1411365Y1156791D02*
X1411369Y1156890D01*
G01X1411359Y1156719D02*
X1411365Y1156791D01*
G01X1411361Y1156693D02*
X1411359Y1156719D01*
G01X1411365Y1161791D02*
X1411369Y1161890D01*
G01X1411359Y1161719D02*
X1411365Y1161791D01*
G01X1411361Y1161693D02*
X1411359Y1161719D01*
G01X1411365Y1166791D02*
X1411369Y1166890D01*
G01X1411359Y1166719D02*
X1411365Y1166791D01*
G01X1411361Y1166693D02*
X1411359Y1166719D01*
G01X1411365Y1171791D02*
X1411369Y1171890D01*
G01X1411359Y1171719D02*
X1411365Y1171791D01*
G01X1411361Y1171693D02*
X1411359Y1171719D01*
G01X1411365Y1176791D02*
X1411369Y1176890D01*
G01X1411359Y1176719D02*
X1411365Y1176791D01*
G01X1411361Y1176693D02*
X1411359Y1176719D01*
G01X1411385Y1131685D02*
X1411396Y1131669D01*
G01X1411361Y1131693D02*
X1411385Y1131685D01*
G01Y1136685D02*
X1411396Y1136669D01*
G01X1411361Y1136693D02*
X1411385Y1136685D01*
G01Y1141685D02*
X1411396Y1141669D01*
G01X1411361Y1141693D02*
X1411385Y1141685D01*
G01Y1146685D02*
X1411396Y1146669D01*
G01X1411361Y1146693D02*
X1411385Y1146685D01*
G01Y1151685D02*
X1411396Y1151669D01*
G01X1411361Y1151693D02*
X1411385Y1151685D01*
G01Y1156685D02*
X1411396Y1156669D01*
G01X1411361Y1156693D02*
X1411385Y1156685D01*
G01Y1161685D02*
X1411396Y1161669D01*
G01X1411361Y1161693D02*
X1411385Y1161685D01*
G01Y1166685D02*
X1411396Y1166669D01*
G01X1411361Y1166693D02*
X1411385Y1166685D01*
G01Y1171685D02*
X1411396Y1171669D01*
G01X1411361Y1171693D02*
X1411385Y1171685D01*
G01Y1176685D02*
X1411396Y1176669D01*
G01X1411361Y1176693D02*
X1411385Y1176685D01*
G01X1410413Y1131700D02*
Y1131709D01*
G01X1410414Y1131695D02*
X1410413Y1131700D01*
G01X1410415Y1131693D02*
X1410414Y1131695D01*
G01X1410413Y1136700D02*
Y1136709D01*
G01X1410414Y1136695D02*
X1410413Y1136700D01*
G01X1410415Y1136693D02*
X1410414Y1136695D01*
G01X1410413Y1141700D02*
Y1141709D01*
G01X1410414Y1141695D02*
X1410413Y1141700D01*
G01X1410415Y1141693D02*
X1410414Y1141695D01*
G01X1411390Y1131837D02*
X1411398Y1131811D01*
G01X1411380Y1131863D02*
X1411390Y1131837D01*
G01X1411369Y1131890D02*
X1411380Y1131863D01*
G01X1411390Y1136837D02*
X1411398Y1136811D01*
G01X1411380Y1136863D02*
X1411390Y1136837D01*
G01X1411369Y1136890D02*
X1411380Y1136863D01*
G01X1411390Y1141837D02*
X1411398Y1141811D01*
G01X1411380Y1141863D02*
X1411390Y1141837D01*
G01X1411369Y1141890D02*
X1411380Y1141863D01*
G01Y1131688D02*
X1411361Y1131693D01*
G01X1411395Y1131674D02*
X1411380Y1131688D01*
G01X1411400Y1131654D02*
X1411395Y1131674D01*
G01X1411380Y1136688D02*
X1411361Y1136693D01*
G01X1411395Y1136674D02*
X1411380Y1136688D01*
G01X1411400Y1136654D02*
X1411395Y1136674D01*
G01X1411380Y1141688D02*
X1411361Y1141693D01*
G01X1411395Y1141674D02*
X1411380Y1141688D01*
G01X1411400Y1141654D02*
X1411395Y1141674D01*
G01X1411380Y1146688D02*
X1411361Y1146693D01*
G01X1411395Y1146674D02*
X1411380Y1146688D01*
G01X1411400Y1146654D02*
X1411395Y1146674D01*
G01X1411380Y1151688D02*
X1411361Y1151693D01*
G01X1411395Y1151674D02*
X1411380Y1151688D01*
G01X1411400Y1151654D02*
X1411395Y1151674D01*
G01X1411380Y1156688D02*
X1411361Y1156693D01*
G01X1411395Y1156674D02*
X1411380Y1156688D01*
G01X1411400Y1156654D02*
X1411395Y1156674D01*
G01X1411380Y1161688D02*
X1411361Y1161693D01*
G01X1411395Y1161674D02*
X1411380Y1161688D01*
G01X1411400Y1161654D02*
X1411395Y1161674D01*
G01X1411380Y1166688D02*
X1411361Y1166693D01*
G01X1411395Y1166674D02*
X1411380Y1166688D01*
G01X1411400Y1166654D02*
X1411395Y1166674D01*
G01X1411380Y1171688D02*
X1411361Y1171693D01*
G01X1411395Y1171674D02*
X1411380Y1171688D01*
G01X1411400Y1171654D02*
X1411395Y1171674D01*
G01X1411380Y1176688D02*
X1411361Y1176693D01*
G01X1411395Y1176674D02*
X1411380Y1176688D01*
G01X1411400Y1176654D02*
X1411395Y1176674D01*
G01X1411398Y1131660D02*
Y1131667D01*
G01X1411399Y1131656D02*
X1411398Y1131660D01*
G01X1411400Y1131654D02*
X1411399Y1131656D01*
G01X1411398Y1136660D02*
Y1136667D01*
G01X1411399Y1136656D02*
X1411398Y1136660D01*
G01X1411400Y1136654D02*
X1411399Y1136656D01*
G01X1411398Y1141660D02*
Y1141667D01*
G01X1411399Y1141656D02*
X1411398Y1141660D01*
G01X1411400Y1141654D02*
X1411399Y1141656D01*
G01X1411398Y1146660D02*
Y1146667D01*
G01X1411399Y1146656D02*
X1411398Y1146660D01*
G01X1411400Y1146654D02*
X1411399Y1146656D01*
G01X1411398Y1151660D02*
Y1151667D01*
G01X1411399Y1151656D02*
X1411398Y1151660D01*
G01X1411400Y1151654D02*
X1411399Y1151656D01*
G01X1411398Y1156660D02*
Y1156667D01*
G01X1411399Y1156656D02*
X1411398Y1156660D01*
G01X1411400Y1156654D02*
X1411399Y1156656D01*
G01X1411398Y1161660D02*
Y1161667D01*
G01X1411399Y1161656D02*
X1411398Y1161660D01*
G01X1411400Y1161654D02*
X1411399Y1161656D01*
G01X1411398Y1166660D02*
Y1166667D01*
G01X1411399Y1166656D02*
X1411398Y1166660D01*
G01X1411400Y1166654D02*
X1411399Y1166656D01*
G01X1411398Y1171660D02*
Y1171667D01*
G01X1411399Y1171656D02*
X1411398Y1171660D01*
G01X1411400Y1171654D02*
X1411399Y1171656D01*
G01X1411398Y1176660D02*
Y1176667D01*
G01X1411399Y1176656D02*
X1411398Y1176660D01*
G01X1411400Y1176654D02*
X1411399Y1176656D01*
G01X1410413Y1146700D02*
Y1146709D01*
G01X1410414Y1146695D02*
X1410413Y1146700D01*
G01X1410415Y1146693D02*
X1410414Y1146695D01*
G01X1410413Y1151700D02*
Y1151709D01*
G01X1410414Y1151695D02*
X1410413Y1151700D01*
G01X1410415Y1151693D02*
X1410414Y1151695D01*
G01X1410413Y1156700D02*
Y1156709D01*
G01X1410414Y1156695D02*
X1410413Y1156700D01*
G01X1410415Y1156693D02*
X1410414Y1156695D01*
G01X1410413Y1161700D02*
Y1161709D01*
G01X1410414Y1161695D02*
X1410413Y1161700D01*
G01X1410415Y1161693D02*
X1410414Y1161695D01*
G01X1410413Y1166700D02*
Y1166709D01*
G01X1410414Y1166695D02*
X1410413Y1166700D01*
G01X1410415Y1166693D02*
X1410414Y1166695D01*
G01X1410413Y1171700D02*
Y1171709D01*
G01X1410414Y1171695D02*
X1410413Y1171700D01*
G01X1410415Y1171693D02*
X1410414Y1171695D01*
G01X1410413Y1176700D02*
Y1176709D01*
G01X1410414Y1176695D02*
X1410413Y1176700D01*
G01X1410415Y1176693D02*
X1410414Y1176695D01*
G01X1411390Y1146837D02*
X1411398Y1146811D01*
G01X1411380Y1146863D02*
X1411390Y1146837D01*
G01X1411369Y1146890D02*
X1411380Y1146863D01*
G01X1411390Y1151837D02*
X1411398Y1151811D01*
G01X1411380Y1151863D02*
X1411390Y1151837D01*
G01X1411369Y1151890D02*
X1411380Y1151863D01*
G01X1411390Y1156837D02*
X1411398Y1156811D01*
G01X1411380Y1156863D02*
X1411390Y1156837D01*
G01X1411369Y1156890D02*
X1411380Y1156863D01*
G01X1411390Y1161837D02*
X1411398Y1161811D01*
G01X1411380Y1161863D02*
X1411390Y1161837D01*
G01X1411369Y1161890D02*
X1411380Y1161863D01*
G01X1411390Y1166837D02*
X1411398Y1166811D01*
G01X1411380Y1166863D02*
X1411390Y1166837D01*
G01X1411369Y1166890D02*
X1411380Y1166863D01*
G01X1411390Y1171837D02*
X1411398Y1171811D01*
G01X1411380Y1171863D02*
X1411390Y1171837D01*
G01X1411369Y1171890D02*
X1411380Y1171863D01*
G01X1411390Y1176837D02*
X1411398Y1176811D01*
G01X1411380Y1176863D02*
X1411390Y1176837D01*
G01X1411369Y1176890D02*
X1411380Y1176863D01*
G01X1411398Y1177185D02*
X1410413D01*
G01X1410415Y1176693D02*
X1415748D01*
G01Y1176654D02*
X1411400D01*
G01X1415748Y1175315D02*
X1410415D01*
G01X1410413Y1174823D02*
X1411398D01*
G01Y1172185D02*
X1410413D01*
G01X1410415Y1171693D02*
X1415748D01*
G01Y1171654D02*
X1411400D01*
G01X1415748Y1170315D02*
X1410415D01*
G01X1410413Y1169823D02*
X1411398D01*
G01Y1167185D02*
X1410413D01*
G01X1410415Y1166693D02*
X1415748D01*
G01Y1166654D02*
X1411400D01*
G01X1415748Y1165315D02*
X1410415D01*
G01X1410413Y1164823D02*
X1411398D01*
G01Y1162185D02*
X1410413D01*
G01X1410415Y1161693D02*
X1415748D01*
G01Y1161654D02*
X1411400D01*
G01X1415748Y1160315D02*
X1410415D01*
G01X1410413Y1159823D02*
X1411398D01*
G01Y1157185D02*
X1410413D01*
G01X1410415Y1156693D02*
X1415748D01*
G01Y1156654D02*
X1411400D01*
G01X1415748Y1155315D02*
X1410415D01*
G01X1410413Y1154823D02*
X1411398D01*
G01X1410413Y1176889D02*
X1411369Y1176890D01*
G01X1411398Y1175119D02*
X1410413Y1175118D01*
G01Y1171889D02*
X1411369Y1171890D01*
G01X1411398Y1170119D02*
X1410413Y1170118D01*
G01Y1166889D02*
X1411369Y1166890D01*
G01X1411398Y1165119D02*
X1410413Y1165118D01*
G01Y1161889D02*
X1411369Y1161890D01*
G01X1411398Y1160119D02*
X1410413Y1160118D01*
G01Y1156889D02*
X1411369Y1156890D01*
G01X1411398Y1155119D02*
X1410413Y1155118D01*
G01X1411398Y1131667D02*
Y1131676D01*
G01Y1136667D02*
Y1136676D01*
G01Y1141667D02*
Y1141676D01*
G01Y1146667D02*
Y1146676D01*
G01Y1151667D02*
Y1151676D01*
G01Y1156667D02*
Y1156676D01*
G01Y1161667D02*
Y1161676D01*
G01Y1166667D02*
Y1166676D01*
G01Y1171667D02*
Y1171676D01*
G01Y1176667D02*
Y1176676D01*
G01X1415748Y1175315D02*
Y1176693D01*
G01Y1170315D02*
Y1171693D01*
G01Y1165315D02*
Y1166693D01*
G01Y1160315D02*
Y1161693D01*
G01Y1155315D02*
Y1156693D01*
G01Y1150315D02*
Y1151693D01*
G01Y1145315D02*
Y1146693D01*
G01Y1140315D02*
Y1141693D01*
G01Y1135315D02*
Y1136693D01*
G01X1412579D02*
Y1135315D01*
G01Y1141693D02*
Y1140315D01*
G01Y1146693D02*
Y1145315D01*
G01Y1151693D02*
Y1150315D01*
G01Y1156693D02*
Y1155315D01*
G01Y1161693D02*
Y1160315D01*
G01Y1166693D02*
Y1165315D01*
G01Y1171693D02*
Y1170315D01*
G01Y1176693D02*
Y1175315D01*
G01X1411398Y1174823D02*
Y1177185D01*
G01Y1169823D02*
Y1172185D01*
G01Y1164823D02*
Y1167185D01*
G01Y1159823D02*
Y1162185D01*
G01Y1154823D02*
Y1157185D01*
G01Y1149823D02*
Y1152185D01*
G01Y1144823D02*
Y1147185D01*
G01Y1139823D02*
Y1142185D01*
G01Y1134823D02*
Y1137185D01*
G01Y1131667D02*
Y1131811D01*
G01Y1136667D02*
Y1136811D01*
G01Y1141667D02*
Y1141811D01*
G01Y1146667D02*
Y1146811D01*
G01Y1151667D02*
Y1151811D01*
G01Y1156667D02*
Y1156811D01*
G01Y1161667D02*
Y1161811D01*
G01Y1166667D02*
Y1166811D01*
G01Y1171667D02*
Y1171811D01*
G01Y1176667D02*
Y1176811D01*
G01X1410413Y1137185D02*
Y1134823D01*
G01Y1142185D02*
Y1139823D01*
G01Y1147185D02*
Y1144823D01*
G01Y1152185D02*
Y1149823D01*
G01Y1157185D02*
Y1154823D01*
G01Y1162185D02*
Y1159823D01*
G01Y1167185D02*
Y1164823D01*
G01Y1172185D02*
Y1169823D01*
G01Y1177185D02*
Y1174823D01*
G01X1411398Y1152185D02*
X1410413D01*
G01X1410415Y1151693D02*
X1415748D01*
G01Y1151654D02*
X1411400D01*
G01X1415748Y1150315D02*
X1410415D01*
G01X1410413Y1149823D02*
X1411398D01*
G01Y1147185D02*
X1410413D01*
G01X1410415Y1146693D02*
X1415748D01*
G01Y1146654D02*
X1411400D01*
G01X1415748Y1145315D02*
X1410415D01*
G01X1410413Y1144823D02*
X1411398D01*
G01Y1142185D02*
X1410413D01*
G01X1410415Y1141693D02*
X1415748D01*
G01Y1141654D02*
X1411400D01*
G01X1415748Y1140315D02*
X1410415D01*
G01X1410413Y1139823D02*
X1411398D01*
G01Y1137185D02*
X1410413D01*
G01X1410415Y1136693D02*
X1415748D01*
G01Y1136654D02*
X1411400D01*
G01X1415748Y1135315D02*
X1410415D01*
G01X1410413Y1134823D02*
X1411398D01*
G01Y1132185D02*
X1410413D01*
G01X1410415Y1131693D02*
X1415748D01*
G01Y1131654D02*
X1411400D01*
G01X1410413Y1151889D02*
X1411369Y1151890D01*
G01X1411398Y1150119D02*
X1410413Y1150118D01*
G01Y1146889D02*
X1411369Y1146890D01*
G01X1411398Y1145119D02*
X1410413Y1145118D01*
G01Y1141889D02*
X1411369Y1141890D01*
G01X1411398Y1140119D02*
X1410413Y1140118D01*
G01Y1136889D02*
X1411369Y1136890D01*
G01X1411398Y1135119D02*
X1410413Y1135118D01*
G01Y1131889D02*
X1411369Y1131890D01*
G01X1411398Y1195308D02*
Y1195299D01*
G01X1411399Y1195313D02*
X1411398Y1195308D01*
G01X1411400Y1195315D02*
X1411399Y1195313D01*
G01X1411398Y1190308D02*
Y1190299D01*
G01X1411399Y1190313D02*
X1411398Y1190308D01*
G01X1411400Y1190315D02*
X1411399Y1190313D01*
G01X1411398Y1185308D02*
Y1185299D01*
G01X1411399Y1185313D02*
X1411398Y1185308D01*
G01X1411400Y1185315D02*
X1411399Y1185313D01*
G01X1411398Y1180308D02*
Y1180299D01*
G01X1411399Y1180313D02*
X1411398Y1180308D01*
G01X1411400Y1180315D02*
X1411399Y1180313D01*
G01X1410414Y1195313D02*
X1410415Y1195315D01*
G01X1410413Y1195308D02*
X1410414Y1195313D01*
G01X1410413Y1195299D02*
Y1195308D01*
G01X1410414Y1190313D02*
X1410415Y1190315D01*
G01X1410413Y1190308D02*
X1410414Y1190313D01*
G01X1410413Y1190299D02*
Y1190308D01*
G01X1410414Y1185313D02*
X1410415Y1185315D01*
G01X1410413Y1185308D02*
X1410414Y1185313D01*
G01X1410413Y1185299D02*
Y1185308D01*
G01X1410414Y1180313D02*
X1410415Y1180315D01*
G01X1410413Y1180308D02*
X1410414Y1180313D01*
G01X1410413Y1180299D02*
Y1180308D01*
G01X1411365Y1181791D02*
X1411369Y1181890D01*
G01X1411359Y1181719D02*
X1411365Y1181791D01*
G01X1411361Y1181693D02*
X1411359Y1181719D01*
G01X1411365Y1186791D02*
X1411369Y1186890D01*
G01X1411359Y1186719D02*
X1411365Y1186791D01*
G01X1411361Y1186693D02*
X1411359Y1186719D01*
G01X1411365Y1191791D02*
X1411369Y1191890D01*
G01X1411359Y1191719D02*
X1411365Y1191791D01*
G01X1411361Y1191693D02*
X1411359Y1191719D01*
G01X1411365Y1196791D02*
X1411369Y1196890D01*
G01X1411359Y1196719D02*
X1411365Y1196791D01*
G01X1411361Y1196693D02*
X1411359Y1196719D01*
G01X1411385Y1181685D02*
X1411396Y1181669D01*
G01X1411361Y1181693D02*
X1411385Y1181685D01*
G01Y1186685D02*
X1411396Y1186669D01*
G01X1411361Y1186693D02*
X1411385Y1186685D01*
G01Y1191685D02*
X1411396Y1191669D01*
G01X1411361Y1191693D02*
X1411385Y1191685D01*
G01Y1196685D02*
X1411396Y1196669D01*
G01X1411361Y1196693D02*
X1411385Y1196685D01*
G01X1411380Y1181688D02*
X1411361Y1181693D01*
G01X1411395Y1181674D02*
X1411380Y1181688D01*
G01X1411400Y1181654D02*
X1411395Y1181674D01*
G01X1411380Y1186688D02*
X1411361Y1186693D01*
G01X1411395Y1186674D02*
X1411380Y1186688D01*
G01X1411400Y1186654D02*
X1411395Y1186674D01*
G01X1411380Y1191688D02*
X1411361Y1191693D01*
G01X1411395Y1191674D02*
X1411380Y1191688D01*
G01X1411400Y1191654D02*
X1411395Y1191674D01*
G01X1411380Y1196688D02*
X1411361Y1196693D01*
G01X1411395Y1196674D02*
X1411380Y1196688D01*
G01X1411400Y1196654D02*
X1411395Y1196674D01*
G01X1411398Y1181660D02*
Y1181667D01*
G01X1411399Y1181656D02*
X1411398Y1181660D01*
G01X1411400Y1181654D02*
X1411399Y1181656D01*
G01X1411398Y1186660D02*
Y1186667D01*
G01X1411399Y1186656D02*
X1411398Y1186660D01*
G01X1411400Y1186654D02*
X1411399Y1186656D01*
G01X1411398Y1191660D02*
Y1191667D01*
G01X1411399Y1191656D02*
X1411398Y1191660D01*
G01X1411400Y1191654D02*
X1411399Y1191656D01*
G01X1411398Y1196660D02*
Y1196667D01*
G01X1411399Y1196656D02*
X1411398Y1196660D01*
G01X1411400Y1196654D02*
X1411399Y1196656D01*
G01X1410413Y1181700D02*
Y1181709D01*
G01X1410414Y1181695D02*
X1410413Y1181700D01*
G01X1410415Y1181693D02*
X1410414Y1181695D01*
G01X1410413Y1186700D02*
Y1186709D01*
G01X1410414Y1186695D02*
X1410413Y1186700D01*
G01X1410415Y1186693D02*
X1410414Y1186695D01*
G01X1410413Y1191700D02*
Y1191709D01*
G01X1410414Y1191695D02*
X1410413Y1191700D01*
G01X1410415Y1191693D02*
X1410414Y1191695D01*
G01X1410413Y1196700D02*
Y1196709D01*
G01X1410414Y1196695D02*
X1410413Y1196700D01*
G01X1410415Y1196693D02*
X1410414Y1196695D01*
G01X1411390Y1181837D02*
X1411398Y1181811D01*
G01X1411380Y1181863D02*
X1411390Y1181837D01*
G01X1411369Y1181890D02*
X1411380Y1181863D01*
G01X1411390Y1186837D02*
X1411398Y1186811D01*
G01X1411380Y1186863D02*
X1411390Y1186837D01*
G01X1411369Y1186890D02*
X1411380Y1186863D01*
G01X1411390Y1191837D02*
X1411398Y1191811D01*
G01X1411380Y1191863D02*
X1411390Y1191837D01*
G01X1411369Y1191890D02*
X1411380Y1191863D01*
G01X1411390Y1196837D02*
X1411398Y1196811D01*
G01X1411380Y1196863D02*
X1411390Y1196837D01*
G01X1411369Y1196890D02*
X1411380Y1196863D01*
G01X1409843Y1222185D02*
G03X1409252Y1222776I-591J0D01*
G01X1402559D02*
G03X1401969Y1222185I0J-590D01*
G01X1404724Y1221004D02*
G03Y1219035I0J-985D01*
G01X1407087D02*
G03Y1221004I0J985D01*
G01X1416732Y1221594D02*
G03X1414764Y1223563I-1968J1D01*
G01X1397047D02*
G03X1395079Y1221594I0J-1968D01*
G01X1403346Y1213091D02*
G03X1402165Y1211909I0J-1181D01*
G01X1409646D02*
G03X1408465Y1213091I-1181J1D01*
G01X1407795Y1207815D02*
G03I-1889J0D01*
G01X1408268D02*
G03I-2362J0D01*
G01X1404724Y1208406D02*
X1402414Y1212635D01*
G01X1407087Y1206713D02*
X1408390Y1204744D01*
G01X1400197Y1201004D02*
X1401378Y1199823D01*
G01X1395079Y1205846D02*
X1398425Y1202500D01*
G01X1414764Y1223563D02*
X1397047D01*
G01X1409252Y1222776D02*
X1402559D01*
G01X1407087Y1221004D02*
X1404724D01*
G01Y1219035D02*
X1407087D01*
G01X1409843Y1217657D02*
X1401969D01*
G01Y1216083D02*
X1409843D01*
G01X1416732Y1213130D02*
X1395079D01*
G01X1403346Y1213091D02*
X1408465D01*
G01X1404724Y1208406D02*
X1407087D01*
G01X1404724Y1206713D02*
X1407087D01*
G01X1398425Y1204744D02*
X1412795D01*
G01X1398425Y1203366D02*
X1402165D01*
G01X1412795D02*
X1409646D01*
G01X1398425Y1202500D02*
X1413386D01*
G01X1400197Y1201004D02*
X1408071D01*
G01X1401378Y1199823D02*
X1406890D01*
G01X1411398Y1197185D02*
X1410413D01*
G01X1410415Y1196693D02*
X1415748D01*
G01Y1196654D02*
X1411400D01*
G01X1415748Y1195315D02*
X1410415D01*
G01X1410413Y1194823D02*
X1411398D01*
G01Y1192185D02*
X1410413D01*
G01X1410415Y1191693D02*
X1415748D01*
G01Y1191654D02*
X1411400D01*
G01X1415748Y1190315D02*
X1410415D01*
G01X1410413Y1189823D02*
X1411398D01*
G01Y1187185D02*
X1410413D01*
G01X1410415Y1186693D02*
X1415748D01*
G01Y1186654D02*
X1411400D01*
G01X1415748Y1185315D02*
X1410415D01*
G01X1410413Y1184823D02*
X1411398D01*
G01Y1182185D02*
X1410413D01*
G01X1410415Y1181693D02*
X1415748D01*
G01Y1181654D02*
X1411400D01*
G01X1415748Y1180315D02*
X1410415D01*
G01X1410413Y1179823D02*
X1411398D01*
G01X1410413Y1196889D02*
X1411369Y1196890D01*
G01X1411398Y1195119D02*
X1410413Y1195118D01*
G01Y1191889D02*
X1411369Y1191890D01*
G01X1411398Y1190119D02*
X1410413Y1190118D01*
G01Y1186889D02*
X1411369Y1186890D01*
G01X1411398Y1185119D02*
X1410413Y1185118D01*
G01Y1181889D02*
X1411369Y1181890D01*
G01X1411398Y1180119D02*
X1410413Y1180118D01*
G01X1411398Y1181667D02*
Y1181676D01*
G01Y1186667D02*
Y1186676D01*
G01Y1191667D02*
Y1191676D01*
G01Y1196667D02*
Y1196676D01*
G01X1416732Y1205846D02*
Y1221594D01*
G01X1415748Y1195315D02*
Y1196693D01*
G01Y1190315D02*
Y1191693D01*
G01Y1185315D02*
Y1186693D01*
G01Y1180315D02*
Y1181693D01*
G01X1412579D02*
Y1180315D01*
G01Y1186693D02*
Y1185315D01*
G01Y1191693D02*
Y1190315D01*
G01Y1196693D02*
Y1195315D01*
G01X1411398Y1194823D02*
Y1197185D01*
G01Y1189823D02*
Y1192185D01*
G01Y1184823D02*
Y1187185D01*
G01Y1179823D02*
Y1182185D01*
G01Y1181667D02*
Y1181811D01*
G01Y1186667D02*
Y1186811D01*
G01Y1191667D02*
Y1191811D01*
G01Y1196667D02*
Y1196811D01*
G01X1410413Y1182185D02*
Y1179823D01*
G01Y1187185D02*
Y1184823D01*
G01Y1192185D02*
Y1189823D01*
G01Y1197185D02*
Y1194823D01*
G01X1409843Y1216083D02*
Y1222185D01*
G01X1409646Y1211909D02*
Y1203366D01*
G01X1407087Y1208406D02*
Y1206713D01*
G01X1404724D02*
Y1208406D01*
G01X1402165Y1203366D02*
Y1211909D01*
G01X1401969Y1216083D02*
Y1222185D01*
G01X1395079Y1221594D02*
Y1205846D01*
G01X1403421Y1204744D02*
X1404724Y1206713D01*
G01X1409397Y1212635D02*
X1407087Y1208406D01*
G01X1416732Y1205846D02*
X1413386Y1202500D01*
G01X1406890Y1199823D02*
X1408071Y1201004D01*
G01X1418913Y1841823D02*
Y1822886D01*
G01X1460138Y110551D02*
G03X1470178I5020J0D01*
G01D02*
G03X1460138I-5020J0D01*
G01X1460413Y80906D02*
G03X1469902I4745J0D01*
G01D02*
G03X1460413I-4744J0D01*
G01X1469902D02*
G03I-4744J0D01*
G01X1470177Y110551D02*
G03I-5019J0D01*
G01X1471260Y866929D02*
G03I-8268J0D01*
G01X1450256Y1658268D02*
X1919843D01*
G01X1442382D02*
G03X1450256I3937J0D01*
G01D02*
X1919843D01*
G01X1446319D02*
Y1657874D01*
G01Y1658268D02*
Y1658661D01*
G01X1445827Y1658268D02*
X1446811D01*
G01X1442382D02*
G03X1450256I3937J0D01*
G01X1519291Y139902D02*
G03X1521260Y137933I1969J0D01*
G01X1522638Y158996D02*
X1519291Y155650D01*
G01X1522638Y195787D02*
Y156752D01*
G01X1519291Y155650D02*
Y139902D01*
G01X1537598Y158996D02*
X1522638D01*
G01X1526378Y158130D02*
X1522638D01*
G01Y156752D02*
X1537008D01*
G01X1540945Y148366D02*
X1519291D01*
G01X1538976Y137933D02*
X1521260D01*
G01X1521204Y199114D02*
X1521198Y199094D01*
G01X1521218Y199129D02*
X1521204Y199114D01*
G01X1521238Y199134D02*
X1521218Y199129D01*
G01X1522178Y197972D02*
X1522183Y197992D01*
G01X1522164Y197958D02*
X1522178Y197972D01*
G01X1522144Y197953D02*
X1522164Y197958D01*
G01X1521204Y202264D02*
X1521198Y202244D01*
G01X1521218Y202278D02*
X1521204Y202264D01*
G01X1521238Y202283D02*
X1521218Y202278D01*
G01X1521204Y205413D02*
X1521198Y205394D01*
G01X1521218Y205428D02*
X1521204Y205413D01*
G01X1521238Y205433D02*
X1521218Y205428D01*
G01X1521204Y208563D02*
X1521198Y208543D01*
G01X1521218Y208578D02*
X1521204Y208563D01*
G01X1521238Y208583D02*
X1521218Y208578D01*
G01X1521204Y211713D02*
X1521198Y211693D01*
G01X1521218Y211727D02*
X1521204Y211713D01*
G01X1521238Y211732D02*
X1521218Y211727D01*
G01X1522178Y201122D02*
X1522183Y201142D01*
G01X1522164Y201108D02*
X1522178Y201122D01*
G01X1522144Y201102D02*
X1522164Y201108D01*
G01X1522178Y204272D02*
X1522183Y204291D01*
G01X1522164Y204257D02*
X1522178Y204272D01*
G01X1522144Y204252D02*
X1522164Y204257D01*
G01X1522178Y207421D02*
X1522183Y207441D01*
G01X1522164Y207407D02*
X1522178Y207421D01*
G01X1522144Y207402D02*
X1522164Y207407D01*
G01X1522178Y210571D02*
X1522183Y210591D01*
G01X1522164Y210557D02*
X1522178Y210571D01*
G01X1522144Y210551D02*
X1522164Y210557D01*
G01X1522163Y197945D02*
X1522166Y197947D01*
G01X1522159Y197944D02*
X1522163Y197945D01*
G01X1522156Y197943D02*
X1522159Y197944D01*
G01X1522153Y197942D02*
X1522156Y197943D01*
G01X1522149Y197942D02*
X1522153D01*
G01X1522146D02*
X1522149D01*
G01X1521223Y199142D02*
X1521220Y199140D01*
G01X1521226Y199143D02*
X1521223Y199142D01*
G01X1521230Y199144D02*
X1521226Y199143D01*
G01X1521233Y199144D02*
X1521230D01*
G01X1521237Y199145D02*
X1521233Y199144D01*
G01X1521240Y199145D02*
X1521237D01*
G01X1522163Y201095D02*
X1522166Y201096D01*
G01X1522159Y201094D02*
X1522163Y201095D01*
G01X1522156Y201093D02*
X1522159Y201094D01*
G01X1522153Y201092D02*
X1522156Y201093D01*
G01X1522149Y201091D02*
X1522153Y201092D01*
G01X1522146Y201091D02*
X1522149D01*
G01X1521223Y202291D02*
X1521220Y202290D01*
G01X1521226Y202293D02*
X1521223Y202291D01*
G01X1521230Y202294D02*
X1521226Y202293D01*
G01X1521233Y202294D02*
X1521230D01*
G01X1521237Y202295D02*
X1521233Y202294D01*
G01X1521240Y202295D02*
X1521237D01*
G01X1522163Y204244D02*
X1522166Y204246D01*
G01X1522159Y204243D02*
X1522163Y204244D01*
G01X1522156Y204242D02*
X1522159Y204243D01*
G01X1522153Y204241D02*
X1522156Y204242D01*
G01X1522149Y204241D02*
X1522153D01*
G01X1522146D02*
X1522149D01*
G01X1521223Y205441D02*
X1521220Y205439D01*
G01X1521226Y205442D02*
X1521223Y205441D01*
G01X1521230Y205443D02*
X1521226Y205442D01*
G01X1521233Y205444D02*
X1521230Y205443D01*
G01X1521237Y205444D02*
X1521233D01*
G01X1521240D02*
X1521237D01*
G01X1522163Y207394D02*
X1522166Y207396D01*
G01X1522159Y207393D02*
X1522163Y207394D01*
G01X1522156Y207392D02*
X1522159Y207393D01*
G01X1522153Y207391D02*
X1522156Y207392D01*
G01X1522149Y207391D02*
X1522153D01*
G01X1522146D02*
X1522149D01*
G01X1521223Y208591D02*
X1521220Y208589D01*
G01X1521226Y208592D02*
X1521223Y208591D01*
G01X1521230Y208593D02*
X1521226Y208592D01*
G01X1521233Y208593D02*
X1521230D01*
G01X1521237Y208594D02*
X1521233Y208593D01*
G01X1521240Y208594D02*
X1521237D01*
G01X1522163Y210544D02*
X1522166Y210545D01*
G01X1522159Y210543D02*
X1522163Y210544D01*
G01X1522156Y210541D02*
X1522159Y210543D01*
G01X1522153Y210541D02*
X1522156D01*
G01X1522149Y210540D02*
X1522153Y210541D01*
G01X1522146Y210540D02*
X1522149D01*
G01X1521223Y211740D02*
X1521220Y211739D01*
G01X1521226Y211741D02*
X1521223Y211740D01*
G01X1521230Y211743D02*
X1521226Y211741D01*
G01X1521233Y211743D02*
X1521230D01*
G01X1521237Y211744D02*
X1521233Y211743D01*
G01X1521240Y211744D02*
X1521237D01*
G01X1522176Y199132D02*
X1522180Y199127D01*
G01X1522171Y199137D02*
X1522176Y199132D01*
G01X1522165Y199141D02*
X1522171Y199137D01*
G01X1522159Y199143D02*
X1522165Y199141D01*
G01X1522152Y199145D02*
X1522159Y199143D01*
G01X1522146Y199145D02*
X1522152D01*
G01X1522176Y202282D02*
X1522180Y202277D01*
G01X1522171Y202286D02*
X1522176Y202282D01*
G01X1522165Y202290D02*
X1522171Y202286D01*
G01X1522159Y202293D02*
X1522165Y202290D01*
G01X1522152Y202294D02*
X1522159Y202293D01*
G01X1522146Y202295D02*
X1522152Y202294D01*
G01X1522176Y205431D02*
X1522180Y205426D01*
G01X1522171Y205436D02*
X1522176Y205431D01*
G01X1522165Y205440D02*
X1522171Y205436D01*
G01X1522159Y205442D02*
X1522165Y205440D01*
G01X1522152Y205444D02*
X1522159Y205442D01*
G01X1522146Y205444D02*
X1522152D01*
G01X1522176Y208581D02*
X1522180Y208576D01*
G01X1522171Y208585D02*
X1522176Y208581D01*
G01X1522165Y208589D02*
X1522171Y208585D01*
G01X1522159Y208592D02*
X1522165Y208589D01*
G01X1522152Y208594D02*
X1522159Y208592D01*
G01X1522146Y208594D02*
X1522152D01*
G01X1521202Y197971D02*
X1521201Y197979D01*
G01X1521204Y197965D02*
X1521202Y197971D01*
G01X1521207Y197958D02*
X1521204Y197965D01*
G01X1521212Y197952D02*
X1521207Y197958D01*
G01X1521219Y197948D02*
X1521212Y197952D01*
G01X1521225Y197944D02*
X1521219Y197948D01*
G01X1521233Y197943D02*
X1521225Y197944D01*
G01X1521240Y197942D02*
X1521233Y197943D01*
G01X1521202Y201121D02*
X1521201Y201128D01*
G01X1521204Y201114D02*
X1521202Y201121D01*
G01X1521207Y201108D02*
X1521204Y201114D01*
G01X1521212Y201102D02*
X1521207Y201108D01*
G01X1521219Y201097D02*
X1521212Y201102D01*
G01X1521225Y201094D02*
X1521219Y201097D01*
G01X1521233Y201092D02*
X1521225Y201094D01*
G01X1521240Y201091D02*
X1521233Y201092D01*
G01X1522176Y211731D02*
X1522180Y211726D01*
G01X1522171Y211735D02*
X1522176Y211731D01*
G01X1522165Y211739D02*
X1522171Y211735D01*
G01X1522159Y211741D02*
X1522165Y211739D01*
G01X1522152Y211743D02*
X1522159Y211741D01*
G01X1522146Y211744D02*
X1522152Y211743D01*
G01X1521202Y204270D02*
X1521201Y204278D01*
G01X1521204Y204264D02*
X1521202Y204270D01*
G01X1521207Y204257D02*
X1521204Y204264D01*
G01X1521212Y204252D02*
X1521207Y204257D01*
G01X1521219Y204247D02*
X1521212Y204252D01*
G01X1521225Y204244D02*
X1521219Y204247D01*
G01X1521233Y204242D02*
X1521225Y204244D01*
G01X1521240Y204241D02*
X1521233Y204242D01*
G01X1521202Y207420D02*
X1521201Y207428D01*
G01X1521204Y207413D02*
X1521202Y207420D01*
G01X1521207Y207407D02*
X1521204Y207413D01*
G01X1521212Y207401D02*
X1521207Y207407D01*
G01X1521219Y207396D02*
X1521212Y207401D01*
G01X1521225Y207393D02*
X1521219Y207396D01*
G01X1521233Y207391D02*
X1521225Y207393D01*
G01X1521240Y207391D02*
X1521233D01*
G01X1521202Y210570D02*
X1521201Y210577D01*
G01X1521204Y210563D02*
X1521202Y210570D01*
G01X1521207Y210557D02*
X1521204Y210563D01*
G01X1521212Y210551D02*
X1521207Y210557D01*
G01X1521219Y210546D02*
X1521212Y210551D01*
G01X1521225Y210543D02*
X1521219Y210546D01*
G01X1521233Y210541D02*
X1521225Y210543D01*
G01X1521240Y210540D02*
X1521233Y210541D01*
G01X1522155Y199133D02*
X1522164Y199128D01*
G01X1522144Y199134D02*
X1522155Y199133D01*
G01Y202282D02*
X1522164Y202278D01*
G01X1522144Y202283D02*
X1522155Y202282D01*
G01Y205432D02*
X1522164Y205428D01*
G01X1522144Y205433D02*
X1522155Y205432D01*
G01Y208581D02*
X1522164Y208577D01*
G01X1522144Y208583D02*
X1522155Y208581D01*
G01Y211731D02*
X1522164Y211727D01*
G01X1522144Y211732D02*
X1522155Y211731D01*
G01X1521201Y201132D02*
Y201128D01*
G01X1521202Y201126D02*
X1521201Y201132D01*
G01X1521214Y201111D02*
X1521202Y201126D01*
G01X1521239Y201102D02*
X1521214Y201111D01*
G01X1521201Y204282D02*
Y204278D01*
G01X1521202Y204276D02*
X1521201Y204282D01*
G01X1521214Y204260D02*
X1521202Y204276D01*
G01X1521238Y204252D02*
X1521214Y204260D01*
G01X1521201Y210581D02*
Y210577D01*
G01X1521202Y210575D02*
X1521201Y210581D01*
G01X1521214Y210559D02*
X1521202Y210575D01*
G01X1521238Y210551D02*
X1521214Y210559D01*
G01X1521201Y197983D02*
Y197979D01*
G01X1521202Y197976D02*
X1521201Y197983D01*
G01X1521214Y197961D02*
X1521202Y197976D01*
G01X1521238Y197953D02*
X1521214Y197961D01*
G01X1521201Y207431D02*
Y207428D01*
G01X1521202Y207426D02*
X1521201Y207431D01*
G01X1521212Y207411D02*
X1521202Y207426D01*
G01X1521235Y207402D02*
X1521212Y207411D01*
G01X1522154Y199133D02*
X1522144Y199134D01*
G01X1522163Y199130D02*
X1522154Y199133D01*
G01X1522170Y199124D02*
X1522163Y199130D01*
G01X1522154Y205432D02*
X1522144Y205433D01*
G01X1522162Y205429D02*
X1522154Y205432D01*
G01X1522170Y205424D02*
X1522162Y205429D01*
G01X1522154Y202282D02*
X1522144Y202283D01*
G01X1522163Y202279D02*
X1522154Y202282D01*
G01X1522170Y202274D02*
X1522163Y202279D01*
G01X1522154Y208581D02*
X1522144Y208583D01*
G01X1522163Y208578D02*
X1522154Y208581D01*
G01X1522170Y208573D02*
X1522163Y208578D01*
G01X1522154Y211731D02*
X1522144Y211732D01*
G01X1522163Y211728D02*
X1522154Y211731D01*
G01X1522170Y211723D02*
X1522163Y211728D01*
G01X1521240Y197948D02*
Y197942D01*
G01X1521239Y197952D02*
X1521240Y197948D01*
G01X1521238Y197953D02*
X1521239Y197952D01*
G01X1521240Y201098D02*
Y201091D01*
G01X1521239Y201101D02*
X1521240Y201098D01*
G01X1521238Y201102D02*
X1521239Y201101D01*
G01X1521240Y204247D02*
Y204241D01*
G01X1521239Y204251D02*
X1521240Y204247D01*
G01X1521238Y204252D02*
X1521239Y204251D01*
G01X1521240Y207397D02*
Y207391D01*
G01X1521239Y207400D02*
X1521240Y207397D01*
G01X1521238Y207402D02*
X1521239Y207400D01*
G01X1521240Y210546D02*
Y210540D01*
G01X1521239Y210550D02*
X1521240Y210546D01*
G01X1521238Y210551D02*
X1521239Y210550D01*
G01X1521224Y201105D02*
X1521238Y201102D01*
G01X1521212Y201112D02*
X1521224Y201105D01*
G01X1521200Y201131D02*
X1521212Y201112D01*
G01X1521224Y210554D02*
X1521238Y210551D01*
G01X1521212Y210561D02*
X1521224Y210554D01*
G01X1521200Y210580D02*
X1521212Y210561D01*
G01X1521223Y204255D02*
X1521238Y204252D01*
G01X1521211Y204263D02*
X1521223Y204255D01*
G01X1521199Y204283D02*
X1521211Y204263D01*
G01X1522185Y197986D02*
Y197979D01*
G01X1522184Y197991D02*
X1522185Y197986D01*
G01X1522183Y197992D02*
X1522184Y197991D01*
G01X1522185Y201136D02*
Y201128D01*
G01X1522184Y201141D02*
X1522185Y201136D01*
G01X1522183Y201142D02*
X1522184Y201141D01*
G01X1522185Y204285D02*
Y204278D01*
G01X1522184Y204290D02*
X1522185Y204285D01*
G01X1522183Y204291D02*
X1522184Y204290D01*
G01X1522185Y207435D02*
Y207428D01*
G01X1522184Y207440D02*
X1522185Y207435D01*
G01X1522183Y207441D02*
X1522184Y207440D01*
G01X1522185Y210585D02*
Y210577D01*
G01X1522184Y210589D02*
X1522185Y210585D01*
G01X1522183Y210591D02*
X1522184Y210589D01*
G01X1521223Y197956D02*
X1521238Y197953D01*
G01X1521210Y197964D02*
X1521223Y197956D01*
G01X1521199Y197985D02*
X1521210Y197964D01*
G01X1522184Y199115D02*
X1522185Y199108D01*
G01X1522183Y199121D02*
X1522184Y199115D01*
G01X1522180Y199127D02*
X1522183Y199121D01*
G01X1522184Y202265D02*
X1522185Y202258D01*
G01X1522183Y202271D02*
X1522184Y202265D01*
G01X1522180Y202277D02*
X1522183Y202271D01*
G01X1522184Y205414D02*
X1522185Y205407D01*
G01X1522183Y205420D02*
X1522184Y205414D01*
G01X1522180Y205426D02*
X1522183Y205420D01*
G01X1522184Y208564D02*
X1522185Y208557D01*
G01X1522183Y208570D02*
X1522184Y208564D01*
G01X1522180Y208576D02*
X1522183Y208570D01*
G01X1522184Y211713D02*
X1522185Y211707D01*
G01X1522183Y211720D02*
X1522184Y211713D01*
G01X1522180Y211726D02*
X1522183Y211720D01*
G01X1522146Y197948D02*
Y197942D01*
G01X1522145Y197952D02*
X1522146Y197948D01*
G01X1522144Y197953D02*
X1522145Y197952D01*
G01X1522146Y201097D02*
Y201091D01*
G01X1522145Y201101D02*
X1522146Y201097D01*
G01X1522144Y201102D02*
X1522145Y201101D01*
G01X1522146Y204247D02*
Y204241D01*
G01X1522145Y204251D02*
X1522146Y204247D01*
G01X1522144Y204252D02*
X1522145Y204251D01*
G01X1522146Y207396D02*
Y207391D01*
G01X1522145Y207400D02*
X1522146Y207396D01*
G01X1522144Y207402D02*
X1522145Y207400D01*
G01X1522146Y210546D02*
Y210540D01*
G01X1522145Y210550D02*
X1522146Y210546D01*
G01X1522144Y210551D02*
X1522145Y210550D01*
G01X1521219Y207407D02*
X1521238Y207402D01*
G01X1521205Y207419D02*
X1521219Y207407D01*
G01X1521198Y207437D02*
X1521205Y207419D01*
G01X1521200Y210585D02*
X1521201Y210577D01*
G01X1521200Y210589D02*
Y210585D01*
G01Y210580D02*
Y210589D01*
G01X1522178Y205415D02*
X1522170Y205424D01*
G01X1522182Y205405D02*
X1522178Y205415D01*
G01X1522184Y205394D02*
X1522182Y205405D01*
G01X1522178Y199116D02*
X1522170Y199124D01*
G01X1522182Y199106D02*
X1522178Y199116D01*
G01X1522184Y199094D02*
X1522182Y199106D01*
G01X1522178Y202265D02*
X1522170Y202274D01*
G01X1522182Y202255D02*
X1522178Y202265D01*
G01X1522184Y202244D02*
X1522182Y202255D01*
G01X1522178Y208565D02*
X1522170Y208573D01*
G01X1522182Y208554D02*
X1522178Y208565D01*
G01X1522184Y208543D02*
X1522182Y208554D01*
G01X1522178Y211714D02*
X1522170Y211723D01*
G01X1522182Y211704D02*
X1522178Y211714D01*
G01X1522184Y211693D02*
X1522182Y211704D01*
G01X1521241Y211917D02*
X1521240Y211929D01*
G01X1521238Y211904D02*
X1521241Y211917D01*
G01X1521238Y211890D02*
Y211904D01*
G01X1521241Y208767D02*
X1521240Y208780D01*
G01X1521238Y208754D02*
X1521241Y208767D01*
G01X1521238Y208741D02*
Y208754D01*
G01X1521241Y205618D02*
X1521240Y205630D01*
G01X1521238Y205605D02*
X1521241Y205618D01*
G01X1521238Y205591D02*
Y205605D01*
G01X1521241Y202468D02*
X1521240Y202480D01*
G01X1521238Y202455D02*
X1521241Y202468D01*
G01X1521238Y202441D02*
Y202455D01*
G01X1521241Y199319D02*
X1521240Y199331D01*
G01X1521238Y199306D02*
X1521241Y199319D01*
G01X1521238Y199292D02*
Y199306D01*
G01Y210380D02*
X1521237Y210393D01*
G01X1521241Y210367D02*
X1521238Y210380D01*
G01X1521240Y210354D02*
X1521241Y210367D01*
G01X1521238Y207230D02*
X1521237Y207244D01*
G01X1521241Y207217D02*
X1521238Y207230D01*
G01X1521240Y207205D02*
X1521241Y207217D01*
G01X1521238Y204081D02*
X1521237Y204094D01*
G01X1521241Y204068D02*
X1521238Y204081D01*
G01X1521240Y204055D02*
X1521241Y204068D01*
G01X1521238Y200931D02*
X1521237Y200944D01*
G01X1521241Y200918D02*
X1521238Y200931D01*
G01X1521240Y200906D02*
X1521241Y200918D01*
G01X1521238Y197781D02*
X1521237Y197795D01*
G01X1521241Y197769D02*
X1521238Y197781D01*
G01X1521240Y197756D02*
X1521241Y197769D01*
G01X1522148Y211904D02*
X1522149Y211890D01*
G01X1522145Y211917D02*
X1522148Y211904D01*
G01X1522146Y211929D02*
X1522145Y211917D01*
G01X1522148Y208754D02*
X1522149Y208741D01*
G01X1522145Y208767D02*
X1522148Y208754D01*
G01X1522146Y208780D02*
X1522145Y208767D01*
G01X1522148Y205604D02*
X1522149Y205591D01*
G01X1522145Y205617D02*
X1522148Y205604D01*
G01X1522146Y205630D02*
X1522145Y205617D01*
G01X1522148Y202455D02*
X1522149Y202441D01*
G01X1522145Y202468D02*
X1522148Y202455D01*
G01X1522146Y202480D02*
X1522145Y202468D01*
G01X1522148Y199305D02*
X1522149Y199292D01*
G01X1522145Y199318D02*
X1522148Y199305D01*
G01X1522146Y199331D02*
X1522145Y199318D01*
G01X1521200Y204285D02*
X1521201Y204278D01*
G01X1521200Y204290D02*
Y204285D01*
G01X1521199Y204283D02*
X1521200Y204290D01*
G01X1522145Y210367D02*
X1522146Y210354D01*
G01X1522148Y210380D02*
X1522145Y210367D01*
G01X1522149Y210393D02*
X1522148Y210380D01*
G01X1522145Y207217D02*
X1522146Y207205D01*
G01X1522148Y207230D02*
X1522145Y207217D01*
G01X1522149Y207244D02*
X1522148Y207230D01*
G01X1522145Y204068D02*
X1522146Y204055D01*
G01X1522148Y204081D02*
X1522145Y204068D01*
G01X1522149Y204094D02*
X1522148Y204081D01*
G01X1522145Y200918D02*
X1522146Y200906D01*
G01X1522148Y200931D02*
X1522145Y200918D01*
G01X1522149Y200944D02*
X1522148Y200931D01*
G01X1522145Y197769D02*
X1522146Y197756D01*
G01X1522148Y197781D02*
X1522145Y197769D01*
G01X1522149Y197795D02*
X1522148Y197781D01*
G01X1521200Y197987D02*
X1521201Y197979D01*
G01X1521200Y197991D02*
Y197987D01*
G01X1521199Y197985D02*
X1521200Y197991D01*
G01X1521214Y211724D02*
X1521238Y211732D01*
G01X1521202Y211709D02*
X1521214Y211724D01*
G01X1521201Y211703D02*
X1521202Y211709D01*
G01X1521214Y208574D02*
X1521238Y208583D01*
G01X1521202Y208560D02*
X1521214Y208574D01*
G01X1521201Y208553D02*
X1521202Y208560D01*
G01X1521214Y205425D02*
X1521238Y205433D01*
G01X1521202Y205410D02*
X1521214Y205425D01*
G01X1521201Y205404D02*
X1521202Y205410D01*
G01X1521214Y202275D02*
X1521238Y202283D01*
G01X1521202Y202261D02*
X1521214Y202275D01*
G01X1521201Y202254D02*
X1521202Y202261D01*
G01X1521214Y199126D02*
X1521238Y199134D01*
G01X1521202Y199111D02*
X1521214Y199126D01*
G01X1521201Y199104D02*
X1521202Y199111D01*
G01X1522185Y211699D02*
Y211706D01*
G01Y211695D02*
Y211699D01*
G01X1522184Y211693D02*
X1522185Y211695D01*
G01Y208550D02*
Y208557D01*
G01Y208545D02*
Y208550D01*
G01X1522184Y208543D02*
X1522185Y208545D01*
G01Y205400D02*
Y205407D01*
G01Y205396D02*
Y205400D01*
G01X1522184Y205394D02*
X1522185Y205396D01*
G01Y202250D02*
Y202257D01*
G01Y202246D02*
Y202250D01*
G01X1522184Y202244D02*
X1522185Y202246D01*
G01Y199101D02*
Y199108D01*
G01Y199096D02*
Y199101D01*
G01X1522184Y199094D02*
X1522185Y199096D01*
G01X1521200Y207435D02*
X1521201Y207428D01*
G01X1521200Y207440D02*
Y207435D01*
G01X1521198Y207437D02*
X1521200Y207440D01*
G01Y201136D02*
X1521201Y201128D01*
G01X1521200Y201141D02*
Y201136D01*
G01X1521198Y201138D02*
X1521200Y201141D01*
G01X1522146Y211737D02*
Y211744D01*
G01X1522145Y211734D02*
X1522146Y211737D01*
G01X1522144Y211732D02*
X1522145Y211734D01*
G01X1522146Y208588D02*
Y208594D01*
G01X1522145Y208584D02*
X1522146Y208588D01*
G01X1522144Y208583D02*
X1522145Y208584D01*
G01X1522146Y205438D02*
Y205444D01*
G01X1522145Y205435D02*
X1522146Y205438D01*
G01X1522144Y205433D02*
X1522145Y205435D01*
G01X1522146Y202289D02*
Y202295D01*
G01X1522145Y202285D02*
X1522146Y202289D01*
G01X1522144Y202283D02*
X1522145Y202285D01*
G01X1522146Y199139D02*
Y199145D01*
G01X1522145Y199135D02*
X1522146Y199139D01*
G01X1522144Y199134D02*
X1522145Y199135D01*
G01X1521200Y211699D02*
X1521201Y211707D01*
G01X1521200Y211694D02*
Y211699D01*
G01X1521198Y211693D02*
X1521200Y211694D01*
G01Y208550D02*
X1521201Y208557D01*
G01X1521200Y208545D02*
Y208550D01*
G01X1521198Y208543D02*
X1521200Y208545D01*
G01Y205400D02*
X1521201Y205407D01*
G01X1521200Y205395D02*
Y205400D01*
G01X1521198Y205394D02*
X1521200Y205395D01*
G01Y202250D02*
X1521201Y202258D01*
G01X1521200Y202246D02*
Y202250D01*
G01X1521198Y202244D02*
X1521200Y202246D01*
G01Y199101D02*
X1521201Y199108D01*
G01X1521200Y199096D02*
Y199101D01*
G01X1521198Y199094D02*
X1521200Y199096D01*
G01X1522183Y210565D02*
X1522185Y210577D01*
G01X1522176Y210554D02*
X1522183Y210565D01*
G01X1522166Y210545D02*
X1522176Y210554D01*
G01X1522183Y207415D02*
X1522185Y207428D01*
G01X1522176Y207404D02*
X1522183Y207415D01*
G01X1522166Y207396D02*
X1522176Y207404D01*
G01X1522183Y204265D02*
X1522185Y204278D01*
G01X1522176Y204254D02*
X1522183Y204265D01*
G01X1522166Y204246D02*
X1522176Y204254D01*
G01X1522183Y201116D02*
X1522185Y201128D01*
G01X1522176Y201105D02*
X1522183Y201116D01*
G01X1522166Y201096D02*
X1522176Y201105D01*
G01X1522183Y197966D02*
X1522185Y197979D01*
G01X1522176Y197955D02*
X1522183Y197966D01*
G01X1522166Y197947D02*
X1522176Y197955D01*
G01X1521239Y211737D02*
Y211744D01*
G01Y211733D02*
Y211737D01*
G01X1521237Y211732D02*
X1521239Y211733D01*
G01Y208588D02*
Y208594D01*
G01Y208584D02*
Y208588D01*
G01X1521237Y208583D02*
X1521239Y208584D01*
G01Y205438D02*
Y205444D01*
G01Y205434D02*
Y205438D01*
G01X1521237Y205433D02*
X1521239Y205434D01*
G01Y202289D02*
Y202295D01*
G01Y202285D02*
Y202289D01*
G01X1521237Y202283D02*
X1521239Y202285D01*
G01Y199139D02*
Y199145D01*
G01Y199135D02*
Y199139D01*
G01X1521237Y199134D02*
X1521239Y199135D01*
G01X1521202Y211713D02*
X1521201Y211707D01*
G01X1521203Y211719D02*
X1521202Y211713D01*
G01X1521206Y211725D02*
X1521203Y211719D01*
G01X1521210Y211730D02*
X1521206Y211725D01*
G01X1521215Y211735D02*
X1521210Y211730D01*
G01X1521220Y211739D02*
X1521215Y211735D01*
G01X1521202Y208563D02*
X1521201Y208557D01*
G01X1521203Y208570D02*
X1521202Y208563D01*
G01X1521206Y208575D02*
X1521203Y208570D01*
G01X1521210Y208581D02*
X1521206Y208575D01*
G01X1521215Y208585D02*
X1521210Y208581D01*
G01X1521220Y208589D02*
X1521215Y208585D01*
G01X1521202Y205414D02*
X1521201Y205407D01*
G01X1521203Y205420D02*
X1521202Y205414D01*
G01X1521206Y205426D02*
X1521203Y205420D01*
G01X1521210Y205431D02*
X1521206Y205426D01*
G01X1521215Y205435D02*
X1521210Y205431D01*
G01X1521220Y205439D02*
X1521215Y205435D01*
G01X1521202Y202264D02*
X1521201Y202258D01*
G01X1521203Y202270D02*
X1521202Y202264D01*
G01X1521206Y202276D02*
X1521203Y202270D01*
G01X1521210Y202281D02*
X1521206Y202276D01*
G01X1521215Y202286D02*
X1521210Y202281D01*
G01X1521220Y202290D02*
X1521215Y202286D01*
G01X1521202Y199115D02*
X1521201Y199108D01*
G01X1521203Y199121D02*
X1521202Y199115D01*
G01X1521206Y199126D02*
X1521203Y199121D01*
G01X1521210Y199132D02*
X1521206Y199126D01*
G01X1521215Y199136D02*
X1521210Y199132D01*
G01X1521220Y199140D02*
X1521215Y199136D01*
G01X1522156Y210553D02*
X1522144Y210551D01*
G01X1522167Y210558D02*
X1522156Y210553D01*
G01Y207404D02*
X1522144Y207402D01*
G01X1522167Y207409D02*
X1522156Y207404D01*
G01Y204254D02*
X1522144Y204252D01*
G01X1522167Y204259D02*
X1522156Y204254D01*
G01Y201104D02*
X1522144Y201102D01*
G01X1522167Y201109D02*
X1522156Y201104D01*
G01Y197955D02*
X1522144Y197953D01*
G01X1522167Y197960D02*
X1522156Y197955D01*
G01X1522185Y199097D02*
Y199108D01*
G01Y202246D02*
Y202257D01*
G01Y205396D02*
Y205407D01*
G01Y208546D02*
Y208557D01*
G01Y211695D02*
Y211706D01*
G01Y210394D02*
Y211890D01*
G01Y207244D02*
Y208740D01*
G01Y204094D02*
Y205591D01*
G01Y200945D02*
Y202441D01*
G01Y197795D02*
Y199291D01*
G01X1522146Y197942D02*
Y197795D01*
G01Y201091D02*
Y200944D01*
G01Y202441D02*
Y202295D01*
G01Y199292D02*
Y199145D01*
G01Y207391D02*
Y207244D01*
G01Y204241D02*
Y204094D01*
G01Y205591D02*
Y205444D01*
G01Y210540D02*
Y210393D01*
G01Y211890D02*
Y211744D01*
G01Y208741D02*
Y208594D01*
G01X1521240Y210393D02*
Y210540D01*
G01Y211744D02*
Y211891D01*
G01Y208594D02*
Y208741D01*
G01Y207243D02*
Y207391D01*
G01Y204094D02*
Y204241D01*
G01Y205444D02*
Y205591D01*
G01Y200944D02*
Y201091D01*
G01Y202295D02*
Y202442D01*
G01Y199145D02*
Y199292D01*
G01Y197794D02*
Y197942D01*
G01X1521201Y202441D02*
Y200945D01*
G01Y199291D02*
Y197795D01*
G01Y205591D02*
Y204094D01*
G01Y211890D02*
Y210394D01*
G01Y208740D02*
Y207244D01*
G01X1520020Y199134D02*
Y197953D01*
G01Y202283D02*
Y201102D01*
G01Y208583D02*
Y207402D01*
G01Y205433D02*
Y204252D01*
G01Y211732D02*
Y210551D01*
G01X1519685Y220197D02*
Y195787D01*
G01X1519291D02*
Y220197D01*
G01X1516260Y210551D02*
Y211732D01*
G01Y207402D02*
Y208583D01*
G01Y204252D02*
Y205433D01*
G01Y201102D02*
Y202283D01*
G01Y197953D02*
Y199134D01*
G01X1522185Y210577D02*
Y210588D01*
G01Y207428D02*
Y207439D01*
G01Y204278D02*
Y204289D01*
G01Y201128D02*
Y201139D01*
G01Y197979D02*
Y197990D01*
G01X1521198Y207437D02*
X1521087Y207441D01*
G01X1521198Y201138D02*
X1521087Y201142D01*
G01X1521198Y210587D02*
X1521087Y210591D01*
G01X1522146Y211929D02*
X1521240D01*
G01X1522185Y211890D02*
X1521201D01*
G01X1522144Y211732D02*
X1516260D01*
G01Y211693D02*
X1522184D01*
G01X1520454Y210591D02*
X1520020D01*
G01X1522183D02*
X1516260D01*
G01X1522144Y210551D02*
X1516260D01*
G01X1521201Y210394D02*
X1522185D01*
G01X1521240Y210354D02*
X1522146D01*
G01Y208780D02*
X1521240D01*
G01X1522185Y208740D02*
X1521201D01*
G01X1522144Y208583D02*
X1516260D01*
G01Y208543D02*
X1522184D01*
G01X1520454Y207441D02*
X1520020D01*
G01X1522183D02*
X1516260D01*
G01X1522144Y207402D02*
X1516260D01*
G01X1521201Y207244D02*
X1522185D01*
G01X1521240Y207205D02*
X1522146D01*
G01Y205630D02*
X1521240D01*
G01X1522185Y205591D02*
X1521201D01*
G01X1522144Y205433D02*
X1516260D01*
G01Y205394D02*
X1522184D01*
G01X1522183Y204291D02*
X1516260D01*
G01X1522144Y204252D02*
X1516260D01*
G01X1521201Y204094D02*
X1522185D01*
G01X1521240Y204055D02*
X1522146D01*
G01Y202480D02*
X1521240D01*
G01X1522185Y202441D02*
X1521201D01*
G01X1522144Y202283D02*
X1516260D01*
G01Y202244D02*
X1522184D01*
G01X1520454Y201142D02*
X1520020D01*
G01X1522183D02*
X1516260D01*
G01X1522144Y201102D02*
X1516260D01*
G01X1521201Y200945D02*
X1522185D01*
G01X1521240Y200906D02*
X1522146D01*
G01Y199331D02*
X1521240D01*
G01X1522185Y199291D02*
X1521201D01*
G01X1522144Y199134D02*
X1516260D01*
G01Y199094D02*
X1522184D01*
G01X1522183Y197992D02*
X1516260D01*
G01X1522144Y197953D02*
X1516260D01*
G01X1521201Y197795D02*
X1522185D01*
G01X1521240Y197756D02*
X1522146D01*
G01X1522638Y195787D02*
X1519291D01*
G01X1521204Y214862D02*
X1521198Y214843D01*
G01X1521218Y214877D02*
X1521204Y214862D01*
G01X1521238Y214882D02*
X1521218Y214877D01*
G01X1521204Y218012D02*
X1521198Y217992D01*
G01X1521218Y218026D02*
X1521204Y218012D01*
G01X1521238Y218031D02*
X1521218Y218026D01*
G01X1522178Y213720D02*
X1522183Y213740D01*
G01X1522164Y213706D02*
X1522178Y213720D01*
G01X1522144Y213701D02*
X1522164Y213706D01*
G01X1522178Y216870D02*
X1522183Y216890D01*
G01X1522164Y216856D02*
X1522178Y216870D01*
G01X1522144Y216850D02*
X1522164Y216856D01*
G01X1522184Y213719D02*
X1522185Y213727D01*
G01X1522182Y213713D02*
X1522184Y213719D01*
G01X1522178Y213706D02*
X1522182Y213713D01*
G01X1522174Y213700D02*
X1522178Y213706D01*
G01X1522167Y213696D02*
X1522174Y213700D01*
G01X1522161Y213693D02*
X1522167Y213696D01*
G01X1522153Y213691D02*
X1522161Y213693D01*
G01X1522146Y213690D02*
X1522153Y213691D01*
G01X1521223Y214890D02*
X1521220Y214888D01*
G01X1521226Y214891D02*
X1521223Y214890D01*
G01X1521230Y214892D02*
X1521226Y214891D01*
G01X1521233Y214893D02*
X1521230Y214892D01*
G01X1521237Y214893D02*
X1521233D01*
G01X1521240D02*
X1521237D01*
G01X1522163Y216843D02*
X1522166Y216844D01*
G01X1522159Y216842D02*
X1522163Y216843D01*
G01X1522156Y216841D02*
X1522159Y216842D01*
G01X1522153Y216840D02*
X1522156Y216841D01*
G01X1522149Y216839D02*
X1522153Y216840D01*
G01X1522146Y216839D02*
X1522149D01*
G01X1521223Y218039D02*
X1521220Y218038D01*
G01X1521226Y218041D02*
X1521223Y218039D01*
G01X1521230Y218042D02*
X1521226Y218041D01*
G01X1521233Y218042D02*
X1521230D01*
G01X1521237Y218043D02*
X1521233Y218042D01*
G01X1521240Y218043D02*
X1521237D01*
G01X1522176Y214880D02*
X1522180Y214875D01*
G01X1522171Y214885D02*
X1522176Y214880D01*
G01X1522165Y214889D02*
X1522171Y214885D01*
G01X1522159Y214891D02*
X1522165Y214889D01*
G01X1522152Y214893D02*
X1522159Y214891D01*
G01X1522146Y214893D02*
X1522152D01*
G01X1522176Y218030D02*
X1522180Y218025D01*
G01X1522171Y218034D02*
X1522176Y218030D01*
G01X1522165Y218038D02*
X1522171Y218034D01*
G01X1522159Y218041D02*
X1522165Y218038D01*
G01X1522152Y218043D02*
X1522159Y218041D01*
G01X1522146Y218043D02*
X1522152D01*
G01X1521202Y213719D02*
X1521201Y213727D01*
G01X1521204Y213713D02*
X1521202Y213719D01*
G01X1521207Y213706D02*
X1521204Y213713D01*
G01X1521212Y213700D02*
X1521207Y213706D01*
G01X1521219Y213696D02*
X1521212Y213700D01*
G01X1521225Y213693D02*
X1521219Y213696D01*
G01X1521233Y213691D02*
X1521225Y213693D01*
G01X1521240Y213690D02*
X1521233Y213691D01*
G01X1521202Y216869D02*
X1521201Y216876D01*
G01X1521204Y216862D02*
X1521202Y216869D01*
G01X1521207Y216856D02*
X1521204Y216862D01*
G01X1521212Y216850D02*
X1521207Y216856D01*
G01X1521219Y216845D02*
X1521212Y216850D01*
G01X1521225Y216842D02*
X1521219Y216845D01*
G01X1521233Y216840D02*
X1521225Y216842D01*
G01X1521240Y216839D02*
X1521233Y216840D01*
G01X1522155Y214881D02*
X1522164Y214876D01*
G01X1522144Y214882D02*
X1522155Y214881D01*
G01Y218030D02*
X1522164Y218026D01*
G01X1522144Y218031D02*
X1522155Y218030D01*
G01X1521201Y213731D02*
Y213727D01*
G01X1521202Y213724D02*
X1521201Y213731D01*
G01X1521214Y213709D02*
X1521202Y213724D01*
G01X1521238Y213701D02*
X1521214Y213709D01*
G01X1521201Y216880D02*
Y216876D01*
G01X1521202Y216874D02*
X1521201Y216880D01*
G01X1521214Y216859D02*
X1521202Y216874D01*
G01X1521238Y216850D02*
X1521214Y216859D01*
G01X1522154Y214881D02*
X1522144Y214882D01*
G01X1522163Y214878D02*
X1522154Y214881D01*
G01X1522170Y214872D02*
X1522163Y214878D01*
G01X1522154Y218030D02*
X1522144Y218031D01*
G01X1522163Y218027D02*
X1522154Y218030D01*
G01X1522170Y218022D02*
X1522163Y218027D01*
G01X1521240Y213696D02*
Y213690D01*
G01X1521239Y213700D02*
X1521240Y213696D01*
G01X1521238Y213701D02*
X1521239Y213700D01*
G01X1521240Y216846D02*
Y216839D01*
G01X1521239Y216849D02*
X1521240Y216846D01*
G01X1521238Y216850D02*
X1521239Y216849D01*
G01X1521223Y213704D02*
X1521238Y213701D01*
G01X1521211Y213711D02*
X1521223Y213704D01*
G01X1521199Y213731D02*
X1521211Y213711D01*
G01X1522185Y213734D02*
Y213727D01*
G01X1522184Y213739D02*
X1522185Y213734D01*
G01X1522183Y213740D02*
X1522184Y213739D01*
G01X1522185Y216884D02*
Y216876D01*
G01X1522184Y216889D02*
X1522185Y216884D01*
G01X1522183Y216890D02*
X1522184Y216889D01*
G01X1521223Y216853D02*
X1521238Y216850D01*
G01X1521211Y216861D02*
X1521223Y216853D01*
G01X1521199Y216881D02*
X1521211Y216861D01*
G01X1522184Y214863D02*
X1522185Y214856D01*
G01X1522183Y214869D02*
X1522184Y214863D01*
G01X1522180Y214875D02*
X1522183Y214869D01*
G01X1522184Y218013D02*
X1522185Y218006D01*
G01X1522183Y218019D02*
X1522184Y218013D01*
G01X1522180Y218025D02*
X1522183Y218019D01*
G01X1522146Y216845D02*
Y216839D01*
G01X1522145Y216849D02*
X1522146Y216845D01*
G01X1522144Y216850D02*
X1522145Y216849D01*
G01X1522178Y214864D02*
X1522170Y214872D01*
G01X1522182Y214854D02*
X1522178Y214864D01*
G01X1522184Y214843D02*
X1522182Y214854D01*
G01X1522178Y218013D02*
X1522170Y218022D01*
G01X1522182Y218003D02*
X1522178Y218013D01*
G01X1522184Y217992D02*
X1522182Y218003D01*
G01X1521241Y218216D02*
X1521240Y218228D01*
G01X1521238Y218203D02*
X1521241Y218216D01*
G01X1521238Y218189D02*
Y218203D01*
G01X1521241Y215067D02*
X1521240Y215079D01*
G01X1521238Y215054D02*
X1521241Y215067D01*
G01X1521238Y215040D02*
Y215054D01*
G01X1521200Y216884D02*
X1521201Y216876D01*
G01X1521200Y216889D02*
Y216884D01*
G01Y216881D02*
Y216889D01*
G01X1521238Y216679D02*
X1521237Y216693D01*
G01X1521241Y216666D02*
X1521238Y216679D01*
G01X1521240Y216654D02*
X1521241Y216666D01*
G01X1521238Y213530D02*
X1521237Y213543D01*
G01X1521241Y213517D02*
X1521238Y213530D01*
G01X1521240Y213504D02*
X1521241Y213517D01*
G01X1522148Y218203D02*
X1522149Y218189D01*
G01X1522145Y218216D02*
X1522148Y218203D01*
G01X1522146Y218228D02*
X1522145Y218216D01*
G01X1522148Y215053D02*
X1522149Y215040D01*
G01X1522145Y215066D02*
X1522148Y215053D01*
G01X1522146Y215079D02*
X1522145Y215066D01*
G01X1521200Y213734D02*
X1521201Y213727D01*
G01X1521200Y213739D02*
Y213734D01*
G01X1521199Y213732D02*
X1521200Y213739D01*
G01X1522145Y216666D02*
X1522146Y216654D01*
G01X1522148Y216679D02*
X1522145Y216666D01*
G01X1522149Y216693D02*
X1522148Y216679D01*
G01X1522145Y213517D02*
X1522146Y213504D01*
G01X1522148Y213530D02*
X1522145Y213517D01*
G01X1522149Y213543D02*
X1522148Y213530D01*
G01X1521214Y218023D02*
X1521238Y218031D01*
G01X1521202Y218009D02*
X1521214Y218023D01*
G01X1521201Y218002D02*
X1521202Y218009D01*
G01X1521214Y214874D02*
X1521238Y214882D01*
G01X1521202Y214859D02*
X1521214Y214874D01*
G01X1521201Y214852D02*
X1521202Y214859D01*
G01X1522185Y217998D02*
Y218006D01*
G01Y217994D02*
Y217998D01*
G01X1522184Y217992D02*
X1522185Y217994D01*
G01Y214849D02*
Y214856D01*
G01Y214844D02*
Y214849D01*
G01X1522184Y214843D02*
X1522185Y214844D01*
G01X1522146Y218037D02*
Y218043D01*
G01X1522145Y218033D02*
X1522146Y218037D01*
G01X1522144Y218031D02*
X1522145Y218033D01*
G01X1522146Y214887D02*
Y214893D01*
G01X1522145Y214883D02*
X1522146Y214887D01*
G01X1522144Y214882D02*
X1522145Y214883D01*
G01X1521200Y217998D02*
X1521201Y218006D01*
G01X1521200Y217994D02*
Y217998D01*
G01X1521198Y217992D02*
X1521200Y217994D01*
G01Y214849D02*
X1521201Y214856D01*
G01X1521200Y214844D02*
Y214849D01*
G01X1521198Y214843D02*
X1521200Y214844D01*
G01X1522183Y216864D02*
X1522185Y216876D01*
G01X1522176Y216853D02*
X1522183Y216864D01*
G01X1522166Y216844D02*
X1522176Y216853D01*
G01X1521239Y218037D02*
Y218043D01*
G01Y218033D02*
Y218037D01*
G01X1521237Y218031D02*
X1521239Y218033D01*
G01Y214887D02*
Y214893D01*
G01Y214883D02*
Y214887D01*
G01X1521237Y214882D02*
X1521239Y214883D01*
G01X1521202Y218012D02*
X1521201Y218006D01*
G01X1521203Y218019D02*
X1521202Y218012D01*
G01X1521206Y218024D02*
X1521203Y218019D01*
G01X1521210Y218030D02*
X1521206Y218024D01*
G01X1521215Y218034D02*
X1521210Y218030D01*
G01X1521220Y218038D02*
X1521215Y218034D01*
G01X1521202Y214863D02*
X1521201Y214856D01*
G01X1521203Y214869D02*
X1521202Y214863D01*
G01X1521206Y214874D02*
X1521203Y214869D01*
G01X1521210Y214880D02*
X1521206Y214874D01*
G01X1521215Y214884D02*
X1521210Y214880D01*
G01X1521220Y214888D02*
X1521215Y214884D01*
G01X1522156Y216852D02*
X1522144Y216850D01*
G01X1522167Y216857D02*
X1522156Y216852D01*
G01Y213703D02*
X1522144Y213701D01*
G01X1522167Y213708D02*
X1522156Y213703D01*
G01X1522185Y214845D02*
Y214856D01*
G01Y217994D02*
Y218006D01*
G01X1522638Y299232D02*
Y220197D01*
G01X1522185Y216693D02*
Y218189D01*
G01Y213543D02*
Y215039D01*
G01X1522146Y216839D02*
Y216693D01*
G01Y213690D02*
Y213543D01*
G01Y215040D02*
Y214893D01*
G01Y218189D02*
Y218043D01*
G01X1521240D02*
Y218190D01*
G01Y216692D02*
Y216839D01*
G01Y213543D02*
Y213690D01*
G01Y214893D02*
Y215040D01*
G01X1521201Y215039D02*
Y213543D01*
G01Y218189D02*
Y216693D01*
G01X1520020Y218031D02*
Y216850D01*
G01Y214882D02*
Y213701D01*
G01X1516260Y216850D02*
Y218031D01*
G01Y213701D02*
Y214882D01*
G01X1522185Y216876D02*
Y216887D01*
G01Y213727D02*
Y213738D01*
G01X1522144Y213701D02*
X1522148Y213690D01*
G01X1521087Y216890D02*
X1521199Y216881D01*
G01X1522638Y220197D02*
X1519291D01*
G01X1522146Y218228D02*
X1521240D01*
G01X1522185Y218189D02*
X1521201D01*
G01X1522144Y218031D02*
X1516260D01*
G01Y217992D02*
X1522184D01*
G01X1522183Y216890D02*
X1516260D01*
G01X1522144Y216850D02*
X1516260D01*
G01X1521201Y216693D02*
X1522185D01*
G01X1521240Y216654D02*
X1522146D01*
G01Y215079D02*
X1521240D01*
G01X1522185Y215039D02*
X1521201D01*
G01X1522144Y214882D02*
X1516260D01*
G01Y214843D02*
X1522184D01*
G01X1522183Y213740D02*
X1516260D01*
G01X1522144Y213701D02*
X1516260D01*
G01X1521201Y213543D02*
X1522185D01*
G01X1521240Y213504D02*
X1522146D01*
G01X1519291Y316083D02*
Y300335D01*
G01D02*
X1522638Y296988D01*
G01X1540945Y307618D02*
X1519291D01*
G01X1522638Y299232D02*
X1537008D01*
G01X1522638Y297854D02*
X1526378D01*
G01X1522638Y296988D02*
X1537598D01*
G01X1521260Y318051D02*
G03X1519291Y316083I0J-1969D01*
G01X1538976Y318051D02*
X1521260D01*
G01X1490157Y374803D02*
G03X1491339I591J0D01*
G01Y368504D02*
G03X1490157I-591J0D01*
G01X1488189D02*
G03X1487008I-591J0D01*
G01Y374803D02*
G03X1488189I591J0D01*
G01X1490157D02*
G03X1491339I591J0D01*
G01Y368504D02*
G03X1490157I-591J0D01*
G01X1488189D02*
G03X1487008I-591J0D01*
G01Y374803D02*
G03X1488189I591J0D01*
G01X1492126Y368504D02*
Y374803D01*
G01Y368504D02*
Y374803D01*
G01X1486220Y368504D02*
Y374803D01*
G01D02*
Y368504D01*
G01X1490157Y374803D02*
X1488189D01*
G01X1487008D02*
X1486220D01*
G01X1490157D02*
X1488189D01*
G01X1487008D02*
X1486220D01*
G01X1492126D02*
X1491339D01*
G01X1492126D02*
X1491339D01*
G01X1492126Y373819D02*
X1486220D01*
G01Y373622D02*
X1492126D01*
G01X1486220Y369685D02*
X1492126D01*
G01Y369488D02*
X1486220D01*
G01X1491339Y368504D02*
X1492126D01*
G01X1491339D02*
X1492126D01*
G01X1488189D02*
X1490157D01*
G01X1486220D02*
X1487008D01*
G01X1488189D02*
X1490157D01*
G01X1486220D02*
X1487008D01*
G01X1519291Y592657D02*
G03X1521260Y590689I1969J1D01*
G01X1519291Y608406D02*
Y592657D01*
G01X1538976Y590689D02*
X1521260D01*
G01X1522638Y648543D02*
Y609508D01*
G01Y611752D02*
X1519291Y608406D01*
G01X1537598Y611752D02*
X1522638D01*
G01X1526378Y610886D02*
X1522638D01*
G01Y609508D02*
X1537008D01*
G01X1540945Y601122D02*
X1519291D01*
G01X1521204Y651870D02*
X1521198Y651850D01*
G01X1521218Y651885D02*
X1521204Y651870D01*
G01X1521238Y651890D02*
X1521218Y651885D01*
G01X1521204Y655020D02*
X1521198Y655000D01*
G01X1521218Y655034D02*
X1521204Y655020D01*
G01X1521238Y655039D02*
X1521218Y655034D01*
G01X1521204Y658169D02*
X1521198Y658150D01*
G01X1521218Y658184D02*
X1521204Y658169D01*
G01X1521238Y658189D02*
X1521218Y658184D01*
G01X1521204Y661319D02*
X1521198Y661299D01*
G01X1521218Y661333D02*
X1521204Y661319D01*
G01X1521238Y661339D02*
X1521218Y661333D01*
G01X1521204Y664469D02*
X1521198Y664449D01*
G01X1521218Y664483D02*
X1521204Y664469D01*
G01X1521238Y664488D02*
X1521218Y664483D01*
G01X1522178Y650728D02*
X1522183Y650748D01*
G01X1522164Y650714D02*
X1522178Y650728D01*
G01X1522144Y650709D02*
X1522164Y650714D01*
G01X1522178Y653878D02*
X1522183Y653898D01*
G01X1522164Y653864D02*
X1522178Y653878D01*
G01X1522144Y653858D02*
X1522164Y653864D01*
G01X1522178Y657028D02*
X1522183Y657047D01*
G01X1522164Y657013D02*
X1522178Y657028D01*
G01X1522144Y657008D02*
X1522164Y657013D01*
G01X1522178Y660177D02*
X1522183Y660197D01*
G01X1522164Y660163D02*
X1522178Y660177D01*
G01X1522144Y660157D02*
X1522164Y660163D01*
G01X1522178Y663327D02*
X1522183Y663346D01*
G01X1522164Y663313D02*
X1522178Y663327D01*
G01X1522144Y663307D02*
X1522164Y663313D01*
G01X1521204Y667618D02*
X1521198Y667598D01*
G01X1521218Y667633D02*
X1521204Y667618D01*
G01X1521238Y667638D02*
X1521218Y667633D01*
G01X1521204Y670768D02*
X1521198Y670748D01*
G01X1521218Y670782D02*
X1521204Y670768D01*
G01X1521238Y670787D02*
X1521218Y670782D01*
G01X1522178Y666476D02*
X1522183Y666496D01*
G01X1522164Y666462D02*
X1522178Y666476D01*
G01X1522144Y666457D02*
X1522164Y666462D01*
G01X1522178Y669626D02*
X1522183Y669646D01*
G01X1522164Y669612D02*
X1522178Y669626D01*
G01X1522144Y669606D02*
X1522164Y669612D01*
G01X1522184Y666475D02*
X1522185Y666483D01*
G01X1522182Y666469D02*
X1522184Y666475D01*
G01X1522178Y666462D02*
X1522182Y666469D01*
G01X1522174Y666456D02*
X1522178Y666462D01*
G01X1522167Y666452D02*
X1522174Y666456D01*
G01X1522161Y666448D02*
X1522167Y666452D01*
G01X1522153Y666446D02*
X1522161Y666448D01*
G01X1522146Y666446D02*
X1522153D01*
G01X1522163Y650701D02*
X1522166Y650703D01*
G01X1522159Y650700D02*
X1522163Y650701D01*
G01X1522156Y650699D02*
X1522159Y650700D01*
G01X1522153Y650698D02*
X1522156Y650699D01*
G01X1522149Y650698D02*
X1522153D01*
G01X1522146D02*
X1522149D01*
G01X1521223Y651898D02*
X1521220Y651896D01*
G01X1521226Y651899D02*
X1521223Y651898D01*
G01X1521230Y651900D02*
X1521226Y651899D01*
G01X1521233Y651900D02*
X1521230D01*
G01X1521237Y651901D02*
X1521233Y651900D01*
G01X1521240Y651901D02*
X1521237D01*
G01X1522163Y653851D02*
X1522166Y653852D01*
G01X1522159Y653850D02*
X1522163Y653851D01*
G01X1522156Y653848D02*
X1522159Y653850D01*
G01X1522153Y653848D02*
X1522156D01*
G01X1522149Y653847D02*
X1522153Y653848D01*
G01X1522146Y653847D02*
X1522149D01*
G01X1521223Y655047D02*
X1521220Y655046D01*
G01X1521226Y655048D02*
X1521223Y655047D01*
G01X1521230Y655050D02*
X1521226Y655048D01*
G01X1521233Y655050D02*
X1521230D01*
G01X1521237Y655051D02*
X1521233Y655050D01*
G01X1521240Y655051D02*
X1521237D01*
G01X1522163Y657000D02*
X1522166Y657002D01*
G01X1522159Y656999D02*
X1522163Y657000D01*
G01X1522156Y656998D02*
X1522159Y656999D01*
G01X1522153Y656997D02*
X1522156Y656998D01*
G01X1522149Y656997D02*
X1522153D01*
G01X1522146D02*
X1522149D01*
G01X1521223Y658197D02*
X1521220Y658195D01*
G01X1521226Y658198D02*
X1521223Y658197D01*
G01X1521230Y658199D02*
X1521226Y658198D01*
G01X1521233Y658200D02*
X1521230Y658199D01*
G01X1521237Y658200D02*
X1521233D01*
G01X1521240D02*
X1521237D01*
G01X1522163Y660150D02*
X1522166Y660152D01*
G01X1522159Y660149D02*
X1522163Y660150D01*
G01X1522156Y660148D02*
X1522159Y660149D01*
G01X1522153Y660147D02*
X1522156Y660148D01*
G01X1522149Y660146D02*
X1522153Y660147D01*
G01X1522146Y660146D02*
X1522149D01*
G01X1521223Y661346D02*
X1521220Y661345D01*
G01X1521226Y661348D02*
X1521223Y661346D01*
G01X1521230Y661349D02*
X1521226Y661348D01*
G01X1521233Y661349D02*
X1521230D01*
G01X1521237Y661350D02*
X1521233Y661349D01*
G01X1521240Y661350D02*
X1521237D01*
G01X1522163Y663300D02*
X1522166Y663301D01*
G01X1522159Y663298D02*
X1522163Y663300D01*
G01X1522156Y663297D02*
X1522159Y663298D01*
G01X1522153Y663296D02*
X1522156Y663297D01*
G01X1522149Y663296D02*
X1522153D01*
G01X1522146D02*
X1522149D01*
G01X1521223Y664496D02*
X1521220Y664494D01*
G01X1521226Y664497D02*
X1521223Y664496D01*
G01X1521230Y664498D02*
X1521226Y664497D01*
G01X1521233Y664499D02*
X1521230Y664498D01*
G01X1521237Y664500D02*
X1521233Y664499D01*
G01X1521240Y664500D02*
X1521237D01*
G01X1521223Y667646D02*
X1521220Y667644D01*
G01X1521226Y667647D02*
X1521223Y667646D01*
G01X1521230Y667648D02*
X1521226Y667647D01*
G01X1521233Y667648D02*
X1521230D01*
G01X1521237Y667649D02*
X1521233Y667648D01*
G01X1521240Y667649D02*
X1521237D01*
G01X1522163Y669599D02*
X1522166Y669600D01*
G01X1522159Y669598D02*
X1522163Y669599D01*
G01X1522156Y669596D02*
X1522159Y669598D01*
G01X1522153Y669596D02*
X1522156D01*
G01X1522149Y669595D02*
X1522153Y669596D01*
G01X1522146Y669595D02*
X1522149D01*
G01X1521223Y670795D02*
X1521220Y670794D01*
G01X1521226Y670796D02*
X1521223Y670795D01*
G01X1521230Y670798D02*
X1521226Y670796D01*
G01X1521233Y670798D02*
X1521230D01*
G01X1521237Y670799D02*
X1521233Y670798D01*
G01X1521240Y670799D02*
X1521237D01*
G01X1522176Y651888D02*
X1522180Y651883D01*
G01X1522171Y651893D02*
X1522176Y651888D01*
G01X1522165Y651896D02*
X1522171Y651893D01*
G01X1522159Y651899D02*
X1522165Y651896D01*
G01X1522152Y651901D02*
X1522159Y651899D01*
G01X1522146Y651901D02*
X1522152D01*
G01X1522176Y655038D02*
X1522180Y655033D01*
G01X1522171Y655042D02*
X1522176Y655038D01*
G01X1522165Y655046D02*
X1522171Y655042D01*
G01X1522159Y655048D02*
X1522165Y655046D01*
G01X1522152Y655050D02*
X1522159Y655048D01*
G01X1522146Y655051D02*
X1522152Y655050D01*
G01X1522176Y658187D02*
X1522180Y658182D01*
G01X1522171Y658192D02*
X1522176Y658187D01*
G01X1522165Y658196D02*
X1522171Y658192D01*
G01X1522159Y658198D02*
X1522165Y658196D01*
G01X1522152Y658200D02*
X1522159Y658198D01*
G01X1522146Y658200D02*
X1522152D01*
G01X1521202Y650727D02*
X1521201Y650735D01*
G01X1521204Y650720D02*
X1521202Y650727D01*
G01X1521207Y650714D02*
X1521204Y650720D01*
G01X1521212Y650708D02*
X1521207Y650714D01*
G01X1521219Y650704D02*
X1521212Y650708D01*
G01X1521225Y650700D02*
X1521219Y650704D01*
G01X1521233Y650698D02*
X1521225Y650700D01*
G01X1521240Y650698D02*
X1521233D01*
G01X1522176Y661337D02*
X1522180Y661332D01*
G01X1522171Y661341D02*
X1522176Y661337D01*
G01X1522165Y661345D02*
X1522171Y661341D01*
G01X1522159Y661348D02*
X1522165Y661345D01*
G01X1522152Y661350D02*
X1522159Y661348D01*
G01X1522146Y661350D02*
X1522152D01*
G01X1522176Y664487D02*
X1522180Y664481D01*
G01X1522171Y664491D02*
X1522176Y664487D01*
G01X1522165Y664495D02*
X1522171Y664491D01*
G01X1522159Y664497D02*
X1522165Y664495D01*
G01X1522152Y664499D02*
X1522159Y664497D01*
G01X1522146Y664500D02*
X1522152Y664499D01*
G01X1522176Y667636D02*
X1522180Y667631D01*
G01X1522171Y667641D02*
X1522176Y667636D01*
G01X1522165Y667644D02*
X1522171Y667641D01*
G01X1522159Y667647D02*
X1522165Y667644D01*
G01X1522152Y667649D02*
X1522159Y667647D01*
G01X1522146Y667649D02*
X1522152D01*
G01X1522176Y670786D02*
X1522180Y670781D01*
G01X1522171Y670790D02*
X1522176Y670786D01*
G01X1522165Y670794D02*
X1522171Y670790D01*
G01X1522159Y670796D02*
X1522165Y670794D01*
G01X1522152Y670798D02*
X1522159Y670796D01*
G01X1522146Y670799D02*
X1522152Y670798D01*
G01X1521202Y653877D02*
X1521201Y653884D01*
G01X1521204Y653870D02*
X1521202Y653877D01*
G01X1521207Y653864D02*
X1521204Y653870D01*
G01X1521212Y653858D02*
X1521207Y653864D01*
G01X1521219Y653853D02*
X1521212Y653858D01*
G01X1521225Y653850D02*
X1521219Y653853D01*
G01X1521233Y653848D02*
X1521225Y653850D01*
G01X1521240Y653847D02*
X1521233Y653848D01*
G01X1521202Y657026D02*
X1521201Y657034D01*
G01X1521204Y657020D02*
X1521202Y657026D01*
G01X1521207Y657013D02*
X1521204Y657020D01*
G01X1521212Y657007D02*
X1521207Y657013D01*
G01X1521219Y657003D02*
X1521212Y657007D01*
G01X1521225Y657000D02*
X1521219Y657003D01*
G01X1521233Y656998D02*
X1521225Y657000D01*
G01X1521240Y656997D02*
X1521233Y656998D01*
G01X1521202Y660176D02*
X1521201Y660183D01*
G01X1521204Y660169D02*
X1521202Y660176D01*
G01X1521207Y660163D02*
X1521204Y660169D01*
G01X1521212Y660157D02*
X1521207Y660163D01*
G01X1521219Y660152D02*
X1521212Y660157D01*
G01X1521225Y660149D02*
X1521219Y660152D01*
G01X1521233Y660147D02*
X1521225Y660149D01*
G01X1521240Y660146D02*
X1521233Y660147D01*
G01X1521202Y663326D02*
X1521201Y663333D01*
G01X1521204Y663319D02*
X1521202Y663326D01*
G01X1521207Y663313D02*
X1521204Y663319D01*
G01X1521212Y663307D02*
X1521207Y663313D01*
G01X1521219Y663302D02*
X1521212Y663307D01*
G01X1521225Y663299D02*
X1521219Y663302D01*
G01X1521233Y663297D02*
X1521225Y663299D01*
G01X1521240Y663296D02*
X1521233Y663297D01*
G01X1521202Y666475D02*
X1521201Y666483D01*
G01X1521204Y666469D02*
X1521202Y666475D01*
G01X1521207Y666462D02*
X1521204Y666469D01*
G01X1521212Y666456D02*
X1521207Y666462D01*
G01X1521219Y666452D02*
X1521212Y666456D01*
G01X1521225Y666448D02*
X1521219Y666452D01*
G01X1521233Y666446D02*
X1521225Y666448D01*
G01X1521240Y666446D02*
X1521233D01*
G01X1521202Y669625D02*
X1521201Y669632D01*
G01X1521204Y669618D02*
X1521202Y669625D01*
G01X1521207Y669612D02*
X1521204Y669618D01*
G01X1521212Y669606D02*
X1521207Y669612D01*
G01X1521219Y669601D02*
X1521212Y669606D01*
G01X1521225Y669598D02*
X1521219Y669601D01*
G01X1521233Y669596D02*
X1521225Y669598D01*
G01X1521240Y669595D02*
X1521233Y669596D01*
G01X1522155Y651889D02*
X1522164Y651884D01*
G01X1522144Y651890D02*
X1522155Y651889D01*
G01Y655038D02*
X1522164Y655034D01*
G01X1522144Y655039D02*
X1522155Y655038D01*
G01Y658188D02*
X1522164Y658183D01*
G01X1522144Y658189D02*
X1522155Y658188D01*
G01Y661337D02*
X1522164Y661333D01*
G01X1522144Y661339D02*
X1522155Y661337D01*
G01Y664487D02*
X1522164Y664483D01*
G01X1522144Y664488D02*
X1522155Y664487D01*
G01Y667637D02*
X1522164Y667632D01*
G01X1522144Y667638D02*
X1522155Y667637D01*
G01Y670786D02*
X1522164Y670782D01*
G01X1522144Y670787D02*
X1522155Y670786D01*
G01X1521201Y653888D02*
Y653884D01*
G01X1521202Y653882D02*
X1521201Y653888D01*
G01X1521214Y653867D02*
X1521202Y653882D01*
G01X1521239Y653858D02*
X1521214Y653867D01*
G01X1521201Y657038D02*
Y657034D01*
G01X1521202Y657031D02*
X1521201Y657038D01*
G01X1521214Y657016D02*
X1521202Y657031D01*
G01X1521238Y657008D02*
X1521214Y657016D01*
G01X1521201Y663337D02*
Y663333D01*
G01X1521202Y663331D02*
X1521201Y663337D01*
G01X1521214Y663315D02*
X1521202Y663331D01*
G01X1521238Y663307D02*
X1521214Y663315D01*
G01X1521201Y666487D02*
Y666483D01*
G01X1521202Y666480D02*
X1521201Y666487D01*
G01X1521214Y666465D02*
X1521202Y666480D01*
G01X1521238Y666457D02*
X1521214Y666465D01*
G01X1521201Y650739D02*
Y650735D01*
G01X1521202Y650732D02*
X1521201Y650739D01*
G01X1521214Y650717D02*
X1521202Y650732D01*
G01X1521238Y650709D02*
X1521214Y650717D01*
G01X1521201Y669636D02*
Y669632D01*
G01X1521202Y669630D02*
X1521201Y669636D01*
G01X1521214Y669615D02*
X1521202Y669630D01*
G01X1521238Y669606D02*
X1521214Y669615D01*
G01X1521201Y660187D02*
Y660183D01*
G01X1521202Y660182D02*
X1521201Y660187D01*
G01X1521212Y660167D02*
X1521202Y660182D01*
G01X1521235Y660158D02*
X1521212Y660167D01*
G01X1522154Y658188D02*
X1522144Y658189D01*
G01X1522162Y658185D02*
X1522154Y658188D01*
G01X1522170Y658180D02*
X1522162Y658185D01*
G01X1522154Y651889D02*
X1522144Y651890D01*
G01X1522163Y651885D02*
X1522154Y651889D01*
G01X1522170Y651880D02*
X1522163Y651885D01*
G01X1522154Y655038D02*
X1522144Y655039D01*
G01X1522163Y655035D02*
X1522154Y655038D01*
G01X1522170Y655030D02*
X1522163Y655035D01*
G01X1522154Y661337D02*
X1522144Y661339D01*
G01X1522163Y661334D02*
X1522154Y661337D01*
G01X1522170Y661329D02*
X1522163Y661334D01*
G01X1522154Y664487D02*
X1522144Y664488D01*
G01X1522163Y664484D02*
X1522154Y664487D01*
G01X1522170Y664479D02*
X1522163Y664484D01*
G01X1522154Y667637D02*
X1522144Y667638D01*
G01X1522163Y667633D02*
X1522154Y667637D01*
G01X1522170Y667628D02*
X1522163Y667633D01*
G01X1522154Y670786D02*
X1522144Y670787D01*
G01X1522163Y670783D02*
X1522154Y670786D01*
G01X1522170Y670778D02*
X1522163Y670783D01*
G01X1521240Y650704D02*
Y650698D01*
G01X1521239Y650707D02*
X1521240Y650704D01*
G01X1521238Y650709D02*
X1521239Y650707D01*
G01X1521240Y653854D02*
Y653847D01*
G01X1521239Y653857D02*
X1521240Y653854D01*
G01X1521238Y653858D02*
X1521239Y653857D01*
G01X1521240Y657003D02*
Y656997D01*
G01X1521239Y657007D02*
X1521240Y657003D01*
G01X1521238Y657008D02*
X1521239Y657007D01*
G01X1521240Y660153D02*
Y660146D01*
G01X1521239Y660156D02*
X1521240Y660153D01*
G01X1521238Y660157D02*
X1521239Y660156D01*
G01X1521240Y663302D02*
Y663296D01*
G01X1521239Y663306D02*
X1521240Y663302D01*
G01X1521238Y663307D02*
X1521239Y663306D01*
G01X1521240Y666452D02*
Y666446D01*
G01X1521239Y666456D02*
X1521240Y666452D01*
G01X1521238Y666457D02*
X1521239Y666456D01*
G01X1521240Y669602D02*
Y669595D01*
G01X1521239Y669605D02*
X1521240Y669602D01*
G01X1521238Y669606D02*
X1521239Y669605D01*
G01X1522156Y669608D02*
X1522144Y669606D01*
G01X1522167Y669613D02*
X1522156Y669608D01*
G01Y666459D02*
X1522144Y666457D01*
G01X1522167Y666464D02*
X1522156Y666459D01*
G01Y663309D02*
X1522144Y663307D01*
G01X1522167Y663314D02*
X1522156Y663309D01*
G01Y660159D02*
X1522144Y660157D01*
G01X1522167Y660165D02*
X1522156Y660159D01*
G01Y657010D02*
X1522144Y657008D01*
G01X1522167Y657015D02*
X1522156Y657010D01*
G01Y653860D02*
X1522144Y653858D01*
G01X1522167Y653865D02*
X1522156Y653860D01*
G01Y650711D02*
X1522144Y650709D01*
G01X1522167Y650716D02*
X1522156Y650711D01*
G01X1522183Y669620D02*
X1522185Y669632D01*
G01X1522176Y669609D02*
X1522183Y669620D01*
G01X1522166Y669600D02*
X1522176Y669609D01*
G01X1522183Y663320D02*
X1522185Y663333D01*
G01X1522176Y663309D02*
X1522183Y663320D01*
G01X1522166Y663301D02*
X1522176Y663309D01*
G01X1522183Y660171D02*
X1522185Y660183D01*
G01X1522176Y660160D02*
X1522183Y660171D01*
G01X1522166Y660152D02*
X1522176Y660160D01*
G01X1522183Y657021D02*
X1522185Y657034D01*
G01X1522176Y657010D02*
X1522183Y657021D01*
G01X1522166Y657002D02*
X1522176Y657010D01*
G01X1522183Y653872D02*
X1522185Y653884D01*
G01X1522176Y653861D02*
X1522183Y653872D01*
G01X1522166Y653852D02*
X1522176Y653861D01*
G01X1522183Y650722D02*
X1522185Y650735D01*
G01X1522176Y650711D02*
X1522183Y650722D01*
G01X1522166Y650703D02*
X1522176Y650711D01*
G01X1521239Y670793D02*
Y670799D01*
G01Y670789D02*
Y670793D01*
G01X1521237Y670787D02*
X1521239Y670789D01*
G01Y667643D02*
Y667649D01*
G01Y667639D02*
Y667643D01*
G01X1521237Y667638D02*
X1521239Y667639D01*
G01Y664493D02*
Y664500D01*
G01Y664489D02*
Y664493D01*
G01X1521237Y664488D02*
X1521239Y664489D01*
G01Y661344D02*
Y661350D01*
G01Y661340D02*
Y661344D01*
G01X1521237Y661339D02*
X1521239Y661340D01*
G01Y658194D02*
Y658200D01*
G01Y658190D02*
Y658194D01*
G01X1521237Y658189D02*
X1521239Y658190D01*
G01Y655044D02*
Y655051D01*
G01Y655041D02*
Y655044D01*
G01X1521237Y655039D02*
X1521239Y655041D01*
G01Y651895D02*
Y651901D01*
G01Y651891D02*
Y651895D01*
G01X1521237Y651890D02*
X1521239Y651891D01*
G01X1521202Y670768D02*
X1521201Y670762D01*
G01X1521203Y670774D02*
X1521202Y670768D01*
G01X1521206Y670780D02*
X1521203Y670774D01*
G01X1521210Y670785D02*
X1521206Y670780D01*
G01X1521215Y670790D02*
X1521210Y670785D01*
G01X1521220Y670794D02*
X1521215Y670790D01*
G01X1521202Y667619D02*
X1521201Y667612D01*
G01X1521203Y667625D02*
X1521202Y667619D01*
G01X1521206Y667630D02*
X1521203Y667625D01*
G01X1521210Y667636D02*
X1521206Y667630D01*
G01X1521215Y667640D02*
X1521210Y667636D01*
G01X1521220Y667644D02*
X1521215Y667640D01*
G01X1521202Y664469D02*
X1521201Y664463D01*
G01X1521203Y664475D02*
X1521202Y664469D01*
G01X1521206Y664481D02*
X1521203Y664475D01*
G01X1521210Y664486D02*
X1521206Y664481D01*
G01X1521215Y664491D02*
X1521210Y664486D01*
G01X1521220Y664494D02*
X1521215Y664491D01*
G01X1521202Y661319D02*
X1521201Y661313D01*
G01X1521203Y661326D02*
X1521202Y661319D01*
G01X1521206Y661331D02*
X1521203Y661326D01*
G01X1521210Y661337D02*
X1521206Y661331D01*
G01X1521215Y661341D02*
X1521210Y661337D01*
G01X1521220Y661345D02*
X1521215Y661341D01*
G01X1521202Y658170D02*
X1521201Y658163D01*
G01X1521203Y658176D02*
X1521202Y658170D01*
G01X1521206Y658181D02*
X1521203Y658176D01*
G01X1521210Y658187D02*
X1521206Y658181D01*
G01X1521215Y658191D02*
X1521210Y658187D01*
G01X1521220Y658195D02*
X1521215Y658191D01*
G01X1521202Y655020D02*
X1521201Y655014D01*
G01X1521203Y655026D02*
X1521202Y655020D01*
G01X1521206Y655032D02*
X1521203Y655026D01*
G01X1521210Y655037D02*
X1521206Y655032D01*
G01X1521215Y655042D02*
X1521210Y655037D01*
G01X1521220Y655046D02*
X1521215Y655042D01*
G01X1521202Y651870D02*
X1521201Y651864D01*
G01X1521203Y651877D02*
X1521202Y651870D01*
G01X1521206Y651882D02*
X1521203Y651877D01*
G01X1521210Y651888D02*
X1521206Y651882D01*
G01X1521215Y651892D02*
X1521210Y651888D01*
G01X1521220Y651896D02*
X1521215Y651892D01*
G01X1521224Y653861D02*
X1521238Y653858D01*
G01X1521212Y653868D02*
X1521224Y653861D01*
G01X1521200Y653887D02*
X1521212Y653868D01*
G01X1521224Y663310D02*
X1521238Y663307D01*
G01X1521212Y663317D02*
X1521224Y663310D01*
G01X1521200Y663335D02*
X1521212Y663317D01*
G01X1521223Y657011D02*
X1521238Y657008D01*
G01X1521211Y657019D02*
X1521223Y657011D01*
G01X1521199Y657039D02*
X1521211Y657019D01*
G01X1521223Y666459D02*
X1521238Y666457D01*
G01X1521211Y666467D02*
X1521223Y666459D01*
G01X1521199Y666487D02*
X1521211Y666467D01*
G01X1522185Y650742D02*
Y650735D01*
G01X1522184Y650747D02*
X1522185Y650742D01*
G01X1522183Y650748D02*
X1522184Y650747D01*
G01X1522185Y653892D02*
Y653884D01*
G01X1522184Y653896D02*
X1522185Y653892D01*
G01X1522183Y653898D02*
X1522184Y653896D01*
G01X1522185Y657041D02*
Y657034D01*
G01X1522184Y657046D02*
X1522185Y657041D01*
G01X1522183Y657047D02*
X1522184Y657046D01*
G01X1522185Y660191D02*
Y660183D01*
G01X1522184Y660196D02*
X1522185Y660191D01*
G01X1522183Y660197D02*
X1522184Y660196D01*
G01X1522185Y663341D02*
Y663333D01*
G01X1522184Y663345D02*
X1522185Y663341D01*
G01X1522183Y663346D02*
X1522184Y663345D01*
G01X1522185Y666490D02*
Y666483D01*
G01X1522184Y666495D02*
X1522185Y666490D01*
G01X1522183Y666496D02*
X1522184Y666495D01*
G01X1522185Y669640D02*
Y669632D01*
G01X1522184Y669644D02*
X1522185Y669640D01*
G01X1522183Y669646D02*
X1522184Y669644D01*
G01X1521223Y669609D02*
X1521238Y669606D01*
G01X1521211Y669617D02*
X1521223Y669609D01*
G01X1521199Y669637D02*
X1521211Y669617D01*
G01X1521223Y650712D02*
X1521238Y650709D01*
G01X1521210Y650720D02*
X1521223Y650712D01*
G01X1521199Y650741D02*
X1521210Y650720D01*
G01X1522184Y651871D02*
X1522185Y651864D01*
G01X1522183Y651877D02*
X1522184Y651871D01*
G01X1522180Y651883D02*
X1522183Y651877D01*
G01X1522184Y655020D02*
X1522185Y655014D01*
G01X1522183Y655027D02*
X1522184Y655020D01*
G01X1522180Y655033D02*
X1522183Y655027D01*
G01X1522184Y658170D02*
X1522185Y658163D01*
G01X1522183Y658176D02*
X1522184Y658170D01*
G01X1522180Y658182D02*
X1522183Y658176D01*
G01X1522184Y661320D02*
X1522185Y661313D01*
G01X1522183Y661326D02*
X1522184Y661320D01*
G01X1522180Y661332D02*
X1522183Y661326D01*
G01X1522184Y664469D02*
X1522185Y664463D01*
G01X1522183Y664476D02*
X1522184Y664469D01*
G01X1522180Y664481D02*
X1522183Y664476D01*
G01X1522184Y667619D02*
X1522185Y667612D01*
G01X1522183Y667625D02*
X1522184Y667619D01*
G01X1522180Y667631D02*
X1522183Y667625D01*
G01X1522184Y670769D02*
X1522185Y670762D01*
G01X1522183Y670775D02*
X1522184Y670769D01*
G01X1522180Y670781D02*
X1522183Y670775D01*
G01X1522146Y650704D02*
Y650698D01*
G01X1522145Y650707D02*
X1522146Y650704D01*
G01X1522144Y650709D02*
X1522145Y650707D01*
G01X1522146Y653853D02*
Y653847D01*
G01X1522145Y653857D02*
X1522146Y653853D01*
G01X1522144Y653858D02*
X1522145Y653857D01*
G01X1522146Y657003D02*
Y656997D01*
G01X1522145Y657007D02*
X1522146Y657003D01*
G01X1522144Y657008D02*
X1522145Y657007D01*
G01X1522146Y660152D02*
Y660146D01*
G01X1522145Y660156D02*
X1522146Y660152D01*
G01X1522144Y660157D02*
X1522145Y660156D01*
G01X1522146Y663302D02*
Y663296D01*
G01X1522145Y663306D02*
X1522146Y663302D01*
G01X1522144Y663307D02*
X1522145Y663306D01*
G01X1522146Y669601D02*
Y669595D01*
G01X1522145Y669605D02*
X1522146Y669601D01*
G01X1522144Y669606D02*
X1522145Y669605D01*
G01X1521200Y653892D02*
X1521201Y653884D01*
G01X1521200Y653896D02*
Y653892D01*
G01X1521198Y653894D02*
X1521200Y653896D01*
G01X1522146Y670793D02*
Y670799D01*
G01X1522145Y670789D02*
X1522146Y670793D01*
G01X1522144Y670787D02*
X1522145Y670789D01*
G01X1522146Y667643D02*
Y667649D01*
G01X1522145Y667639D02*
X1522146Y667643D01*
G01X1522144Y667638D02*
X1522145Y667639D01*
G01X1522146Y664493D02*
Y664500D01*
G01X1522145Y664490D02*
X1522146Y664493D01*
G01X1522144Y664488D02*
X1522145Y664490D01*
G01X1522146Y661344D02*
Y661350D01*
G01X1522145Y661340D02*
X1522146Y661344D01*
G01X1522144Y661339D02*
X1522145Y661340D01*
G01X1522146Y658194D02*
Y658200D01*
G01X1522145Y658191D02*
X1522146Y658194D01*
G01X1522144Y658189D02*
X1522145Y658191D01*
G01X1522146Y655044D02*
Y655051D01*
G01X1522145Y655041D02*
X1522146Y655044D01*
G01X1522144Y655039D02*
X1522145Y655041D01*
G01X1522146Y651895D02*
Y651901D01*
G01X1522145Y651891D02*
X1522146Y651895D01*
G01X1522144Y651890D02*
X1522145Y651891D01*
G01X1521200Y670754D02*
X1521201Y670762D01*
G01X1521200Y670750D02*
Y670754D01*
G01X1521198Y670748D02*
X1521200Y670750D01*
G01Y667605D02*
X1521201Y667612D01*
G01X1521200Y667600D02*
Y667605D01*
G01X1521198Y667598D02*
X1521200Y667600D01*
G01Y664455D02*
X1521201Y664463D01*
G01X1521200Y664450D02*
Y664455D01*
G01X1521198Y664449D02*
X1521200Y664450D01*
G01Y661306D02*
X1521201Y661313D01*
G01X1521200Y661301D02*
Y661306D01*
G01X1521198Y661299D02*
X1521200Y661301D01*
G01Y658156D02*
X1521201Y658163D01*
G01X1521200Y658151D02*
Y658156D01*
G01X1521198Y658150D02*
X1521200Y658151D01*
G01Y655006D02*
X1521201Y655014D01*
G01X1521200Y655002D02*
Y655006D01*
G01X1521198Y655000D02*
X1521200Y655002D01*
G01Y651857D02*
X1521201Y651864D01*
G01X1521200Y651852D02*
Y651857D01*
G01X1521198Y651850D02*
X1521200Y651852D01*
G01X1521219Y660163D02*
X1521238Y660157D01*
G01X1521205Y660175D02*
X1521219Y660163D01*
G01X1521198Y660193D02*
X1521205Y660175D01*
G01X1522178Y658171D02*
X1522170Y658180D01*
G01X1522182Y658161D02*
X1522178Y658171D01*
G01X1522184Y658150D02*
X1522182Y658161D01*
G01X1522178Y651872D02*
X1522170Y651880D01*
G01X1522182Y651861D02*
X1522178Y651872D01*
G01X1522184Y651850D02*
X1522182Y651861D01*
G01X1522178Y655021D02*
X1522170Y655030D01*
G01X1522182Y655011D02*
X1522178Y655021D01*
G01X1522184Y655000D02*
X1522182Y655011D01*
G01X1522178Y661320D02*
X1522170Y661329D01*
G01X1522182Y661310D02*
X1522178Y661320D01*
G01X1522184Y661299D02*
X1522182Y661310D01*
G01X1522178Y664470D02*
X1522170Y664479D01*
G01X1522182Y664460D02*
X1522178Y664470D01*
G01X1522184Y664449D02*
X1522182Y664460D01*
G01X1522178Y667620D02*
X1522170Y667628D01*
G01X1522182Y667609D02*
X1522178Y667620D01*
G01X1522184Y667598D02*
X1522182Y667609D01*
G01X1522178Y670769D02*
X1522170Y670778D01*
G01X1522182Y670759D02*
X1522178Y670769D01*
G01X1522184Y670748D02*
X1522182Y670759D01*
G01X1521200Y663341D02*
X1521201Y663333D01*
G01X1521200Y663345D02*
Y663341D01*
G01Y663336D02*
Y663345D01*
G01X1521241Y670972D02*
X1521240Y670984D01*
G01X1521238Y670959D02*
X1521241Y670972D01*
G01X1521238Y670945D02*
Y670959D01*
G01X1521241Y667822D02*
X1521240Y667835D01*
G01X1521238Y667809D02*
X1521241Y667822D01*
G01X1521238Y667796D02*
Y667809D01*
G01X1521241Y664673D02*
X1521240Y664685D01*
G01X1521238Y664660D02*
X1521241Y664673D01*
G01X1521238Y664646D02*
Y664660D01*
G01X1521241Y661523D02*
X1521240Y661535D01*
G01X1521238Y661510D02*
X1521241Y661523D01*
G01X1521238Y661496D02*
Y661510D01*
G01X1521241Y658374D02*
X1521240Y658386D01*
G01X1521238Y658361D02*
X1521241Y658374D01*
G01X1521238Y658347D02*
Y658361D01*
G01X1521241Y655224D02*
X1521240Y655236D01*
G01X1521238Y655211D02*
X1521241Y655224D01*
G01X1521238Y655197D02*
Y655211D01*
G01X1521241Y652074D02*
X1521240Y652087D01*
G01X1521238Y652061D02*
X1521241Y652074D01*
G01X1521238Y652048D02*
Y652061D01*
G01X1521200Y669640D02*
X1521201Y669632D01*
G01X1521200Y669644D02*
Y669640D01*
G01Y669637D02*
Y669644D01*
G01X1521238Y669435D02*
X1521237Y669448D01*
G01X1521241Y669422D02*
X1521238Y669435D01*
G01X1521240Y669409D02*
X1521241Y669422D01*
G01X1521238Y666285D02*
X1521237Y666299D01*
G01X1521241Y666272D02*
X1521238Y666285D01*
G01X1521240Y666260D02*
X1521241Y666272D01*
G01X1521238Y663136D02*
X1521237Y663149D01*
G01X1521241Y663123D02*
X1521238Y663136D01*
G01X1521240Y663110D02*
X1521241Y663123D01*
G01X1521238Y659986D02*
X1521237Y660000D01*
G01X1521241Y659973D02*
X1521238Y659986D01*
G01X1521240Y659961D02*
X1521241Y659973D01*
G01X1521238Y656837D02*
X1521237Y656850D01*
G01X1521241Y656824D02*
X1521238Y656837D01*
G01X1521240Y656811D02*
X1521241Y656824D01*
G01X1521238Y653687D02*
X1521237Y653700D01*
G01X1521241Y653674D02*
X1521238Y653687D01*
G01X1521240Y653661D02*
X1521241Y653674D01*
G01X1521238Y650537D02*
X1521237Y650551D01*
G01X1521241Y650524D02*
X1521238Y650537D01*
G01X1521240Y650512D02*
X1521241Y650524D01*
G01X1522148Y670959D02*
X1522149Y670945D01*
G01X1522145Y670972D02*
X1522148Y670959D01*
G01X1522146Y670984D02*
X1522145Y670972D01*
G01X1522148Y667809D02*
X1522149Y667796D01*
G01X1522145Y667822D02*
X1522148Y667809D01*
G01X1522146Y667835D02*
X1522145Y667822D01*
G01X1522148Y664659D02*
X1522149Y664646D01*
G01X1522145Y664672D02*
X1522148Y664659D01*
G01X1522146Y664685D02*
X1522145Y664672D01*
G01X1522148Y661510D02*
X1522149Y661496D01*
G01X1522145Y661523D02*
X1522148Y661510D01*
G01X1522146Y661535D02*
X1522145Y661523D01*
G01X1522148Y658360D02*
X1522149Y658347D01*
G01X1522145Y658373D02*
X1522148Y658360D01*
G01X1522146Y658386D02*
X1522145Y658373D01*
G01X1522148Y655211D02*
X1522149Y655197D01*
G01X1522145Y655224D02*
X1522148Y655211D01*
G01X1522146Y655236D02*
X1522145Y655224D01*
G01X1522148Y652061D02*
X1522149Y652048D01*
G01X1522145Y652074D02*
X1522148Y652061D01*
G01X1522146Y652087D02*
X1522145Y652074D01*
G01X1521200Y657041D02*
X1521201Y657034D01*
G01X1521200Y657046D02*
Y657041D01*
G01X1521199Y657039D02*
X1521200Y657046D01*
G01Y666490D02*
X1521201Y666483D01*
G01X1521200Y666495D02*
Y666490D01*
G01X1521199Y666488D02*
X1521200Y666495D01*
G01X1522145Y669422D02*
X1522146Y669409D01*
G01X1522148Y669435D02*
X1522145Y669422D01*
G01X1522149Y669448D02*
X1522148Y669435D01*
G01X1522145Y666272D02*
X1522146Y666260D01*
G01X1522148Y666285D02*
X1522145Y666272D01*
G01X1522149Y666299D02*
X1522148Y666285D01*
G01X1522145Y663123D02*
X1522146Y663110D01*
G01X1522148Y663136D02*
X1522145Y663123D01*
G01X1522149Y663149D02*
X1522148Y663136D01*
G01X1522145Y659973D02*
X1522146Y659961D01*
G01X1522148Y659986D02*
X1522145Y659973D01*
G01X1522149Y660000D02*
X1522148Y659986D01*
G01X1522145Y656824D02*
X1522146Y656811D01*
G01X1522148Y656837D02*
X1522145Y656824D01*
G01X1522149Y656850D02*
X1522148Y656837D01*
G01X1522145Y653674D02*
X1522146Y653661D01*
G01X1522148Y653687D02*
X1522145Y653674D01*
G01X1522149Y653700D02*
X1522148Y653687D01*
G01X1522145Y650524D02*
X1522146Y650512D01*
G01X1522148Y650537D02*
X1522145Y650524D01*
G01X1522149Y650551D02*
X1522148Y650537D01*
G01X1521200Y650743D02*
X1521201Y650735D01*
G01X1521200Y650747D02*
Y650743D01*
G01X1521199Y650741D02*
X1521200Y650747D01*
G01X1521214Y670779D02*
X1521238Y670787D01*
G01X1521202Y670765D02*
X1521214Y670779D01*
G01X1521201Y670758D02*
X1521202Y670765D01*
G01X1521214Y667630D02*
X1521238Y667638D01*
G01X1521202Y667615D02*
X1521214Y667630D01*
G01X1521201Y667608D02*
X1521202Y667615D01*
G01X1521214Y664480D02*
X1521238Y664488D01*
G01X1521202Y664465D02*
X1521214Y664480D01*
G01X1521201Y664459D02*
X1521202Y664465D01*
G01X1521214Y661330D02*
X1521238Y661339D01*
G01X1521202Y661316D02*
X1521214Y661330D01*
G01X1521201Y661309D02*
X1521202Y661316D01*
G01X1521214Y658181D02*
X1521238Y658189D01*
G01X1521202Y658166D02*
X1521214Y658181D01*
G01X1521201Y658159D02*
X1521202Y658166D01*
G01X1521214Y655031D02*
X1521238Y655039D01*
G01X1521202Y655017D02*
X1521214Y655031D01*
G01X1521201Y655010D02*
X1521202Y655017D01*
G01X1521214Y651881D02*
X1521238Y651890D01*
G01X1521202Y651867D02*
X1521214Y651881D01*
G01X1521201Y651860D02*
X1521202Y651867D01*
G01X1522185Y670754D02*
Y670761D01*
G01Y670750D02*
Y670754D01*
G01X1522184Y670748D02*
X1522185Y670750D01*
G01Y667605D02*
Y667612D01*
G01Y667600D02*
Y667605D01*
G01X1522184Y667598D02*
X1522185Y667600D01*
G01Y664455D02*
Y664462D01*
G01Y664451D02*
Y664455D01*
G01X1522184Y664449D02*
X1522185Y664451D01*
G01Y661306D02*
Y661313D01*
G01Y661301D02*
Y661306D01*
G01X1522184Y661299D02*
X1522185Y661301D01*
G01Y658156D02*
Y658163D01*
G01Y658152D02*
Y658156D01*
G01X1522184Y658150D02*
X1522185Y658152D01*
G01Y655006D02*
Y655013D01*
G01Y655002D02*
Y655006D01*
G01X1522184Y655000D02*
X1522185Y655002D01*
G01Y651857D02*
Y651864D01*
G01Y651852D02*
Y651857D01*
G01X1522184Y651850D02*
X1522185Y651852D01*
G01X1521200Y660191D02*
X1521201Y660183D01*
G01X1521200Y660196D02*
Y660191D01*
G01X1521198Y660193D02*
X1521200Y660196D01*
G01X1522185Y651853D02*
Y651864D01*
G01Y655002D02*
Y655013D01*
G01Y658152D02*
Y658163D01*
G01Y661302D02*
Y661313D01*
G01Y664451D02*
Y664462D01*
G01Y667601D02*
Y667612D01*
G01Y670750D02*
Y670761D01*
G01X1522638Y751988D02*
Y672953D01*
G01X1522185Y669449D02*
Y670945D01*
G01Y666299D02*
Y667795D01*
G01Y663150D02*
Y664646D01*
G01Y660000D02*
Y661496D01*
G01Y656850D02*
Y658346D01*
G01Y653701D02*
Y655197D01*
G01Y650551D02*
Y652047D01*
G01X1522146Y650698D02*
Y650551D01*
G01Y652048D02*
Y651901D01*
G01Y656997D02*
Y656850D01*
G01Y653847D02*
Y653700D01*
G01Y655197D02*
Y655051D01*
G01Y660146D02*
Y660000D01*
G01Y661496D02*
Y661350D01*
G01Y658347D02*
Y658200D01*
G01Y666446D02*
Y666299D01*
G01Y663296D02*
Y663149D01*
G01Y664646D02*
Y664500D01*
G01Y669595D02*
Y669448D01*
G01Y670945D02*
Y670799D01*
G01Y667796D02*
Y667649D01*
G01X1521240Y669448D02*
Y669595D01*
G01Y670799D02*
Y670946D01*
G01Y667649D02*
Y667796D01*
G01Y666298D02*
Y666446D01*
G01Y663149D02*
Y663296D01*
G01Y664500D02*
Y664646D01*
G01Y659999D02*
Y660146D01*
G01Y661350D02*
Y661497D01*
G01Y658200D02*
Y658347D01*
G01Y656850D02*
Y656997D01*
G01Y653700D02*
Y653847D01*
G01Y655051D02*
Y655198D01*
G01Y650550D02*
Y650698D01*
G01Y651901D02*
Y652048D01*
G01X1521201Y652047D02*
Y650551D01*
G01Y655197D02*
Y653701D01*
G01Y661496D02*
Y660000D01*
G01Y658346D02*
Y656850D01*
G01Y664646D02*
Y663150D01*
G01Y670945D02*
Y669449D01*
G01Y667795D02*
Y666299D01*
G01X1520020Y651890D02*
Y650709D01*
G01Y658189D02*
Y657008D01*
G01Y655039D02*
Y653858D01*
G01Y661339D02*
Y660157D01*
G01Y667638D02*
Y666457D01*
G01Y664488D02*
Y663307D01*
G01Y670787D02*
Y669606D01*
G01X1519685Y672953D02*
Y648543D01*
G01X1519291D02*
Y672953D01*
G01X1522185Y669632D02*
Y669643D01*
G01Y666483D02*
Y666494D01*
G01Y663333D02*
Y663344D01*
G01Y660183D02*
Y660194D01*
G01Y657034D02*
Y657045D01*
G01Y653884D02*
Y653895D01*
G01Y650735D02*
Y650746D01*
G01X1522144Y666457D02*
X1522148Y666446D01*
G01X1516260Y669606D02*
Y670787D01*
G01Y666457D02*
Y667638D01*
G01Y663307D02*
Y664488D01*
G01Y660157D02*
Y661339D01*
G01Y657008D02*
Y658189D01*
G01Y653858D02*
Y655039D01*
G01Y650709D02*
Y651890D01*
G01X1521087Y669646D02*
X1521199Y669637D01*
G01X1521198Y660193D02*
X1521087Y660197D01*
G01X1521198Y653894D02*
X1521087Y653898D01*
G01X1521198Y663343D02*
X1521087Y663346D01*
G01X1522638Y672953D02*
X1519291D01*
G01X1522146Y670984D02*
X1521240D01*
G01X1522185Y670945D02*
X1521201D01*
G01X1522144Y670787D02*
X1516260D01*
G01Y670748D02*
X1522184D01*
G01X1522183Y669646D02*
X1516260D01*
G01X1522144Y669606D02*
X1516260D01*
G01X1521201Y669449D02*
X1522185D01*
G01X1521240Y669409D02*
X1522146D01*
G01Y667835D02*
X1521240D01*
G01X1522185Y667795D02*
X1521201D01*
G01X1522144Y667638D02*
X1516260D01*
G01Y667598D02*
X1522184D01*
G01X1522183Y666496D02*
X1516260D01*
G01X1522144Y666457D02*
X1516260D01*
G01X1521201Y666299D02*
X1522185D01*
G01X1521240Y666260D02*
X1522146D01*
G01Y664685D02*
X1521240D01*
G01X1522185Y664646D02*
X1521201D01*
G01X1522144Y664488D02*
X1516260D01*
G01Y664449D02*
X1522184D01*
G01X1520454Y663346D02*
X1520020D01*
G01X1522183D02*
X1516260D01*
G01X1522144Y663307D02*
X1516260D01*
G01X1521201Y663150D02*
X1522185D01*
G01X1521240Y663110D02*
X1522146D01*
G01Y661535D02*
X1521240D01*
G01X1522185Y661496D02*
X1521201D01*
G01X1522144Y661339D02*
X1516260D01*
G01Y661299D02*
X1522184D01*
G01X1520454Y660197D02*
X1520020D01*
G01X1522183D02*
X1516260D01*
G01X1522144Y660157D02*
X1516260D01*
G01X1521201Y660000D02*
X1522185D01*
G01X1521240Y659961D02*
X1522146D01*
G01Y658386D02*
X1521240D01*
G01X1522185Y658346D02*
X1521201D01*
G01X1522144Y658189D02*
X1516260D01*
G01Y658150D02*
X1522184D01*
G01X1522183Y657047D02*
X1516260D01*
G01X1522144Y657008D02*
X1516260D01*
G01X1521201Y656850D02*
X1522185D01*
G01X1521240Y656811D02*
X1522146D01*
G01Y655236D02*
X1521240D01*
G01X1522185Y655197D02*
X1521201D01*
G01X1522144Y655039D02*
X1516260D01*
G01Y655000D02*
X1522184D01*
G01X1520454Y653898D02*
X1520020D01*
G01X1522183D02*
X1516260D01*
G01X1522144Y653858D02*
X1516260D01*
G01X1521201Y653701D02*
X1522185D01*
G01X1521240Y653661D02*
X1522146D01*
G01Y652087D02*
X1521240D01*
G01X1522185Y652047D02*
X1521201D01*
G01X1522144Y651890D02*
X1516260D01*
G01Y651850D02*
X1522184D01*
G01X1522183Y650748D02*
X1516260D01*
G01X1522144Y650709D02*
X1516260D01*
G01X1521201Y650551D02*
X1522185D01*
G01X1521240Y650512D02*
X1522146D01*
G01X1522638Y648543D02*
X1519291D01*
G01X1521260Y770807D02*
G03X1519291Y768839I0J-1969D01*
G01D02*
Y753091D01*
G01D02*
X1522638Y749744D01*
G01X1538976Y770807D02*
X1521260D01*
G01X1540945Y760374D02*
X1519291D01*
G01X1522638Y751988D02*
X1537008D01*
G01X1522638Y750610D02*
X1526378D01*
G01X1522638Y749744D02*
X1537598D01*
G01X1490157Y827559D02*
G03X1491339I591J0D01*
G01Y821260D02*
G03X1490157I-591J0D01*
G01X1488189D02*
G03X1487008I-591J0D01*
G01Y827559D02*
G03X1488189I591J0D01*
G01X1490157D02*
G03X1491339I591J0D01*
G01Y821260D02*
G03X1490157I-591J0D01*
G01X1488189D02*
G03X1487008I-591J0D01*
G01Y827559D02*
G03X1488189I591J0D01*
G01X1492126Y821260D02*
Y827559D01*
G01Y821260D02*
Y827559D01*
G01X1486220Y821260D02*
Y827559D01*
G01D02*
Y821260D01*
G01X1490157Y827559D02*
X1488189D01*
G01X1487008D02*
X1486220D01*
G01X1490157D02*
X1488189D01*
G01X1487008D02*
X1486220D01*
G01X1492126D02*
X1491339D01*
G01X1492126D02*
X1491339D01*
G01X1492126Y826575D02*
X1486220D01*
G01Y826378D02*
X1492126D01*
G01X1486220Y822441D02*
X1492126D01*
G01Y822244D02*
X1486220D01*
G01X1491339Y821260D02*
X1492126D01*
G01X1491339D02*
X1492126D01*
G01X1488189D02*
X1490157D01*
G01X1486220D02*
X1487008D01*
G01X1488189D02*
X1490157D01*
G01X1486220D02*
X1487008D01*
G01X1519291Y1045413D02*
G03X1521260Y1043445I1969J1D01*
G01X1522638Y1101299D02*
Y1062264D01*
G01X1519291Y1061161D02*
Y1045413D01*
G01X1537598Y1064508D02*
X1522638D01*
G01X1526378Y1063642D02*
X1522638D01*
G01Y1062264D02*
X1537008D01*
G01X1540945Y1053878D02*
X1519291D01*
G01X1538976Y1043445D02*
X1521260D01*
G01X1522638Y1064508D02*
X1519291Y1061161D01*
G01X1522156Y1122364D02*
X1522144Y1122362D01*
G01X1522167Y1122369D02*
X1522156Y1122364D01*
G01Y1119215D02*
X1522144Y1119213D01*
G01X1522167Y1119220D02*
X1522156Y1119215D01*
G01Y1116065D02*
X1522144Y1116063D01*
G01X1522167Y1116070D02*
X1522156Y1116065D01*
G01Y1112915D02*
X1522144Y1112913D01*
G01X1522167Y1112920D02*
X1522156Y1112915D01*
G01Y1109766D02*
X1522144Y1109764D01*
G01X1522167Y1109771D02*
X1522156Y1109766D01*
G01Y1106616D02*
X1522144Y1106614D01*
G01X1522167Y1106621D02*
X1522156Y1106616D01*
G01Y1103467D02*
X1522144Y1103465D01*
G01X1522167Y1103472D02*
X1522156Y1103467D01*
G01X1522183Y1122376D02*
X1522185Y1122388D01*
G01X1522176Y1122365D02*
X1522183Y1122376D01*
G01X1522166Y1122356D02*
X1522176Y1122365D01*
G01X1522183Y1116076D02*
X1522185Y1116089D01*
G01X1522176Y1116065D02*
X1522183Y1116076D01*
G01X1522166Y1116057D02*
X1522176Y1116065D01*
G01X1522183Y1112927D02*
X1522185Y1112939D01*
G01X1522176Y1112916D02*
X1522183Y1112927D01*
G01X1522166Y1112907D02*
X1522176Y1112916D01*
G01X1522183Y1109777D02*
X1522185Y1109790D01*
G01X1522176Y1109766D02*
X1522183Y1109777D01*
G01X1522166Y1109758D02*
X1522176Y1109766D01*
G01X1522183Y1106628D02*
X1522185Y1106640D01*
G01X1522176Y1106617D02*
X1522183Y1106628D01*
G01X1522166Y1106608D02*
X1522176Y1106617D01*
G01X1522183Y1103478D02*
X1522185Y1103491D01*
G01X1522176Y1103467D02*
X1522183Y1103478D01*
G01X1522166Y1103459D02*
X1522176Y1103467D01*
G01X1521239Y1123548D02*
Y1123555D01*
G01Y1123544D02*
Y1123548D01*
G01X1521237Y1123543D02*
X1521239Y1123544D01*
G01Y1120399D02*
Y1120405D01*
G01Y1120395D02*
Y1120399D01*
G01X1521237Y1120394D02*
X1521239Y1120395D01*
G01Y1117249D02*
Y1117256D01*
G01Y1117245D02*
Y1117249D01*
G01X1521237Y1117244D02*
X1521239Y1117245D01*
G01Y1114100D02*
Y1114106D01*
G01Y1114096D02*
Y1114100D01*
G01X1521237Y1114094D02*
X1521239Y1114096D01*
G01Y1110950D02*
Y1110956D01*
G01Y1110946D02*
Y1110950D01*
G01X1521237Y1110945D02*
X1521239Y1110946D01*
G01Y1107800D02*
Y1107807D01*
G01Y1107796D02*
Y1107800D01*
G01X1521237Y1107795D02*
X1521239Y1107796D01*
G01Y1104651D02*
Y1104657D01*
G01Y1104647D02*
Y1104651D01*
G01X1521237Y1104646D02*
X1521239Y1104647D01*
G01X1521202Y1123524D02*
X1521201Y1123518D01*
G01X1521203Y1123530D02*
X1521202Y1123524D01*
G01X1521206Y1123536D02*
X1521203Y1123530D01*
G01X1521210Y1123541D02*
X1521206Y1123536D01*
G01X1521215Y1123546D02*
X1521210Y1123541D01*
G01X1521220Y1123550D02*
X1521215Y1123546D01*
G01X1521202Y1120374D02*
X1521201Y1120368D01*
G01X1521203Y1120381D02*
X1521202Y1120374D01*
G01X1521206Y1120386D02*
X1521203Y1120381D01*
G01X1521210Y1120392D02*
X1521206Y1120386D01*
G01X1521215Y1120396D02*
X1521210Y1120392D01*
G01X1521220Y1120400D02*
X1521215Y1120396D01*
G01X1521202Y1117225D02*
X1521201Y1117219D01*
G01X1521203Y1117231D02*
X1521202Y1117225D01*
G01X1521206Y1117237D02*
X1521203Y1117231D01*
G01X1521210Y1117242D02*
X1521206Y1117237D01*
G01X1521215Y1117246D02*
X1521210Y1117242D01*
G01X1521220Y1117250D02*
X1521215Y1117246D01*
G01X1521202Y1114075D02*
X1521201Y1114069D01*
G01X1521203Y1114081D02*
X1521202Y1114075D01*
G01X1521206Y1114087D02*
X1521203Y1114081D01*
G01X1521210Y1114093D02*
X1521206Y1114087D01*
G01X1521215Y1114097D02*
X1521210Y1114093D01*
G01X1521220Y1114101D02*
X1521215Y1114097D01*
G01X1521202Y1110926D02*
X1521201Y1110919D01*
G01X1521203Y1110932D02*
X1521202Y1110926D01*
G01X1521206Y1110937D02*
X1521203Y1110932D01*
G01X1521210Y1110943D02*
X1521206Y1110937D01*
G01X1521215Y1110947D02*
X1521210Y1110943D01*
G01X1521220Y1110951D02*
X1521215Y1110947D01*
G01X1521202Y1107776D02*
X1521201Y1107770D01*
G01X1521203Y1107782D02*
X1521202Y1107776D01*
G01X1521206Y1107788D02*
X1521203Y1107782D01*
G01X1521210Y1107793D02*
X1521206Y1107788D01*
G01X1521215Y1107798D02*
X1521210Y1107793D01*
G01X1521220Y1107802D02*
X1521215Y1107798D01*
G01X1521202Y1104626D02*
X1521201Y1104620D01*
G01X1521203Y1104633D02*
X1521202Y1104626D01*
G01X1521206Y1104638D02*
X1521203Y1104633D01*
G01X1521210Y1104644D02*
X1521206Y1104638D01*
G01X1521215Y1104648D02*
X1521210Y1104644D01*
G01X1521220Y1104652D02*
X1521215Y1104648D01*
G01X1521200Y1123510D02*
X1521201Y1123518D01*
G01X1521200Y1123506D02*
Y1123510D01*
G01X1521198Y1123504D02*
X1521200Y1123506D01*
G01Y1120361D02*
X1521201Y1120368D01*
G01X1521200Y1120356D02*
Y1120361D01*
G01X1521198Y1120354D02*
X1521200Y1120356D01*
G01Y1117211D02*
X1521201Y1117219D01*
G01X1521200Y1117206D02*
Y1117211D01*
G01X1521198Y1117205D02*
X1521200Y1117206D01*
G01Y1114061D02*
X1521201Y1114069D01*
G01X1521200Y1114057D02*
Y1114061D01*
G01X1521198Y1114055D02*
X1521200Y1114057D01*
G01Y1110912D02*
X1521201Y1110919D01*
G01X1521200Y1110907D02*
Y1110912D01*
G01X1521198Y1110906D02*
X1521200Y1110907D01*
G01Y1107762D02*
X1521201Y1107770D01*
G01X1521200Y1107757D02*
Y1107762D01*
G01X1521198Y1107756D02*
X1521200Y1107757D01*
G01Y1104613D02*
X1521201Y1104620D01*
G01X1521200Y1104608D02*
Y1104613D01*
G01X1521198Y1104606D02*
X1521200Y1104608D01*
G01X1521204Y1104626D02*
X1521198Y1104606D01*
G01X1521218Y1104641D02*
X1521204Y1104626D01*
G01X1521238Y1104646D02*
X1521218Y1104641D01*
G01X1521204Y1107776D02*
X1521198Y1107756D01*
G01X1521218Y1107790D02*
X1521204Y1107776D01*
G01X1521238Y1107795D02*
X1521218Y1107790D01*
G01X1521204Y1110925D02*
X1521198Y1110906D01*
G01X1521218Y1110940D02*
X1521204Y1110925D01*
G01X1521238Y1110945D02*
X1521218Y1110940D01*
G01X1521204Y1114075D02*
X1521198Y1114055D01*
G01X1521218Y1114089D02*
X1521204Y1114075D01*
G01X1521238Y1114094D02*
X1521218Y1114089D01*
G01X1521204Y1117224D02*
X1521198Y1117205D01*
G01X1521218Y1117239D02*
X1521204Y1117224D01*
G01X1521238Y1117244D02*
X1521218Y1117239D01*
G01X1521204Y1120374D02*
X1521198Y1120354D01*
G01X1521218Y1120389D02*
X1521204Y1120374D01*
G01X1521238Y1120394D02*
X1521218Y1120389D01*
G01X1521204Y1123524D02*
X1521198Y1123504D01*
G01X1521218Y1123538D02*
X1521204Y1123524D01*
G01X1521238Y1123543D02*
X1521218Y1123538D01*
G01X1522178Y1103484D02*
X1522183Y1103504D01*
G01X1522164Y1103470D02*
X1522178Y1103484D01*
G01X1522144Y1103465D02*
X1522164Y1103470D01*
G01X1522178Y1106634D02*
X1522183Y1106654D01*
G01X1522164Y1106620D02*
X1522178Y1106634D01*
G01X1522144Y1106614D02*
X1522164Y1106620D01*
G01X1522178Y1109783D02*
X1522183Y1109803D01*
G01X1522164Y1109769D02*
X1522178Y1109783D01*
G01X1522144Y1109764D02*
X1522164Y1109769D01*
G01X1522178Y1112933D02*
X1522183Y1112953D01*
G01X1522164Y1112919D02*
X1522178Y1112933D01*
G01X1522144Y1112913D02*
X1522164Y1112919D01*
G01X1522178Y1116083D02*
X1522183Y1116102D01*
G01X1522164Y1116069D02*
X1522178Y1116083D01*
G01X1522144Y1116063D02*
X1522164Y1116069D01*
G01X1522178Y1119232D02*
X1522183Y1119252D01*
G01X1522164Y1119218D02*
X1522178Y1119232D01*
G01X1522144Y1119213D02*
X1522164Y1119218D01*
G01X1522178Y1122382D02*
X1522183Y1122402D01*
G01X1522164Y1122368D02*
X1522178Y1122382D01*
G01X1522144Y1122362D02*
X1522164Y1122368D01*
G01X1522146Y1123548D02*
Y1123555D01*
G01X1522145Y1123545D02*
X1522146Y1123548D01*
G01X1522144Y1123543D02*
X1522145Y1123545D01*
G01X1522185Y1123510D02*
Y1123517D01*
G01Y1123506D02*
Y1123510D01*
G01X1522184Y1123504D02*
X1522185Y1123506D01*
G01X1521200Y1106648D02*
X1521201Y1106640D01*
G01X1521200Y1106652D02*
Y1106648D01*
G01X1521198Y1106650D02*
X1521200Y1106652D01*
G01X1522146Y1120399D02*
Y1120405D01*
G01X1522145Y1120395D02*
X1522146Y1120399D01*
G01X1522144Y1120394D02*
X1522145Y1120395D01*
G01X1522146Y1117249D02*
Y1117256D01*
G01X1522145Y1117246D02*
X1522146Y1117249D01*
G01X1522144Y1117244D02*
X1522145Y1117246D01*
G01X1522146Y1114100D02*
Y1114106D01*
G01X1522145Y1114096D02*
X1522146Y1114100D01*
G01X1522144Y1114094D02*
X1522145Y1114096D01*
G01X1522146Y1110950D02*
Y1110956D01*
G01X1522145Y1110946D02*
X1522146Y1110950D01*
G01X1522144Y1110945D02*
X1522145Y1110946D01*
G01X1522146Y1107800D02*
Y1107807D01*
G01X1522145Y1107797D02*
X1522146Y1107800D01*
G01X1522144Y1107795D02*
X1522145Y1107797D01*
G01X1522146Y1104651D02*
Y1104657D01*
G01X1522145Y1104647D02*
X1522146Y1104651D01*
G01X1522144Y1104646D02*
X1522145Y1104647D01*
G01X1522184Y1119231D02*
X1522185Y1119239D01*
G01X1522182Y1119224D02*
X1522184Y1119231D01*
G01X1522178Y1119218D02*
X1522182Y1119224D01*
G01X1522174Y1119212D02*
X1522178Y1119218D01*
G01X1522167Y1119207D02*
X1522174Y1119212D01*
G01X1522161Y1119204D02*
X1522167Y1119207D01*
G01X1522153Y1119202D02*
X1522161Y1119204D01*
G01X1522146Y1119202D02*
X1522153D01*
G01X1522163Y1103457D02*
X1522166Y1103459D01*
G01X1522159Y1103456D02*
X1522163Y1103457D01*
G01X1522156Y1103455D02*
X1522159Y1103456D01*
G01X1522153Y1103454D02*
X1522156Y1103455D01*
G01X1522149Y1103454D02*
X1522153D01*
G01X1522146D02*
X1522149D01*
G01X1521223Y1104654D02*
X1521220Y1104652D01*
G01X1521226Y1104655D02*
X1521223Y1104654D01*
G01X1521230Y1104656D02*
X1521226Y1104655D01*
G01X1521233Y1104656D02*
X1521230D01*
G01X1521237Y1104657D02*
X1521233Y1104656D01*
G01X1521240Y1104657D02*
X1521237D01*
G01X1522163Y1106607D02*
X1522166Y1106608D01*
G01X1522159Y1106606D02*
X1522163Y1106607D01*
G01X1522156Y1106604D02*
X1522159Y1106606D01*
G01X1522153Y1106604D02*
X1522156D01*
G01X1522149Y1106603D02*
X1522153Y1106604D01*
G01X1522146Y1106603D02*
X1522149D01*
G01X1521223Y1107803D02*
X1521220Y1107802D01*
G01X1521226Y1107804D02*
X1521223Y1107803D01*
G01X1521230Y1107806D02*
X1521226Y1107804D01*
G01X1521233Y1107806D02*
X1521230D01*
G01X1521237Y1107807D02*
X1521233Y1107806D01*
G01X1521240Y1107807D02*
X1521237D01*
G01X1522163Y1109756D02*
X1522166Y1109758D01*
G01X1522159Y1109755D02*
X1522163Y1109756D01*
G01X1522156Y1109754D02*
X1522159Y1109755D01*
G01X1522153Y1109753D02*
X1522156Y1109754D01*
G01X1522149Y1109753D02*
X1522153D01*
G01X1522146D02*
X1522149D01*
G01X1521223Y1110953D02*
X1521220Y1110951D01*
G01X1521226Y1110954D02*
X1521223Y1110953D01*
G01X1521230Y1110955D02*
X1521226Y1110954D01*
G01X1521233Y1110956D02*
X1521230Y1110955D01*
G01X1521237Y1110956D02*
X1521233D01*
G01X1521240D02*
X1521237D01*
G01X1522163Y1112906D02*
X1522166Y1112907D01*
G01X1522159Y1112905D02*
X1522163Y1112906D01*
G01X1522156Y1112904D02*
X1522159Y1112905D01*
G01X1522153Y1112903D02*
X1522156Y1112904D01*
G01X1522149Y1112902D02*
X1522153Y1112903D01*
G01X1522146Y1112902D02*
X1522149D01*
G01X1521223Y1114102D02*
X1521220Y1114101D01*
G01X1521226Y1114104D02*
X1521223Y1114102D01*
G01X1521230Y1114105D02*
X1521226Y1114104D01*
G01X1521233Y1114105D02*
X1521230D01*
G01X1521237Y1114106D02*
X1521233Y1114105D01*
G01X1521240Y1114106D02*
X1521237D01*
G01X1522163Y1116056D02*
X1522166Y1116057D01*
G01X1522159Y1116054D02*
X1522163Y1116056D01*
G01X1522156Y1116053D02*
X1522159Y1116054D01*
G01X1522153Y1116052D02*
X1522156Y1116053D01*
G01X1522149Y1116052D02*
X1522153D01*
G01X1522146D02*
X1522149D01*
G01X1521223Y1117252D02*
X1521220Y1117250D01*
G01X1521226Y1117253D02*
X1521223Y1117252D01*
G01X1521230Y1117254D02*
X1521226Y1117253D01*
G01X1521233Y1117255D02*
X1521230Y1117254D01*
G01X1521237Y1117256D02*
X1521233Y1117255D01*
G01X1521240Y1117256D02*
X1521237D01*
G01X1521223Y1120402D02*
X1521220Y1120400D01*
G01X1521226Y1120403D02*
X1521223Y1120402D01*
G01X1521230Y1120404D02*
X1521226Y1120403D01*
G01X1521233Y1120404D02*
X1521230D01*
G01X1521237Y1120405D02*
X1521233Y1120404D01*
G01X1521240Y1120405D02*
X1521237D01*
G01X1522163Y1122355D02*
X1522166Y1122356D01*
G01X1522159Y1122354D02*
X1522163Y1122355D01*
G01X1522156Y1122352D02*
X1522159Y1122354D01*
G01X1522153Y1122352D02*
X1522156D01*
G01X1522149Y1122351D02*
X1522153Y1122352D01*
G01X1522146Y1122351D02*
X1522149D01*
G01X1521223Y1123551D02*
X1521220Y1123550D01*
G01X1521226Y1123552D02*
X1521223Y1123551D01*
G01X1521230Y1123554D02*
X1521226Y1123552D01*
G01X1521233Y1123554D02*
X1521230D01*
G01X1521237Y1123555D02*
X1521233Y1123554D01*
G01X1521240Y1123555D02*
X1521237D01*
G01X1522176Y1104644D02*
X1522180Y1104639D01*
G01X1522171Y1104648D02*
X1522176Y1104644D01*
G01X1522165Y1104652D02*
X1522171Y1104648D01*
G01X1522159Y1104655D02*
X1522165Y1104652D01*
G01X1522152Y1104657D02*
X1522159Y1104655D01*
G01X1522146Y1104657D02*
X1522152D01*
G01X1522176Y1107794D02*
X1522180Y1107789D01*
G01X1522171Y1107798D02*
X1522176Y1107794D01*
G01X1522165Y1107802D02*
X1522171Y1107798D01*
G01X1522159Y1107804D02*
X1522165Y1107802D01*
G01X1522152Y1107806D02*
X1522159Y1107804D01*
G01X1522146Y1107807D02*
X1522152Y1107806D01*
G01X1521202Y1103483D02*
X1521201Y1103491D01*
G01X1521204Y1103476D02*
X1521202Y1103483D01*
G01X1521207Y1103470D02*
X1521204Y1103476D01*
G01X1521212Y1103464D02*
X1521207Y1103470D01*
G01X1521219Y1103459D02*
X1521212Y1103464D01*
G01X1521225Y1103456D02*
X1521219Y1103459D01*
G01X1521233Y1103454D02*
X1521225Y1103456D01*
G01X1521240Y1103454D02*
X1521233D01*
G01X1521214Y1123535D02*
X1521238Y1123543D01*
G01X1521202Y1123520D02*
X1521214Y1123535D01*
G01X1521201Y1123514D02*
X1521202Y1123520D01*
G01X1521214Y1120385D02*
X1521238Y1120394D01*
G01X1521202Y1120371D02*
X1521214Y1120385D01*
G01X1521201Y1120364D02*
X1521202Y1120371D01*
G01X1521214Y1117236D02*
X1521238Y1117244D01*
G01X1521202Y1117221D02*
X1521214Y1117236D01*
G01X1521201Y1117215D02*
X1521202Y1117221D01*
G01X1521214Y1114086D02*
X1521238Y1114094D01*
G01X1521202Y1114072D02*
X1521214Y1114086D01*
G01X1521201Y1114065D02*
X1521202Y1114072D01*
G01X1521214Y1110937D02*
X1521238Y1110945D01*
G01X1521202Y1110922D02*
X1521214Y1110937D01*
G01X1521201Y1110915D02*
X1521202Y1110922D01*
G01X1521214Y1107787D02*
X1521238Y1107795D01*
G01X1521202Y1107772D02*
X1521214Y1107787D01*
G01X1521201Y1107766D02*
X1521202Y1107772D01*
G01X1521214Y1104637D02*
X1521238Y1104646D01*
G01X1521202Y1104623D02*
X1521214Y1104637D01*
G01X1521201Y1104616D02*
X1521202Y1104623D01*
G01X1522185Y1120361D02*
Y1120368D01*
G01Y1120356D02*
Y1120361D01*
G01X1522184Y1120354D02*
X1522185Y1120356D01*
G01Y1117211D02*
Y1117218D01*
G01Y1117207D02*
Y1117211D01*
G01X1522184Y1117205D02*
X1522185Y1117207D01*
G01Y1114061D02*
Y1114069D01*
G01Y1114057D02*
Y1114061D01*
G01X1522184Y1114055D02*
X1522185Y1114057D01*
G01Y1110912D02*
Y1110919D01*
G01Y1110907D02*
Y1110912D01*
G01X1522184Y1110906D02*
X1522185Y1110907D01*
G01Y1107762D02*
Y1107769D01*
G01Y1107758D02*
Y1107762D01*
G01X1522184Y1107756D02*
X1522185Y1107758D01*
G01Y1104613D02*
Y1104620D01*
G01Y1104608D02*
Y1104613D01*
G01X1522184Y1104606D02*
X1522185Y1104608D01*
G01X1521200Y1112947D02*
X1521201Y1112939D01*
G01X1521200Y1112952D02*
Y1112947D01*
G01X1521198Y1112949D02*
X1521200Y1112952D01*
G01X1522176Y1110943D02*
X1522180Y1110938D01*
G01X1522171Y1110948D02*
X1522176Y1110943D01*
G01X1522165Y1110952D02*
X1522171Y1110948D01*
G01X1522159Y1110954D02*
X1522165Y1110952D01*
G01X1522152Y1110956D02*
X1522159Y1110954D01*
G01X1522146Y1110956D02*
X1522152D01*
G01X1522176Y1114093D02*
X1522180Y1114088D01*
G01X1522171Y1114097D02*
X1522176Y1114093D01*
G01X1522165Y1114101D02*
X1522171Y1114097D01*
G01X1522159Y1114104D02*
X1522165Y1114101D01*
G01X1522152Y1114106D02*
X1522159Y1114104D01*
G01X1522146Y1114106D02*
X1522152D01*
G01X1522176Y1117243D02*
X1522180Y1117237D01*
G01X1522171Y1117247D02*
X1522176Y1117243D01*
G01X1522165Y1117251D02*
X1522171Y1117247D01*
G01X1522159Y1117253D02*
X1522165Y1117251D01*
G01X1522152Y1117255D02*
X1522159Y1117253D01*
G01X1522146Y1117256D02*
X1522152Y1117255D01*
G01X1522176Y1120392D02*
X1522180Y1120387D01*
G01X1522171Y1120396D02*
X1522176Y1120392D01*
G01X1522165Y1120400D02*
X1522171Y1120396D01*
G01X1522159Y1120403D02*
X1522165Y1120400D01*
G01X1522152Y1120405D02*
X1522159Y1120403D01*
G01X1522146Y1120405D02*
X1522152D01*
G01X1522176Y1123542D02*
X1522180Y1123537D01*
G01X1522171Y1123546D02*
X1522176Y1123542D01*
G01X1522165Y1123550D02*
X1522171Y1123546D01*
G01X1522159Y1123552D02*
X1522165Y1123550D01*
G01X1522152Y1123554D02*
X1522159Y1123552D01*
G01X1522146Y1123555D02*
X1522152Y1123554D01*
G01X1521202Y1106633D02*
X1521201Y1106640D01*
G01X1521204Y1106626D02*
X1521202Y1106633D01*
G01X1521207Y1106620D02*
X1521204Y1106626D01*
G01X1521212Y1106614D02*
X1521207Y1106620D01*
G01X1521219Y1106609D02*
X1521212Y1106614D01*
G01X1521225Y1106606D02*
X1521219Y1106609D01*
G01X1521233Y1106604D02*
X1521225Y1106606D01*
G01X1521240Y1106603D02*
X1521233Y1106604D01*
G01X1521202Y1109782D02*
X1521201Y1109790D01*
G01X1521204Y1109776D02*
X1521202Y1109782D01*
G01X1521207Y1109769D02*
X1521204Y1109776D01*
G01X1521212Y1109763D02*
X1521207Y1109769D01*
G01X1521219Y1109759D02*
X1521212Y1109763D01*
G01X1521225Y1109756D02*
X1521219Y1109759D01*
G01X1521233Y1109754D02*
X1521225Y1109756D01*
G01X1521240Y1109753D02*
X1521233Y1109754D01*
G01X1521202Y1112932D02*
X1521201Y1112939D01*
G01X1521204Y1112925D02*
X1521202Y1112932D01*
G01X1521207Y1112919D02*
X1521204Y1112925D01*
G01X1521212Y1112913D02*
X1521207Y1112919D01*
G01X1521219Y1112908D02*
X1521212Y1112913D01*
G01X1521225Y1112905D02*
X1521219Y1112908D01*
G01X1521233Y1112903D02*
X1521225Y1112905D01*
G01X1521240Y1112902D02*
X1521233Y1112903D01*
G01X1521202Y1116081D02*
X1521201Y1116089D01*
G01X1521204Y1116075D02*
X1521202Y1116081D01*
G01X1521207Y1116069D02*
X1521204Y1116075D01*
G01X1521212Y1116063D02*
X1521207Y1116069D01*
G01X1521219Y1116058D02*
X1521212Y1116063D01*
G01X1521225Y1116055D02*
X1521219Y1116058D01*
G01X1521233Y1116053D02*
X1521225Y1116055D01*
G01X1521240Y1116052D02*
X1521233Y1116053D01*
G01X1521202Y1119231D02*
X1521201Y1119239D01*
G01X1521204Y1119224D02*
X1521202Y1119231D01*
G01X1521207Y1119218D02*
X1521204Y1119224D01*
G01X1521212Y1119212D02*
X1521207Y1119218D01*
G01X1521219Y1119207D02*
X1521212Y1119212D01*
G01X1521225Y1119204D02*
X1521219Y1119207D01*
G01X1521233Y1119202D02*
X1521225Y1119204D01*
G01X1521240Y1119202D02*
X1521233D01*
G01X1521202Y1122381D02*
X1521201Y1122388D01*
G01X1521204Y1122374D02*
X1521202Y1122381D01*
G01X1521207Y1122368D02*
X1521204Y1122374D01*
G01X1521212Y1122362D02*
X1521207Y1122368D01*
G01X1521219Y1122357D02*
X1521212Y1122362D01*
G01X1521225Y1122354D02*
X1521219Y1122357D01*
G01X1521233Y1122352D02*
X1521225Y1122354D01*
G01X1521240Y1122351D02*
X1521233Y1122352D01*
G01X1522155Y1104644D02*
X1522164Y1104640D01*
G01X1522144Y1104646D02*
X1522155Y1104644D01*
G01Y1107794D02*
X1522164Y1107790D01*
G01X1522144Y1107795D02*
X1522155Y1107794D01*
G01Y1110944D02*
X1522164Y1110939D01*
G01X1522144Y1110945D02*
X1522155Y1110944D01*
G01Y1114093D02*
X1522164Y1114089D01*
G01X1522144Y1114094D02*
X1522155Y1114093D01*
G01Y1117243D02*
X1522164Y1117239D01*
G01X1522144Y1117244D02*
X1522155Y1117243D01*
G01Y1120393D02*
X1522164Y1120388D01*
G01X1522144Y1120394D02*
X1522155Y1120393D01*
G01Y1123542D02*
X1522164Y1123538D01*
G01X1522144Y1123543D02*
X1522155Y1123542D01*
G01X1521200Y1122396D02*
X1521201Y1122388D01*
G01X1521200Y1122400D02*
Y1122396D01*
G01Y1122393D02*
Y1122400D01*
G01X1521238Y1122191D02*
X1521237Y1122204D01*
G01X1521241Y1122178D02*
X1521238Y1122191D01*
G01X1521240Y1122165D02*
X1521241Y1122178D01*
G01X1521238Y1119041D02*
X1521237Y1119055D01*
G01X1521241Y1119028D02*
X1521238Y1119041D01*
G01X1521240Y1119016D02*
X1521241Y1119028D01*
G01X1521238Y1115892D02*
X1521237Y1115905D01*
G01X1521241Y1115879D02*
X1521238Y1115892D01*
G01X1521240Y1115866D02*
X1521241Y1115879D01*
G01X1521238Y1112742D02*
X1521237Y1112756D01*
G01X1521241Y1112729D02*
X1521238Y1112742D01*
G01X1521240Y1112717D02*
X1521241Y1112729D01*
G01X1521238Y1109593D02*
X1521237Y1109606D01*
G01X1521241Y1109580D02*
X1521238Y1109593D01*
G01X1521240Y1109567D02*
X1521241Y1109580D01*
G01X1521238Y1106443D02*
X1521237Y1106456D01*
G01X1521241Y1106430D02*
X1521238Y1106443D01*
G01X1521240Y1106417D02*
X1521241Y1106430D01*
G01X1521238Y1103293D02*
X1521237Y1103307D01*
G01X1521241Y1103280D02*
X1521238Y1103293D01*
G01X1521240Y1103268D02*
X1521241Y1103280D01*
G01X1522148Y1123715D02*
X1522149Y1123701D01*
G01X1522145Y1123728D02*
X1522148Y1123715D01*
G01X1522146Y1123740D02*
X1522145Y1123728D01*
G01X1522148Y1120565D02*
X1522149Y1120552D01*
G01X1522145Y1120578D02*
X1522148Y1120565D01*
G01X1522146Y1120591D02*
X1522145Y1120578D01*
G01X1522148Y1117415D02*
X1522149Y1117402D01*
G01X1522145Y1117428D02*
X1522148Y1117415D01*
G01X1522146Y1117441D02*
X1522145Y1117428D01*
G01X1522148Y1114266D02*
X1522149Y1114252D01*
G01X1522145Y1114279D02*
X1522148Y1114266D01*
G01X1522146Y1114291D02*
X1522145Y1114279D01*
G01X1522148Y1111116D02*
X1522149Y1111103D01*
G01X1522145Y1111129D02*
X1522148Y1111116D01*
G01X1522146Y1111142D02*
X1522145Y1111129D01*
G01X1522148Y1107967D02*
X1522149Y1107953D01*
G01X1522145Y1107980D02*
X1522148Y1107967D01*
G01X1522146Y1107992D02*
X1522145Y1107980D01*
G01X1522148Y1104817D02*
X1522149Y1104804D01*
G01X1522145Y1104830D02*
X1522148Y1104817D01*
G01X1522146Y1104843D02*
X1522145Y1104830D01*
G01X1521200Y1109797D02*
X1521201Y1109790D01*
G01X1521200Y1109802D02*
Y1109797D01*
G01X1521199Y1109795D02*
X1521200Y1109802D01*
G01Y1119246D02*
X1521201Y1119239D01*
G01X1521200Y1119251D02*
Y1119246D01*
G01X1521199Y1119244D02*
X1521200Y1119251D01*
G01X1522145Y1122178D02*
X1522146Y1122165D01*
G01X1522148Y1122191D02*
X1522145Y1122178D01*
G01X1522149Y1122204D02*
X1522148Y1122191D01*
G01X1522145Y1119028D02*
X1522146Y1119016D01*
G01X1522148Y1119041D02*
X1522145Y1119028D01*
G01X1522149Y1119055D02*
X1522148Y1119041D01*
G01X1522145Y1115879D02*
X1522146Y1115866D01*
G01X1522148Y1115892D02*
X1522145Y1115879D01*
G01X1522149Y1115905D02*
X1522148Y1115892D01*
G01X1522145Y1112729D02*
X1522146Y1112717D01*
G01X1522148Y1112742D02*
X1522145Y1112729D01*
G01X1522149Y1112756D02*
X1522148Y1112742D01*
G01X1522145Y1109580D02*
X1522146Y1109567D01*
G01X1522148Y1109593D02*
X1522145Y1109580D01*
G01X1522149Y1109606D02*
X1522148Y1109593D01*
G01X1522145Y1106430D02*
X1522146Y1106417D01*
G01X1522148Y1106443D02*
X1522145Y1106430D01*
G01X1522149Y1106456D02*
X1522148Y1106443D01*
G01X1522145Y1103280D02*
X1522146Y1103268D01*
G01X1522148Y1103293D02*
X1522145Y1103280D01*
G01X1522149Y1103307D02*
X1522148Y1103293D01*
G01X1521200Y1103498D02*
X1521201Y1103491D01*
G01X1521200Y1103503D02*
Y1103498D01*
G01X1521199Y1103496D02*
X1521200Y1103503D01*
G01X1521201Y1106644D02*
Y1106640D01*
G01X1521202Y1106638D02*
X1521201Y1106644D01*
G01X1521214Y1106622D02*
X1521202Y1106638D01*
G01X1521239Y1106614D02*
X1521214Y1106622D01*
G01X1521201Y1109794D02*
Y1109790D01*
G01X1521202Y1109787D02*
X1521201Y1109794D01*
G01X1521214Y1109772D02*
X1521202Y1109787D01*
G01X1521238Y1109764D02*
X1521214Y1109772D01*
G01X1521201Y1116093D02*
Y1116089D01*
G01X1521202Y1116087D02*
X1521201Y1116093D01*
G01X1521214Y1116071D02*
X1521202Y1116087D01*
G01X1521238Y1116063D02*
X1521214Y1116071D01*
G01X1521201Y1119243D02*
Y1119239D01*
G01X1521202Y1119236D02*
X1521201Y1119243D01*
G01X1521214Y1119221D02*
X1521202Y1119236D01*
G01X1521238Y1119213D02*
X1521214Y1119221D01*
G01X1521201Y1103494D02*
Y1103491D01*
G01X1521202Y1103488D02*
X1521201Y1103494D01*
G01X1521214Y1103473D02*
X1521202Y1103488D01*
G01X1521238Y1103465D02*
X1521214Y1103473D01*
G01X1521201Y1122392D02*
Y1122388D01*
G01X1521202Y1122386D02*
X1521201Y1122392D01*
G01X1521214Y1122370D02*
X1521202Y1122386D01*
G01X1521238Y1122362D02*
X1521214Y1122370D01*
G01X1521201Y1112943D02*
Y1112939D01*
G01X1521202Y1112938D02*
X1521201Y1112943D01*
G01X1521212Y1112923D02*
X1521202Y1112938D01*
G01X1521235Y1112914D02*
X1521212Y1112923D01*
G01X1521200Y1116096D02*
X1521201Y1116089D01*
G01X1521200Y1116101D02*
Y1116096D01*
G01Y1116092D02*
Y1116101D01*
G01X1521241Y1123728D02*
X1521240Y1123740D01*
G01X1521238Y1123715D02*
X1521241Y1123728D01*
G01X1521238Y1123701D02*
Y1123715D01*
G01X1521241Y1120578D02*
X1521240Y1120591D01*
G01X1521238Y1120565D02*
X1521241Y1120578D01*
G01X1521238Y1120552D02*
Y1120565D01*
G01X1521241Y1117429D02*
X1521240Y1117441D01*
G01X1521238Y1117416D02*
X1521241Y1117429D01*
G01X1521238Y1117402D02*
Y1117416D01*
G01X1521241Y1114279D02*
X1521240Y1114291D01*
G01X1521238Y1114266D02*
X1521241Y1114279D01*
G01X1521238Y1114252D02*
Y1114266D01*
G01X1521241Y1111130D02*
X1521240Y1111142D01*
G01X1521238Y1111117D02*
X1521241Y1111130D01*
G01X1521238Y1111103D02*
Y1111117D01*
G01X1521241Y1107980D02*
X1521240Y1107992D01*
G01X1521238Y1107967D02*
X1521241Y1107980D01*
G01X1521238Y1107953D02*
Y1107967D01*
G01X1521241Y1104830D02*
X1521240Y1104843D01*
G01X1521238Y1104817D02*
X1521241Y1104830D01*
G01X1521238Y1104804D02*
Y1104817D01*
G01X1522154Y1110944D02*
X1522144Y1110945D01*
G01X1522162Y1110941D02*
X1522154Y1110944D01*
G01X1522170Y1110935D02*
X1522162Y1110941D01*
G01X1522154Y1104644D02*
X1522144Y1104646D01*
G01X1522163Y1104641D02*
X1522154Y1104644D01*
G01X1522170Y1104636D02*
X1522163Y1104641D01*
G01X1522154Y1107794D02*
X1522144Y1107795D01*
G01X1522163Y1107791D02*
X1522154Y1107794D01*
G01X1522170Y1107786D02*
X1522163Y1107791D01*
G01X1522154Y1114093D02*
X1522144Y1114094D01*
G01X1522163Y1114090D02*
X1522154Y1114093D01*
G01X1522170Y1114085D02*
X1522163Y1114090D01*
G01X1522154Y1117243D02*
X1522144Y1117244D01*
G01X1522163Y1117240D02*
X1522154Y1117243D01*
G01X1522170Y1117235D02*
X1522163Y1117240D01*
G01X1522154Y1120393D02*
X1522144Y1120394D01*
G01X1522163Y1120389D02*
X1522154Y1120393D01*
G01X1522170Y1120384D02*
X1522163Y1120389D01*
G01X1522154Y1123542D02*
X1522144Y1123543D01*
G01X1522163Y1123539D02*
X1522154Y1123542D01*
G01X1522170Y1123534D02*
X1522163Y1123539D01*
G01X1521240Y1103460D02*
Y1103454D01*
G01X1521239Y1103463D02*
X1521240Y1103460D01*
G01X1521238Y1103465D02*
X1521239Y1103463D01*
G01X1521240Y1106609D02*
Y1106603D01*
G01X1521239Y1106613D02*
X1521240Y1106609D01*
G01X1521238Y1106614D02*
X1521239Y1106613D01*
G01X1521240Y1109759D02*
Y1109753D01*
G01X1521239Y1109763D02*
X1521240Y1109759D01*
G01X1521238Y1109764D02*
X1521239Y1109763D01*
G01X1521240Y1112909D02*
Y1112902D01*
G01X1521239Y1112912D02*
X1521240Y1112909D01*
G01X1521238Y1112913D02*
X1521239Y1112912D01*
G01X1521240Y1116058D02*
Y1116052D01*
G01X1521239Y1116062D02*
X1521240Y1116058D01*
G01X1521238Y1116063D02*
X1521239Y1116062D01*
G01X1521240Y1119208D02*
Y1119202D01*
G01X1521239Y1119211D02*
X1521240Y1119208D01*
G01X1521238Y1119213D02*
X1521239Y1119211D01*
G01X1521240Y1122357D02*
Y1122351D01*
G01X1521239Y1122361D02*
X1521240Y1122357D01*
G01X1521238Y1122362D02*
X1521239Y1122361D01*
G01X1521223Y1103468D02*
X1521238Y1103465D01*
G01X1521210Y1103476D02*
X1521223Y1103468D01*
G01X1521199Y1103496D02*
X1521210Y1103476D01*
G01X1522146Y1103459D02*
Y1103454D01*
G01X1522145Y1103463D02*
X1522146Y1103459D01*
G01X1522144Y1103465D02*
X1522145Y1103463D01*
G01X1522146Y1106609D02*
Y1106603D01*
G01X1522145Y1106613D02*
X1522146Y1106609D01*
G01X1522144Y1106614D02*
X1522145Y1106613D01*
G01X1521219Y1112919D02*
X1521238Y1112913D01*
G01X1521205Y1112931D02*
X1521219Y1112919D01*
G01X1521198Y1112949D02*
X1521205Y1112931D01*
G01X1522178Y1110927D02*
X1522170Y1110935D01*
G01X1522182Y1110917D02*
X1522178Y1110927D01*
G01X1522184Y1110906D02*
X1522182Y1110917D01*
G01X1522178Y1104628D02*
X1522170Y1104636D01*
G01X1522182Y1104617D02*
X1522178Y1104628D01*
G01X1522184Y1104606D02*
X1522182Y1104617D01*
G01X1522178Y1107777D02*
X1522170Y1107786D01*
G01X1522182Y1107767D02*
X1522178Y1107777D01*
G01X1522184Y1107756D02*
X1522182Y1107767D01*
G01X1522178Y1114076D02*
X1522170Y1114085D01*
G01X1522182Y1114066D02*
X1522178Y1114076D01*
G01X1522184Y1114055D02*
X1522182Y1114066D01*
G01X1522178Y1117226D02*
X1522170Y1117235D01*
G01X1522182Y1117216D02*
X1522178Y1117226D01*
G01X1522184Y1117205D02*
X1522182Y1117216D01*
G01X1522178Y1120376D02*
X1522170Y1120384D01*
G01X1522182Y1120365D02*
X1522178Y1120376D01*
G01X1522184Y1120354D02*
X1522182Y1120365D01*
G01X1522178Y1123525D02*
X1522170Y1123534D01*
G01X1522182Y1123515D02*
X1522178Y1123525D01*
G01X1522184Y1123504D02*
X1522182Y1123515D01*
G01X1521224Y1106617D02*
X1521238Y1106614D01*
G01X1521212Y1106624D02*
X1521224Y1106617D01*
G01X1521200Y1106643D02*
X1521212Y1106624D01*
G01X1521224Y1116066D02*
X1521238Y1116063D01*
G01X1521212Y1116073D02*
X1521224Y1116066D01*
G01X1521200Y1116091D02*
X1521212Y1116073D01*
G01X1521223Y1109767D02*
X1521238Y1109764D01*
G01X1521211Y1109774D02*
X1521223Y1109767D01*
G01X1521199Y1109794D02*
X1521211Y1109774D01*
G01X1521223Y1119215D02*
X1521238Y1119213D01*
G01X1521211Y1119223D02*
X1521223Y1119215D01*
G01X1521199Y1119243D02*
X1521211Y1119223D01*
G01X1522185Y1103498D02*
Y1103491D01*
G01X1522184Y1103503D02*
X1522185Y1103498D01*
G01X1522183Y1103504D02*
X1522184Y1103503D01*
G01X1522185Y1106648D02*
Y1106640D01*
G01X1522184Y1106652D02*
X1522185Y1106648D01*
G01X1522183Y1106654D02*
X1522184Y1106652D01*
G01X1522185Y1109797D02*
Y1109790D01*
G01X1522184Y1109802D02*
X1522185Y1109797D01*
G01X1522183Y1109803D02*
X1522184Y1109802D01*
G01X1522185Y1112947D02*
Y1112939D01*
G01X1522184Y1112952D02*
X1522185Y1112947D01*
G01X1522183Y1112953D02*
X1522184Y1112952D01*
G01X1522185Y1116096D02*
Y1116089D01*
G01X1522184Y1116101D02*
X1522185Y1116096D01*
G01X1522183Y1116102D02*
X1522184Y1116101D01*
G01X1522185Y1119246D02*
Y1119239D01*
G01X1522184Y1119251D02*
X1522185Y1119246D01*
G01X1522183Y1119252D02*
X1522184Y1119251D01*
G01X1522185Y1122396D02*
Y1122388D01*
G01X1522184Y1122400D02*
X1522185Y1122396D01*
G01X1522183Y1122402D02*
X1522184Y1122400D01*
G01X1521223Y1122365D02*
X1521238Y1122362D01*
G01X1521211Y1122373D02*
X1521223Y1122365D01*
G01X1521199Y1122393D02*
X1521211Y1122373D01*
G01X1522184Y1104627D02*
X1522185Y1104620D01*
G01X1522183Y1104633D02*
X1522184Y1104627D01*
G01X1522180Y1104639D02*
X1522183Y1104633D01*
G01X1522184Y1107776D02*
X1522185Y1107770D01*
G01X1522183Y1107783D02*
X1522184Y1107776D01*
G01X1522180Y1107789D02*
X1522183Y1107783D01*
G01X1522184Y1110926D02*
X1522185Y1110919D01*
G01X1522183Y1110932D02*
X1522184Y1110926D01*
G01X1522180Y1110938D02*
X1522183Y1110932D01*
G01X1522184Y1114076D02*
X1522185Y1114069D01*
G01X1522183Y1114082D02*
X1522184Y1114076D01*
G01X1522180Y1114088D02*
X1522183Y1114082D01*
G01X1522184Y1117225D02*
X1522185Y1117219D01*
G01X1522183Y1117231D02*
X1522184Y1117225D01*
G01X1522180Y1117237D02*
X1522183Y1117231D01*
G01X1522184Y1120375D02*
X1522185Y1120368D01*
G01X1522183Y1120381D02*
X1522184Y1120375D01*
G01X1522180Y1120387D02*
X1522183Y1120381D01*
G01X1522184Y1123524D02*
X1522185Y1123518D01*
G01X1522183Y1123531D02*
X1522184Y1123524D01*
G01X1522180Y1123537D02*
X1522183Y1123531D01*
G01X1522146Y1109759D02*
Y1109753D01*
G01X1522145Y1109763D02*
X1522146Y1109759D01*
G01X1522144Y1109764D02*
X1522145Y1109763D01*
G01X1522146Y1112908D02*
Y1112902D01*
G01X1522145Y1112912D02*
X1522146Y1112908D01*
G01X1522144Y1112913D02*
X1522145Y1112912D01*
G01X1522146Y1116058D02*
Y1116052D01*
G01X1522145Y1116062D02*
X1522146Y1116058D01*
G01X1522144Y1116063D02*
X1522145Y1116062D01*
G01X1522146Y1122357D02*
Y1122351D01*
G01X1522145Y1122361D02*
X1522146Y1122357D01*
G01X1522144Y1122362D02*
X1522145Y1122361D01*
G01X1522144Y1119213D02*
X1522148Y1119202D01*
G01X1522638Y1204744D02*
Y1125709D01*
G01X1522185Y1122205D02*
Y1123701D01*
G01Y1119055D02*
Y1120551D01*
G01Y1115906D02*
Y1117402D01*
G01Y1112756D02*
Y1114252D01*
G01Y1109606D02*
Y1111102D01*
G01Y1106457D02*
Y1107953D01*
G01Y1103307D02*
Y1104803D01*
G01X1522146Y1106603D02*
Y1106456D01*
G01Y1103454D02*
Y1103307D01*
G01Y1104804D02*
Y1104657D01*
G01Y1109753D02*
Y1109606D01*
G01Y1111103D02*
Y1110956D01*
G01Y1107953D02*
Y1107807D01*
G01Y1116052D02*
Y1115905D01*
G01Y1112902D02*
Y1112756D01*
G01Y1114252D02*
Y1114106D01*
G01Y1119202D02*
Y1119055D01*
G01Y1120552D02*
Y1120405D01*
G01Y1117402D02*
Y1117256D01*
G01Y1122351D02*
Y1122204D01*
G01Y1123701D02*
Y1123555D01*
G01X1521240Y1122204D02*
Y1122351D01*
G01Y1123555D02*
Y1123702D01*
G01Y1119054D02*
Y1119202D01*
G01Y1120405D02*
Y1120552D01*
G01Y1117256D02*
Y1117402D01*
G01Y1115905D02*
Y1116052D01*
G01Y1112755D02*
Y1112902D01*
G01Y1114106D02*
Y1114253D01*
G01Y1109606D02*
Y1109753D01*
G01Y1110956D02*
Y1111103D01*
G01Y1107807D02*
Y1107954D01*
G01Y1106456D02*
Y1106603D01*
G01Y1103306D02*
Y1103454D01*
G01Y1104657D02*
Y1104804D01*
G01X1521201Y1104803D02*
Y1103307D01*
G01Y1111102D02*
Y1109606D01*
G01Y1107953D02*
Y1106457D01*
G01Y1114252D02*
Y1112756D01*
G01Y1120551D02*
Y1119055D01*
G01Y1117402D02*
Y1115906D01*
G01Y1123701D02*
Y1122205D01*
G01X1520020Y1107795D02*
Y1106614D01*
G01Y1104646D02*
Y1103465D01*
G01Y1110945D02*
Y1109764D01*
G01Y1117244D02*
Y1116063D01*
G01Y1114094D02*
Y1112913D01*
G01Y1120394D02*
Y1119213D01*
G01Y1123543D02*
Y1122362D01*
G01X1519685Y1125709D02*
Y1101299D01*
G01X1519291D02*
Y1125709D01*
G01X1522185Y1122388D02*
Y1122399D01*
G01Y1119239D02*
Y1119250D01*
G01Y1116089D02*
Y1116100D01*
G01Y1112939D02*
Y1112950D01*
G01Y1109790D02*
Y1109801D01*
G01Y1106640D02*
Y1106651D01*
G01Y1103491D02*
Y1103502D01*
G01Y1104609D02*
Y1104620D01*
G01Y1107758D02*
Y1107769D01*
G01Y1110908D02*
Y1110919D01*
G01Y1114057D02*
Y1114069D01*
G01Y1117207D02*
Y1117218D01*
G01Y1120357D02*
Y1120368D01*
G01Y1123506D02*
Y1123517D01*
G01X1516260Y1122362D02*
Y1123543D01*
G01Y1119213D02*
Y1120394D01*
G01Y1116063D02*
Y1117244D01*
G01Y1112913D02*
Y1114094D01*
G01Y1109764D02*
Y1110945D01*
G01Y1106614D02*
Y1107795D01*
G01Y1103465D02*
Y1104646D01*
G01X1521087Y1122402D02*
X1521199Y1122393D01*
G01X1521198Y1112949D02*
X1521087Y1112953D01*
G01X1521198Y1106650D02*
X1521087Y1106654D01*
G01X1521198Y1116099D02*
X1521087Y1116102D01*
G01X1522638Y1125709D02*
X1519291D01*
G01X1522146Y1123740D02*
X1521240D01*
G01X1522185Y1123701D02*
X1521201D01*
G01X1522144Y1123543D02*
X1516260D01*
G01Y1123504D02*
X1522184D01*
G01X1522183Y1122402D02*
X1516260D01*
G01X1522144Y1122362D02*
X1516260D01*
G01X1521201Y1122205D02*
X1522185D01*
G01X1521240Y1122165D02*
X1522146D01*
G01Y1120591D02*
X1521240D01*
G01X1522185Y1120551D02*
X1521201D01*
G01X1522144Y1120394D02*
X1516260D01*
G01Y1120354D02*
X1522184D01*
G01X1522183Y1119252D02*
X1516260D01*
G01X1522144Y1119213D02*
X1516260D01*
G01X1521201Y1119055D02*
X1522185D01*
G01X1521240Y1119016D02*
X1522146D01*
G01Y1117441D02*
X1521240D01*
G01X1522185Y1117402D02*
X1521201D01*
G01X1522144Y1117244D02*
X1516260D01*
G01Y1117205D02*
X1522184D01*
G01X1520454Y1116102D02*
X1520020D01*
G01X1522183D02*
X1516260D01*
G01X1522144Y1116063D02*
X1516260D01*
G01X1521201Y1115906D02*
X1522185D01*
G01X1521240Y1115866D02*
X1522146D01*
G01Y1114291D02*
X1521240D01*
G01X1522185Y1114252D02*
X1521201D01*
G01X1522144Y1114094D02*
X1516260D01*
G01Y1114055D02*
X1522184D01*
G01X1520454Y1112953D02*
X1520020D01*
G01X1522183D02*
X1516260D01*
G01X1522144Y1112913D02*
X1516260D01*
G01X1521201Y1112756D02*
X1522185D01*
G01X1521240Y1112717D02*
X1522146D01*
G01Y1111142D02*
X1521240D01*
G01X1522185Y1111102D02*
X1521201D01*
G01X1522144Y1110945D02*
X1516260D01*
G01Y1110906D02*
X1522184D01*
G01X1522183Y1109803D02*
X1516260D01*
G01X1522144Y1109764D02*
X1516260D01*
G01X1521201Y1109606D02*
X1522185D01*
G01X1521240Y1109567D02*
X1522146D01*
G01Y1107992D02*
X1521240D01*
G01X1522185Y1107953D02*
X1521201D01*
G01X1522144Y1107795D02*
X1516260D01*
G01Y1107756D02*
X1522184D01*
G01X1520454Y1106654D02*
X1520020D01*
G01X1522183D02*
X1516260D01*
G01X1522144Y1106614D02*
X1516260D01*
G01X1521201Y1106457D02*
X1522185D01*
G01X1521240Y1106417D02*
X1522146D01*
G01Y1104843D02*
X1521240D01*
G01X1522185Y1104803D02*
X1521201D01*
G01X1522144Y1104646D02*
X1516260D01*
G01Y1104606D02*
X1522184D01*
G01X1522183Y1103504D02*
X1516260D01*
G01X1522144Y1103465D02*
X1516260D01*
G01X1521201Y1103307D02*
X1522185D01*
G01X1521240Y1103268D02*
X1522146D01*
G01X1522638Y1101299D02*
X1519291D01*
G01X1521260Y1223563D02*
G03X1519291Y1221594I0J-1969D01*
G01Y1205846D02*
X1522638Y1202500D01*
G01X1519291Y1221594D02*
Y1205846D01*
G01X1538976Y1223563D02*
X1521260D01*
G01X1540945Y1213130D02*
X1519291D01*
G01X1522638Y1204744D02*
X1537008D01*
G01X1522638Y1203366D02*
X1526378D01*
G01X1522638Y1202500D02*
X1537598D01*
G01X1491339Y1274016D02*
G03X1490157I-591J0D01*
G01X1488189D02*
G03X1487008I-591J0D01*
G01X1491339D02*
G03X1490157I-591J0D01*
G01X1488189D02*
G03X1487008I-591J0D01*
G01X1486220Y1275197D02*
X1492126D01*
G01Y1275000D02*
X1486220D01*
G01X1491339Y1274016D02*
X1492126D01*
G01X1491339D02*
X1492126D01*
G01X1488189D02*
X1490157D01*
G01X1486220D02*
X1487008D01*
G01X1488189D02*
X1490157D01*
G01X1486220D02*
X1487008D01*
G01X1492126D02*
Y1280315D01*
G01Y1274016D02*
Y1280315D01*
G01X1486220Y1274016D02*
Y1280315D01*
G01D02*
Y1274016D01*
G01X1490157Y1280315D02*
G03X1491339I591J0D01*
G01X1487008D02*
G03X1488189I591J0D01*
G01X1490157D02*
G03X1491339I591J0D01*
G01X1487008D02*
G03X1488189I591J0D01*
G01X1490157D02*
X1488189D01*
G01X1487008D02*
X1486220D01*
G01X1490157D02*
X1488189D01*
G01X1487008D02*
X1486220D01*
G01X1492126D02*
X1491339D01*
G01X1492126D02*
X1491339D01*
G01X1492126Y1279331D02*
X1486220D01*
G01Y1279134D02*
X1492126D01*
G01X1509310Y1656868D02*
Y1659668D01*
G01X1477815Y1656868D02*
Y1659668D01*
G01X1551181Y3937D02*
G03X1562992Y-7874I11811J0D01*
G01X1551181Y51181D02*
Y3937D01*
G01X1562992Y-7874D02*
X1593701D01*
G01X1562992Y0D02*
X1930906D01*
G01X1559055Y3937D02*
G03X1562992Y0I3937J0D01*
G01X1559055Y55118D02*
Y3937D01*
G01X1562992Y-7874D02*
X1593701D01*
G01X1551181Y3937D02*
G03X1562992Y-7874I11811J0D01*
G01X1551181Y51181D02*
Y3937D01*
G01X1559055D02*
G03X1562992Y0I3937J0D01*
G01X1559055Y55118D02*
Y3937D01*
G01X1562992Y0D02*
X1930906D01*
G01X1559055Y55118D02*
G03X1555118Y59055I-3937J0D01*
G01X1559055Y55118D02*
G03X1555118Y59055I-3937J0D01*
G01X1531220Y153681D02*
G03I-1102J0D01*
G01X1531693D02*
G03I-1575J0D01*
G01X1526181Y139311D02*
G03X1526772Y138720I591J0D01*
G01X1533465D02*
G03X1534055Y139311I-1J591D01*
G01X1531299Y140492D02*
G03Y142461I0J984D01*
G01X1528937D02*
G03Y140492I0J-984D01*
G01X1532677Y148406D02*
G03X1533858Y149587I0J1181D01*
G01X1526378D02*
G03X1527559Y148406I1181J0D01*
G01X1538976Y137933D02*
G03X1540945Y139902I0J1969D01*
G01X1525591Y161673D02*
X1524409Y160492D01*
G01X1532603Y156752D02*
X1531299Y154783D01*
G01X1526627Y148861D02*
X1528937Y153091D01*
G01X1540945Y139902D02*
Y155650D01*
G01X1537598Y296988D02*
Y158996D01*
G01X1537008Y299232D02*
Y156752D01*
G01X1534055Y145413D02*
Y139311D01*
G01X1533858Y158130D02*
Y149587D01*
G01X1532283Y196949D02*
Y160492D01*
G01X1531299Y154783D02*
Y153091D01*
G01X1531102Y198130D02*
Y161673D01*
G01X1528937Y153091D02*
Y154783D01*
G01X1526378Y149587D02*
Y158130D01*
G01X1526181Y145413D02*
Y139311D01*
G01X1525591Y161673D02*
Y294311D01*
G01X1524409Y160492D02*
Y295492D01*
G01X1531299Y153091D02*
X1533609Y148861D01*
G01X1528937Y154783D02*
X1527633Y156752D01*
G01X1537598Y158996D02*
X1540945Y155650D01*
G01X1531102Y161673D02*
X1532283Y160492D01*
G01X1531102Y161673D02*
X1525591D01*
G01X1532283Y160492D02*
X1524409D01*
G01X1533858Y158130D02*
X1537008D01*
G01X1531299Y154783D02*
X1528937D01*
G01X1531299Y153091D02*
X1528937D01*
G01X1532677Y148406D02*
X1527559D01*
G01X1534055Y145413D02*
X1526181D01*
G01Y143839D02*
X1534055D01*
G01X1531299Y142461D02*
X1528937D01*
G01Y140492D02*
X1531299D01*
G01X1533465Y138720D02*
X1526772D01*
G01X1535598Y166173D02*
X1535609Y166157D01*
G01X1535573Y166181D02*
X1535598Y166173D01*
G01Y171173D02*
X1535609Y171157D01*
G01X1535573Y171181D02*
X1535598Y171173D01*
G01Y176173D02*
X1535609Y176157D01*
G01X1535573Y176181D02*
X1535598Y176173D01*
G01Y181173D02*
X1535609Y181157D01*
G01X1535573Y181181D02*
X1535598Y181173D01*
G01Y186173D02*
X1535609Y186157D01*
G01X1535573Y186181D02*
X1535598Y186173D01*
G01Y191173D02*
X1535609Y191157D01*
G01X1535573Y191181D02*
X1535598Y191173D01*
G01Y196173D02*
X1535609Y196157D01*
G01X1535573Y196181D02*
X1535598Y196173D01*
G01X1535611Y166148D02*
X1535610Y166156D01*
G01X1535611Y166144D02*
Y166148D01*
G01X1535613Y166142D02*
X1535611Y166144D01*
G01Y171148D02*
X1535610Y171156D01*
G01X1535611Y171144D02*
Y171148D01*
G01X1535613Y171142D02*
X1535611Y171144D01*
G01Y176148D02*
X1535610Y176156D01*
G01X1535611Y176144D02*
Y176148D01*
G01X1535613Y176142D02*
X1535611Y176144D01*
G01Y181148D02*
X1535610Y181156D01*
G01X1535611Y181144D02*
Y181148D01*
G01X1535613Y181142D02*
X1535611Y181144D01*
G01Y186148D02*
X1535610Y186156D01*
G01X1535611Y186144D02*
Y186148D01*
G01X1535613Y186142D02*
X1535611Y186144D01*
G01Y191148D02*
X1535610Y191156D01*
G01X1535611Y191144D02*
Y191148D01*
G01X1535613Y191142D02*
X1535611Y191144D01*
G01Y196148D02*
X1535610Y196156D01*
G01X1535611Y196144D02*
Y196148D01*
G01X1535613Y196142D02*
X1535611Y196144D01*
G01X1534626Y166189D02*
Y166198D01*
G01X1534627Y166183D02*
X1534626Y166189D01*
G01X1534628Y166181D02*
X1534627Y166183D01*
G01X1534626Y171189D02*
Y171198D01*
G01X1534627Y171183D02*
X1534626Y171189D01*
G01X1534628Y171181D02*
X1534627Y171183D01*
G01X1534626Y176189D02*
Y176198D01*
G01X1534627Y176183D02*
X1534626Y176189D01*
G01X1534628Y176181D02*
X1534627Y176183D01*
G01X1534626Y181189D02*
Y181198D01*
G01X1534627Y181183D02*
X1534626Y181189D01*
G01X1534628Y181181D02*
X1534627Y181183D01*
G01X1534626Y186189D02*
Y186198D01*
G01X1534627Y186183D02*
X1534626Y186189D01*
G01X1534628Y186181D02*
X1534627Y186183D01*
G01X1534626Y191189D02*
Y191198D01*
G01X1534627Y191183D02*
X1534626Y191189D01*
G01X1534628Y191181D02*
X1534627Y191183D01*
G01X1535602Y166325D02*
X1535610Y166299D01*
G01X1535593Y166352D02*
X1535602Y166325D01*
G01X1535581Y166378D02*
X1535593Y166352D01*
G01X1535602Y171325D02*
X1535610Y171299D01*
G01X1535593Y171352D02*
X1535602Y171325D01*
G01X1535581Y171378D02*
X1535593Y171352D01*
G01X1534626Y196189D02*
Y196198D01*
G01X1534627Y196183D02*
X1534626Y196189D01*
G01X1534628Y196181D02*
X1534627Y196183D01*
G01X1535602Y176325D02*
X1535610Y176299D01*
G01X1535593Y176352D02*
X1535602Y176325D01*
G01X1535581Y176378D02*
X1535593Y176352D01*
G01X1535602Y181325D02*
X1535610Y181299D01*
G01X1535593Y181352D02*
X1535602Y181325D01*
G01X1535581Y181378D02*
X1535593Y181352D01*
G01X1535602Y186325D02*
X1535610Y186299D01*
G01X1535593Y186352D02*
X1535602Y186325D01*
G01X1535581Y186378D02*
X1535593Y186352D01*
G01X1535602Y191325D02*
X1535610Y191299D01*
G01X1535593Y191352D02*
X1535602Y191325D01*
G01X1535581Y191378D02*
X1535593Y191352D01*
G01X1535602Y196325D02*
X1535610Y196299D01*
G01X1535593Y196352D02*
X1535602Y196325D01*
G01X1535581Y196378D02*
X1535593Y196352D01*
G01Y166176D02*
X1535574Y166181D01*
G01X1535607Y166162D02*
X1535593Y166176D01*
G01X1535613Y166142D02*
X1535607Y166162D01*
G01X1535593Y171176D02*
X1535574Y171181D01*
G01X1535607Y171162D02*
X1535593Y171176D01*
G01X1535613Y171142D02*
X1535607Y171162D01*
G01X1535593Y176176D02*
X1535574Y176181D01*
G01X1535607Y176162D02*
X1535593Y176176D01*
G01X1535613Y176142D02*
X1535607Y176162D01*
G01X1535593Y181176D02*
X1535574Y181181D01*
G01X1535607Y181162D02*
X1535593Y181176D01*
G01X1535613Y181142D02*
X1535607Y181162D01*
G01X1535593Y186176D02*
X1535574Y186181D01*
G01X1535607Y186162D02*
X1535593Y186176D01*
G01X1535613Y186142D02*
X1535607Y186162D01*
G01X1535593Y191176D02*
X1535574Y191181D01*
G01X1535607Y191162D02*
X1535593Y191176D01*
G01X1535613Y191142D02*
X1535607Y191162D01*
G01X1535593Y196176D02*
X1535574Y196181D01*
G01X1535607Y196162D02*
X1535593Y196176D01*
G01X1535613Y196142D02*
X1535607Y196162D01*
G01X1535577Y166279D02*
X1535581Y166378D01*
G01X1535572Y166207D02*
X1535577Y166279D01*
G01X1535574Y166181D02*
X1535572Y166207D01*
G01X1535577Y171279D02*
X1535581Y171378D01*
G01X1535572Y171207D02*
X1535577Y171279D01*
G01X1535574Y171181D02*
X1535572Y171207D01*
G01X1535577Y176279D02*
X1535581Y176378D01*
G01X1535572Y176207D02*
X1535577Y176279D01*
G01X1535574Y176181D02*
X1535572Y176207D01*
G01X1535577Y181279D02*
X1535581Y181378D01*
G01X1535572Y181207D02*
X1535577Y181279D01*
G01X1535574Y181181D02*
X1535572Y181207D01*
G01X1535577Y186279D02*
X1535581Y186378D01*
G01X1535572Y186207D02*
X1535577Y186279D01*
G01X1535574Y186181D02*
X1535572Y186207D01*
G01X1535577Y191279D02*
X1535581Y191378D01*
G01X1535572Y191207D02*
X1535577Y191279D01*
G01X1535574Y191181D02*
X1535572Y191207D01*
G01X1535577Y196279D02*
X1535581Y196378D01*
G01X1535572Y196207D02*
X1535577Y196279D01*
G01X1535574Y196181D02*
X1535572Y196207D01*
G01X1534627Y194802D02*
X1534628Y194803D01*
G01X1534626Y194796D02*
X1534627Y194802D01*
G01X1534626Y194787D02*
Y194796D01*
G01X1534627Y189802D02*
X1534628Y189803D01*
G01X1534626Y189796D02*
X1534627Y189802D01*
G01X1534626Y189787D02*
Y189796D01*
G01X1534627Y184802D02*
X1534628Y184803D01*
G01X1534626Y184796D02*
X1534627Y184802D01*
G01X1534626Y184787D02*
Y184796D01*
G01X1534627Y179802D02*
X1534628Y179803D01*
G01X1534626Y179796D02*
X1534627Y179802D01*
G01X1534626Y179787D02*
Y179796D01*
G01X1534627Y174802D02*
X1534628Y174803D01*
G01X1534626Y174796D02*
X1534627Y174802D01*
G01X1534626Y174787D02*
Y174796D01*
G01X1534627Y169802D02*
X1534628Y169803D01*
G01X1534626Y169796D02*
X1534627Y169802D01*
G01X1534626Y169787D02*
Y169796D01*
G01X1534627Y164802D02*
X1534628Y164803D01*
G01X1534626Y164796D02*
X1534627Y164802D01*
G01X1534626Y164787D02*
Y164796D01*
G01X1535611Y194796D02*
X1535610Y194787D01*
G01X1535611Y194802D02*
Y194796D01*
G01X1535613Y194803D02*
X1535611Y194802D01*
G01Y189796D02*
X1535610Y189787D01*
G01X1535611Y189802D02*
Y189796D01*
G01X1535613Y189803D02*
X1535611Y189802D01*
G01Y184796D02*
X1535610Y184787D01*
G01X1535611Y184802D02*
Y184796D01*
G01X1535613Y184803D02*
X1535611Y184802D01*
G01Y179796D02*
X1535610Y179787D01*
G01X1535611Y179802D02*
Y179796D01*
G01X1535613Y179803D02*
X1535611Y179802D01*
G01Y174796D02*
X1535610Y174787D01*
G01X1535611Y174802D02*
Y174796D01*
G01X1535613Y174803D02*
X1535611Y174802D01*
G01Y169796D02*
X1535610Y169787D01*
G01X1535611Y169802D02*
Y169796D01*
G01X1535613Y169803D02*
X1535611Y169802D01*
G01Y164796D02*
X1535610Y164787D01*
G01X1535611Y164802D02*
Y164796D01*
G01X1535613Y164803D02*
X1535611Y164802D01*
G01X1535610Y166155D02*
X1535611Y166164D01*
G01X1535610Y171155D02*
X1535611Y171164D01*
G01X1535610Y176155D02*
X1535611Y176164D01*
G01X1535610Y181155D02*
X1535611Y181164D01*
G01X1535610Y186155D02*
X1535611Y186164D01*
G01X1535610Y191155D02*
X1535611Y191164D01*
G01X1535610Y196155D02*
X1535611Y196164D01*
G01X1539961Y194803D02*
Y196181D01*
G01Y189803D02*
Y191181D01*
G01Y184803D02*
Y186181D01*
G01Y179803D02*
Y181181D01*
G01Y174803D02*
Y176181D01*
G01Y169803D02*
Y171181D01*
G01Y164803D02*
Y166181D01*
G01X1536791D02*
Y164803D01*
G01Y171181D02*
Y169803D01*
G01Y176181D02*
Y174803D01*
G01Y181181D02*
Y179803D01*
G01Y186181D02*
Y184803D01*
G01Y191181D02*
Y189803D01*
G01Y196181D02*
Y194803D01*
G01X1536220Y219035D02*
Y196949D01*
G01X1535610Y166156D02*
Y166299D01*
G01Y171156D02*
Y171299D01*
G01Y176156D02*
Y176299D01*
G01Y181156D02*
Y181299D01*
G01Y186156D02*
Y186299D01*
G01Y191156D02*
Y191299D01*
G01Y196156D02*
Y196299D01*
G01Y194311D02*
Y196673D01*
G01Y189311D02*
Y191673D01*
G01Y184311D02*
Y186673D01*
G01Y179311D02*
Y181673D01*
G01Y174311D02*
Y176673D01*
G01Y169311D02*
Y171673D01*
G01Y164311D02*
Y166673D01*
G01X1535039Y217854D02*
Y198130D01*
G01X1534626Y166673D02*
Y164311D01*
G01Y171673D02*
Y169311D01*
G01Y176673D02*
Y174311D01*
G01Y181673D02*
Y179311D01*
G01Y186673D02*
Y184311D01*
G01Y191673D02*
Y189311D01*
G01Y196673D02*
Y194311D01*
G01X1535039Y198130D02*
X1536220Y196949D01*
G01X1531102Y198130D02*
X1532283Y196949D01*
G01X1535039Y198130D02*
X1531102D01*
G01X1536220Y196949D02*
X1532283D01*
G01X1535610Y196673D02*
X1534626D01*
G01X1534628Y196181D02*
X1539961D01*
G01Y196142D02*
X1535613D01*
G01X1539961Y194803D02*
X1534628D01*
G01X1534626Y194311D02*
X1535610D01*
G01Y191673D02*
X1534626D01*
G01X1534628Y191181D02*
X1539961D01*
G01Y191142D02*
X1535613D01*
G01X1539961Y189803D02*
X1534628D01*
G01X1534626Y189311D02*
X1535610D01*
G01Y186673D02*
X1534626D01*
G01X1534628Y186181D02*
X1539961D01*
G01Y186142D02*
X1535613D01*
G01X1539961Y184803D02*
X1534628D01*
G01X1534626Y184311D02*
X1535610D01*
G01Y181673D02*
X1534626D01*
G01X1534628Y181181D02*
X1539961D01*
G01Y181142D02*
X1535613D01*
G01X1539961Y179803D02*
X1534628D01*
G01X1534626Y179311D02*
X1535610D01*
G01Y176673D02*
X1534626D01*
G01X1534628Y176181D02*
X1539961D01*
G01Y176142D02*
X1535613D01*
G01X1539961Y174803D02*
X1534628D01*
G01X1534626Y174311D02*
X1535610D01*
G01Y171673D02*
X1534626D01*
G01X1534628Y171181D02*
X1539961D01*
G01Y171142D02*
X1535613D01*
G01X1539961Y169803D02*
X1534628D01*
G01X1534626Y169311D02*
X1535610D01*
G01X1534626Y196377D02*
X1535581Y196378D01*
G01X1535610Y194607D02*
X1534626Y194606D01*
G01Y191377D02*
X1535581Y191378D01*
G01X1535610Y189607D02*
X1534626Y189606D01*
G01Y186377D02*
X1535581Y186378D01*
G01X1535610Y184607D02*
X1534626Y184606D01*
G01Y181377D02*
X1535581Y181378D01*
G01X1535610Y179607D02*
X1534626Y179606D01*
G01Y176377D02*
X1535581Y176378D01*
G01X1535610Y174607D02*
X1534626Y174606D01*
G01Y171377D02*
X1535581Y171378D01*
G01X1535610Y169607D02*
X1534626Y169606D01*
G01X1535610Y166673D02*
X1534626D01*
G01X1534628Y166181D02*
X1539961D01*
G01Y166142D02*
X1535613D01*
G01X1539961Y164803D02*
X1534628D01*
G01X1534626Y164311D02*
X1535610D01*
G01X1534626Y166377D02*
X1535581Y166378D01*
G01X1535610Y164607D02*
X1534626Y164606D01*
G01X1535598Y221173D02*
X1535609Y221157D01*
G01X1535573Y221181D02*
X1535598Y221173D01*
G01Y226173D02*
X1535609Y226157D01*
G01X1535573Y226181D02*
X1535598Y226173D01*
G01Y231173D02*
X1535609Y231157D01*
G01X1535573Y231181D02*
X1535598Y231173D01*
G01Y236173D02*
X1535609Y236157D01*
G01X1535573Y236181D02*
X1535598Y236173D01*
G01Y241173D02*
X1535609Y241157D01*
G01X1535573Y241181D02*
X1535598Y241173D01*
G01Y246173D02*
X1535609Y246157D01*
G01X1535573Y246181D02*
X1535598Y246173D01*
G01Y251173D02*
X1535609Y251157D01*
G01X1535573Y251181D02*
X1535598Y251173D01*
G01Y256173D02*
X1535609Y256157D01*
G01X1535573Y256181D02*
X1535598Y256173D01*
G01X1535611Y221148D02*
X1535610Y221156D01*
G01X1535611Y221144D02*
Y221148D01*
G01X1535613Y221142D02*
X1535611Y221144D01*
G01Y226148D02*
X1535610Y226156D01*
G01X1535611Y226144D02*
Y226148D01*
G01X1535613Y226142D02*
X1535611Y226144D01*
G01Y231148D02*
X1535610Y231156D01*
G01X1535611Y231144D02*
Y231148D01*
G01X1535613Y231142D02*
X1535611Y231144D01*
G01Y236148D02*
X1535610Y236156D01*
G01X1535611Y236144D02*
Y236148D01*
G01X1535613Y236142D02*
X1535611Y236144D01*
G01Y241148D02*
X1535610Y241156D01*
G01X1535611Y241144D02*
Y241148D01*
G01X1535613Y241142D02*
X1535611Y241144D01*
G01Y246148D02*
X1535610Y246156D01*
G01X1535611Y246144D02*
Y246148D01*
G01X1535613Y246142D02*
X1535611Y246144D01*
G01Y251148D02*
X1535610Y251156D01*
G01X1535611Y251144D02*
Y251148D01*
G01X1535613Y251142D02*
X1535611Y251144D01*
G01Y256148D02*
X1535610Y256156D01*
G01X1535611Y256144D02*
Y256148D01*
G01X1535613Y256142D02*
X1535611Y256144D01*
G01X1534626Y221189D02*
Y221198D01*
G01X1534627Y221183D02*
X1534626Y221189D01*
G01X1534628Y221181D02*
X1534627Y221183D01*
G01X1534626Y226189D02*
Y226198D01*
G01X1534627Y226183D02*
X1534626Y226189D01*
G01X1534628Y226181D02*
X1534627Y226183D01*
G01X1534626Y231189D02*
Y231198D01*
G01X1534627Y231183D02*
X1534626Y231189D01*
G01X1534628Y231181D02*
X1534627Y231183D01*
G01X1534626Y236189D02*
Y236198D01*
G01X1534627Y236183D02*
X1534626Y236189D01*
G01X1534628Y236181D02*
X1534627Y236183D01*
G01X1534626Y241189D02*
Y241198D01*
G01X1534627Y241183D02*
X1534626Y241189D01*
G01X1534628Y241181D02*
X1534627Y241183D01*
G01X1534626Y246189D02*
Y246198D01*
G01X1534627Y246183D02*
X1534626Y246189D01*
G01X1534628Y246181D02*
X1534627Y246183D01*
G01X1534626Y251189D02*
Y251198D01*
G01X1534627Y251183D02*
X1534626Y251189D01*
G01X1534628Y251181D02*
X1534627Y251183D01*
G01X1534626Y256189D02*
Y256198D01*
G01X1534627Y256183D02*
X1534626Y256189D01*
G01X1534628Y256181D02*
X1534627Y256183D01*
G01X1535602Y221325D02*
X1535610Y221299D01*
G01X1535593Y221352D02*
X1535602Y221325D01*
G01X1535581Y221378D02*
X1535593Y221352D01*
G01X1535602Y226325D02*
X1535610Y226299D01*
G01X1535593Y226352D02*
X1535602Y226325D01*
G01X1535581Y226378D02*
X1535593Y226352D01*
G01X1535602Y231325D02*
X1535610Y231299D01*
G01X1535593Y231352D02*
X1535602Y231325D01*
G01X1535581Y231378D02*
X1535593Y231352D01*
G01X1535602Y236325D02*
X1535610Y236299D01*
G01X1535593Y236352D02*
X1535602Y236325D01*
G01X1535581Y236378D02*
X1535593Y236352D01*
G01X1535602Y241325D02*
X1535610Y241299D01*
G01X1535593Y241352D02*
X1535602Y241325D01*
G01X1535581Y241378D02*
X1535593Y241352D01*
G01X1535602Y246325D02*
X1535610Y246299D01*
G01X1535593Y246352D02*
X1535602Y246325D01*
G01X1535581Y246378D02*
X1535593Y246352D01*
G01X1535602Y251325D02*
X1535610Y251299D01*
G01X1535593Y251352D02*
X1535602Y251325D01*
G01X1535581Y251378D02*
X1535593Y251352D01*
G01X1535602Y256325D02*
X1535610Y256299D01*
G01X1535593Y256352D02*
X1535602Y256325D01*
G01X1535581Y256378D02*
X1535593Y256352D01*
G01Y221176D02*
X1535574Y221181D01*
G01X1535607Y221162D02*
X1535593Y221176D01*
G01X1535613Y221142D02*
X1535607Y221162D01*
G01X1535593Y226176D02*
X1535574Y226181D01*
G01X1535607Y226162D02*
X1535593Y226176D01*
G01X1535613Y226142D02*
X1535607Y226162D01*
G01X1535593Y231176D02*
X1535574Y231181D01*
G01X1535607Y231162D02*
X1535593Y231176D01*
G01X1535613Y231142D02*
X1535607Y231162D01*
G01X1535593Y236176D02*
X1535574Y236181D01*
G01X1535607Y236162D02*
X1535593Y236176D01*
G01X1535613Y236142D02*
X1535607Y236162D01*
G01X1535593Y241176D02*
X1535574Y241181D01*
G01X1535607Y241162D02*
X1535593Y241176D01*
G01X1535613Y241142D02*
X1535607Y241162D01*
G01X1535593Y246176D02*
X1535574Y246181D01*
G01X1535607Y246162D02*
X1535593Y246176D01*
G01X1535613Y246142D02*
X1535607Y246162D01*
G01X1535593Y251176D02*
X1535574Y251181D01*
G01X1535607Y251162D02*
X1535593Y251176D01*
G01X1535613Y251142D02*
X1535607Y251162D01*
G01X1535593Y256176D02*
X1535574Y256181D01*
G01X1535607Y256162D02*
X1535593Y256176D01*
G01X1535613Y256142D02*
X1535607Y256162D01*
G01X1535577Y221279D02*
X1535581Y221378D01*
G01X1535572Y221207D02*
X1535577Y221279D01*
G01X1535574Y221181D02*
X1535572Y221207D01*
G01X1535577Y226279D02*
X1535581Y226378D01*
G01X1535572Y226207D02*
X1535577Y226279D01*
G01X1535574Y226181D02*
X1535572Y226207D01*
G01X1535577Y231279D02*
X1535581Y231378D01*
G01X1535572Y231207D02*
X1535577Y231279D01*
G01X1535574Y231181D02*
X1535572Y231207D01*
G01X1535577Y236279D02*
X1535581Y236378D01*
G01X1535572Y236207D02*
X1535577Y236279D01*
G01X1535574Y236181D02*
X1535572Y236207D01*
G01X1535577Y241279D02*
X1535581Y241378D01*
G01X1535572Y241207D02*
X1535577Y241279D01*
G01X1535574Y241181D02*
X1535572Y241207D01*
G01X1535577Y246279D02*
X1535581Y246378D01*
G01X1535572Y246207D02*
X1535577Y246279D01*
G01X1535574Y246181D02*
X1535572Y246207D01*
G01X1535577Y251279D02*
X1535581Y251378D01*
G01X1535572Y251207D02*
X1535577Y251279D01*
G01X1535574Y251181D02*
X1535572Y251207D01*
G01X1535577Y256279D02*
X1535581Y256378D01*
G01X1535572Y256207D02*
X1535577Y256279D01*
G01X1535574Y256181D02*
X1535572Y256207D01*
G01X1534627Y259802D02*
X1534628Y259803D01*
G01X1534626Y259796D02*
X1534627Y259802D01*
G01X1534626Y259787D02*
Y259796D01*
G01X1534627Y254802D02*
X1534628Y254803D01*
G01X1534626Y254796D02*
X1534627Y254802D01*
G01X1534626Y254787D02*
Y254796D01*
G01X1534627Y249802D02*
X1534628Y249803D01*
G01X1534626Y249796D02*
X1534627Y249802D01*
G01X1534626Y249787D02*
Y249796D01*
G01X1534627Y244802D02*
X1534628Y244803D01*
G01X1534626Y244796D02*
X1534627Y244802D01*
G01X1534626Y244787D02*
Y244796D01*
G01X1534627Y239802D02*
X1534628Y239803D01*
G01X1534626Y239796D02*
X1534627Y239802D01*
G01X1534626Y239787D02*
Y239796D01*
G01X1534627Y234802D02*
X1534628Y234803D01*
G01X1534626Y234796D02*
X1534627Y234802D01*
G01X1534626Y234787D02*
Y234796D01*
G01X1534627Y229802D02*
X1534628Y229803D01*
G01X1534626Y229796D02*
X1534627Y229802D01*
G01X1534626Y229787D02*
Y229796D01*
G01X1534627Y224802D02*
X1534628Y224803D01*
G01X1534626Y224796D02*
X1534627Y224802D01*
G01X1534626Y224787D02*
Y224796D01*
G01X1534627Y219802D02*
X1534628Y219803D01*
G01X1534626Y219796D02*
X1534627Y219802D01*
G01X1534626Y219787D02*
Y219796D01*
G01X1535611Y259796D02*
X1535610Y259787D01*
G01X1535611Y259802D02*
Y259796D01*
G01X1535613Y259803D02*
X1535611Y259802D01*
G01Y254796D02*
X1535610Y254787D01*
G01X1535611Y254802D02*
Y254796D01*
G01X1535613Y254803D02*
X1535611Y254802D01*
G01Y249796D02*
X1535610Y249787D01*
G01X1535611Y249802D02*
Y249796D01*
G01X1535613Y249803D02*
X1535611Y249802D01*
G01Y244796D02*
X1535610Y244787D01*
G01X1535611Y244802D02*
Y244796D01*
G01X1535613Y244803D02*
X1535611Y244802D01*
G01Y239796D02*
X1535610Y239787D01*
G01X1535611Y239802D02*
Y239796D01*
G01X1535613Y239803D02*
X1535611Y239802D01*
G01Y234796D02*
X1535610Y234787D01*
G01X1535611Y234802D02*
Y234796D01*
G01X1535613Y234803D02*
X1535611Y234802D01*
G01Y229796D02*
X1535610Y229787D01*
G01X1535611Y229802D02*
Y229796D01*
G01X1535613Y229803D02*
X1535611Y229802D01*
G01Y224796D02*
X1535610Y224787D01*
G01X1535611Y224802D02*
Y224796D01*
G01X1535613Y224803D02*
X1535611Y224802D01*
G01Y219796D02*
X1535610Y219787D01*
G01X1535611Y219802D02*
Y219796D01*
G01X1535613Y219803D02*
X1535611Y219802D01*
G01X1535039Y217854D02*
X1536220Y219035D01*
G01X1531102Y217854D02*
X1532283Y219035D01*
G01X1535610Y221155D02*
X1535611Y221164D01*
G01X1535610Y226155D02*
X1535611Y226164D01*
G01X1535610Y231155D02*
X1535611Y231164D01*
G01X1535610Y236155D02*
X1535611Y236164D01*
G01X1535610Y241155D02*
X1535611Y241164D01*
G01X1535610Y246155D02*
X1535611Y246164D01*
G01X1535610Y251155D02*
X1535611Y251164D01*
G01X1535610Y256155D02*
X1535611Y256164D01*
G01X1539961Y259803D02*
Y261181D01*
G01Y254803D02*
Y256181D01*
G01Y249803D02*
Y251181D01*
G01Y244803D02*
Y246181D01*
G01Y239803D02*
Y241181D01*
G01Y234803D02*
Y236181D01*
G01Y229803D02*
Y231181D01*
G01Y224803D02*
Y226181D01*
G01Y219803D02*
Y221181D01*
G01X1536791D02*
Y219803D01*
G01Y226181D02*
Y224803D01*
G01Y231181D02*
Y229803D01*
G01Y236181D02*
Y234803D01*
G01Y241181D02*
Y239803D01*
G01Y246181D02*
Y244803D01*
G01Y251181D02*
Y249803D01*
G01Y256181D02*
Y254803D01*
G01Y261181D02*
Y259803D01*
G01X1535610Y221156D02*
Y221299D01*
G01Y226156D02*
Y226299D01*
G01Y231156D02*
Y231299D01*
G01Y236156D02*
Y236299D01*
G01Y241156D02*
Y241299D01*
G01Y246156D02*
Y246299D01*
G01Y251156D02*
Y251299D01*
G01Y256156D02*
Y256299D01*
G01Y259311D02*
Y261673D01*
G01Y254311D02*
Y256673D01*
G01Y249311D02*
Y251673D01*
G01Y244311D02*
Y246673D01*
G01Y239311D02*
Y241673D01*
G01Y234311D02*
Y236673D01*
G01Y229311D02*
Y231673D01*
G01Y224311D02*
Y226673D01*
G01Y219311D02*
Y221673D01*
G01X1534626D02*
Y219311D01*
G01Y226673D02*
Y224311D01*
G01Y231673D02*
Y229311D01*
G01Y236673D02*
Y234311D01*
G01Y241673D02*
Y239311D01*
G01Y246673D02*
Y244311D01*
G01Y251673D02*
Y249311D01*
G01Y256673D02*
Y254311D01*
G01Y261673D02*
Y259311D01*
G01X1532283Y295492D02*
Y219035D01*
G01X1531102Y294311D02*
Y217854D01*
G01X1539961Y259803D02*
X1534628D01*
G01X1534626Y259311D02*
X1535610D01*
G01Y256673D02*
X1534626D01*
G01X1535610Y259607D02*
X1534626Y259606D01*
G01X1534628Y256181D02*
X1539961D01*
G01Y256142D02*
X1535613D01*
G01X1539961Y254803D02*
X1534628D01*
G01X1534626Y254311D02*
X1535610D01*
G01Y251673D02*
X1534626D01*
G01X1534628Y251181D02*
X1539961D01*
G01Y251142D02*
X1535613D01*
G01X1539961Y249803D02*
X1534628D01*
G01X1534626Y249311D02*
X1535610D01*
G01Y246673D02*
X1534626D01*
G01X1534628Y246181D02*
X1539961D01*
G01Y246142D02*
X1535613D01*
G01X1539961Y244803D02*
X1534628D01*
G01X1534626Y244311D02*
X1535610D01*
G01Y241673D02*
X1534626D01*
G01X1534628Y241181D02*
X1539961D01*
G01Y241142D02*
X1535613D01*
G01X1539961Y239803D02*
X1534628D01*
G01X1534626Y239311D02*
X1535610D01*
G01Y236673D02*
X1534626D01*
G01X1534628Y236181D02*
X1539961D01*
G01Y236142D02*
X1535613D01*
G01X1539961Y234803D02*
X1534628D01*
G01X1534626Y234311D02*
X1535610D01*
G01Y231673D02*
X1534626D01*
G01X1534628Y231181D02*
X1539961D01*
G01Y231142D02*
X1535613D01*
G01X1539961Y229803D02*
X1534628D01*
G01X1534626Y229311D02*
X1535610D01*
G01Y226673D02*
X1534626D01*
G01X1534628Y226181D02*
X1539961D01*
G01Y226142D02*
X1535613D01*
G01X1539961Y224803D02*
X1534628D01*
G01X1534626Y224311D02*
X1535610D01*
G01Y221673D02*
X1534626D01*
G01X1534628Y221181D02*
X1539961D01*
G01Y221142D02*
X1535613D01*
G01X1539961Y219803D02*
X1534628D01*
G01X1534626Y219311D02*
X1535610D01*
G01X1532283Y219035D02*
X1536220D01*
G01X1531102Y217854D02*
X1535039D01*
G01X1534626Y256377D02*
X1535581Y256378D01*
G01X1535610Y254607D02*
X1534626Y254606D01*
G01Y251377D02*
X1535581Y251378D01*
G01X1535610Y249607D02*
X1534626Y249606D01*
G01Y246377D02*
X1535581Y246378D01*
G01X1535610Y244607D02*
X1534626Y244606D01*
G01Y241377D02*
X1535581Y241378D01*
G01X1535610Y239607D02*
X1534626Y239606D01*
G01Y236377D02*
X1535581Y236378D01*
G01X1535610Y234607D02*
X1534626Y234606D01*
G01Y231377D02*
X1535581Y231378D01*
G01X1535610Y229607D02*
X1534626Y229606D01*
G01Y226377D02*
X1535581Y226378D01*
G01X1535610Y224607D02*
X1534626Y224606D01*
G01Y221377D02*
X1535581Y221378D01*
G01X1535610Y219607D02*
X1534626Y219606D01*
G01X1535598Y261173D02*
X1535609Y261157D01*
G01X1535573Y261181D02*
X1535598Y261173D01*
G01Y266173D02*
X1535609Y266157D01*
G01X1535573Y266181D02*
X1535598Y266173D01*
G01Y271173D02*
X1535609Y271157D01*
G01X1535573Y271181D02*
X1535598Y271173D01*
G01Y276173D02*
X1535609Y276157D01*
G01X1535573Y276181D02*
X1535598Y276173D01*
G01Y281173D02*
X1535609Y281157D01*
G01X1535573Y281181D02*
X1535598Y281173D01*
G01Y286173D02*
X1535609Y286157D01*
G01X1535573Y286181D02*
X1535598Y286173D01*
G01Y291173D02*
X1535609Y291157D01*
G01X1535573Y291181D02*
X1535598Y291173D01*
G01X1535611Y261148D02*
X1535610Y261156D01*
G01X1535611Y261144D02*
Y261148D01*
G01X1535613Y261142D02*
X1535611Y261144D01*
G01Y266148D02*
X1535610Y266156D01*
G01X1535611Y266144D02*
Y266148D01*
G01X1535613Y266142D02*
X1535611Y266144D01*
G01Y271148D02*
X1535610Y271156D01*
G01X1535611Y271144D02*
Y271148D01*
G01X1535613Y271142D02*
X1535611Y271144D01*
G01Y276148D02*
X1535610Y276156D01*
G01X1535611Y276144D02*
Y276148D01*
G01X1535613Y276142D02*
X1535611Y276144D01*
G01Y281148D02*
X1535610Y281156D01*
G01X1535611Y281144D02*
Y281148D01*
G01X1535613Y281142D02*
X1535611Y281144D01*
G01Y286148D02*
X1535610Y286156D01*
G01X1535611Y286144D02*
Y286148D01*
G01X1535613Y286142D02*
X1535611Y286144D01*
G01Y291148D02*
X1535610Y291156D01*
G01X1535611Y291144D02*
Y291148D01*
G01X1535613Y291142D02*
X1535611Y291144D01*
G01X1534626Y261189D02*
Y261198D01*
G01X1534627Y261183D02*
X1534626Y261189D01*
G01X1534628Y261181D02*
X1534627Y261183D01*
G01X1534626Y266189D02*
Y266198D01*
G01X1534627Y266183D02*
X1534626Y266189D01*
G01X1534628Y266181D02*
X1534627Y266183D01*
G01X1534626Y271189D02*
Y271198D01*
G01X1534627Y271183D02*
X1534626Y271189D01*
G01X1534628Y271181D02*
X1534627Y271183D01*
G01X1534626Y276189D02*
Y276198D01*
G01X1534627Y276183D02*
X1534626Y276189D01*
G01X1534628Y276181D02*
X1534627Y276183D01*
G01X1534626Y281189D02*
Y281198D01*
G01X1534627Y281183D02*
X1534626Y281189D01*
G01X1534628Y281181D02*
X1534627Y281183D01*
G01X1534626Y286189D02*
Y286198D01*
G01X1534627Y286183D02*
X1534626Y286189D01*
G01X1534628Y286181D02*
X1534627Y286183D01*
G01X1534626Y291189D02*
Y291198D01*
G01X1534627Y291183D02*
X1534626Y291189D01*
G01X1534628Y291181D02*
X1534627Y291183D01*
G01X1535602Y261325D02*
X1535610Y261299D01*
G01X1535593Y261352D02*
X1535602Y261325D01*
G01X1535581Y261378D02*
X1535593Y261352D01*
G01X1535602Y266325D02*
X1535610Y266299D01*
G01X1535593Y266352D02*
X1535602Y266325D01*
G01X1535581Y266378D02*
X1535593Y266352D01*
G01X1535602Y271325D02*
X1535610Y271299D01*
G01X1535593Y271352D02*
X1535602Y271325D01*
G01X1535581Y271378D02*
X1535593Y271352D01*
G01X1535602Y276325D02*
X1535610Y276299D01*
G01X1535593Y276352D02*
X1535602Y276325D01*
G01X1535581Y276378D02*
X1535593Y276352D01*
G01X1535602Y281325D02*
X1535610Y281299D01*
G01X1535593Y281352D02*
X1535602Y281325D01*
G01X1535581Y281378D02*
X1535593Y281352D01*
G01X1535602Y286325D02*
X1535610Y286299D01*
G01X1535593Y286352D02*
X1535602Y286325D01*
G01X1535581Y286378D02*
X1535593Y286352D01*
G01X1535602Y291325D02*
X1535610Y291299D01*
G01X1535593Y291352D02*
X1535602Y291325D01*
G01X1535581Y291378D02*
X1535593Y291352D01*
G01Y261176D02*
X1535574Y261181D01*
G01X1535607Y261162D02*
X1535593Y261176D01*
G01X1535613Y261142D02*
X1535607Y261162D01*
G01X1535593Y266176D02*
X1535574Y266181D01*
G01X1535607Y266162D02*
X1535593Y266176D01*
G01X1535613Y266142D02*
X1535607Y266162D01*
G01X1535593Y271176D02*
X1535574Y271181D01*
G01X1535607Y271162D02*
X1535593Y271176D01*
G01X1535613Y271142D02*
X1535607Y271162D01*
G01X1535593Y276176D02*
X1535574Y276181D01*
G01X1535607Y276162D02*
X1535593Y276176D01*
G01X1535613Y276142D02*
X1535607Y276162D01*
G01X1535593Y281176D02*
X1535574Y281181D01*
G01X1535607Y281162D02*
X1535593Y281176D01*
G01X1535613Y281142D02*
X1535607Y281162D01*
G01X1535593Y286176D02*
X1535574Y286181D01*
G01X1535607Y286162D02*
X1535593Y286176D01*
G01X1535613Y286142D02*
X1535607Y286162D01*
G01X1535593Y291176D02*
X1535574Y291181D01*
G01X1535607Y291162D02*
X1535593Y291176D01*
G01X1535613Y291142D02*
X1535607Y291162D01*
G01X1535577Y261279D02*
X1535581Y261378D01*
G01X1535572Y261207D02*
X1535577Y261279D01*
G01X1535574Y261181D02*
X1535572Y261207D01*
G01X1535577Y266279D02*
X1535581Y266378D01*
G01X1535572Y266207D02*
X1535577Y266279D01*
G01X1535574Y266181D02*
X1535572Y266207D01*
G01X1535577Y271279D02*
X1535581Y271378D01*
G01X1535572Y271207D02*
X1535577Y271279D01*
G01X1535574Y271181D02*
X1535572Y271207D01*
G01X1535577Y276279D02*
X1535581Y276378D01*
G01X1535572Y276207D02*
X1535577Y276279D01*
G01X1535574Y276181D02*
X1535572Y276207D01*
G01X1535577Y281279D02*
X1535581Y281378D01*
G01X1535572Y281207D02*
X1535577Y281279D01*
G01X1535574Y281181D02*
X1535572Y281207D01*
G01X1535577Y286279D02*
X1535581Y286378D01*
G01X1535572Y286207D02*
X1535577Y286279D01*
G01X1535574Y286181D02*
X1535572Y286207D01*
G01X1535577Y291279D02*
X1535581Y291378D01*
G01X1535572Y291207D02*
X1535577Y291279D01*
G01X1535574Y291181D02*
X1535572Y291207D01*
G01X1534627Y289802D02*
X1534628Y289803D01*
G01X1534626Y289796D02*
X1534627Y289802D01*
G01X1534626Y289787D02*
Y289796D01*
G01X1534627Y284802D02*
X1534628Y284803D01*
G01X1534626Y284796D02*
X1534627Y284802D01*
G01X1534626Y284787D02*
Y284796D01*
G01X1534627Y279802D02*
X1534628Y279803D01*
G01X1534626Y279796D02*
X1534627Y279802D01*
G01X1534626Y279787D02*
Y279796D01*
G01X1534627Y274802D02*
X1534628Y274803D01*
G01X1534626Y274796D02*
X1534627Y274802D01*
G01X1534626Y274787D02*
Y274796D01*
G01X1534627Y269802D02*
X1534628Y269803D01*
G01X1534626Y269796D02*
X1534627Y269802D01*
G01X1534626Y269787D02*
Y269796D01*
G01X1534627Y264802D02*
X1534628Y264803D01*
G01X1534626Y264796D02*
X1534627Y264802D01*
G01X1534626Y264787D02*
Y264796D01*
G01X1535611Y289796D02*
X1535610Y289787D01*
G01X1535611Y289802D02*
Y289796D01*
G01X1535613Y289803D02*
X1535611Y289802D01*
G01Y284796D02*
X1535610Y284787D01*
G01X1535611Y284802D02*
Y284796D01*
G01X1535613Y284803D02*
X1535611Y284802D01*
G01Y279796D02*
X1535610Y279787D01*
G01X1535611Y279802D02*
Y279796D01*
G01X1535613Y279803D02*
X1535611Y279802D01*
G01Y274796D02*
X1535610Y274787D01*
G01X1535611Y274802D02*
Y274796D01*
G01X1535613Y274803D02*
X1535611Y274802D01*
G01Y269796D02*
X1535610Y269787D01*
G01X1535611Y269802D02*
Y269796D01*
G01X1535613Y269803D02*
X1535611Y269802D01*
G01Y264796D02*
X1535610Y264787D01*
G01X1535611Y264802D02*
Y264796D01*
G01X1535613Y264803D02*
X1535611Y264802D01*
G01X1527559Y307579D02*
G03X1526378Y306398I0J-1181D01*
G01X1533858D02*
G03X1532677Y307579I-1181J0D01*
G01X1532008Y302303D02*
G03I-1890J0D01*
G01X1532480D02*
G03I-2362J0D01*
G01X1540945Y300335D02*
X1537598Y296988D01*
G01X1531102Y294311D02*
X1532283Y295492D01*
G01X1527633Y299232D02*
X1528937Y301201D01*
G01X1533609Y307123D02*
X1531299Y302894D01*
G01X1535610Y261155D02*
X1535611Y261164D01*
G01X1535610Y266155D02*
X1535611Y266164D01*
G01X1535610Y271155D02*
X1535611Y271164D01*
G01X1535610Y276155D02*
X1535611Y276164D01*
G01X1535610Y281155D02*
X1535611Y281164D01*
G01X1535610Y286155D02*
X1535611Y286164D01*
G01X1535610Y291155D02*
X1535611Y291164D01*
G01X1540945Y300335D02*
Y316083D01*
G01X1539961Y289803D02*
Y291181D01*
G01Y284803D02*
Y286181D01*
G01Y279803D02*
Y281181D01*
G01Y274803D02*
Y276181D01*
G01Y269803D02*
Y271181D01*
G01Y264803D02*
Y266181D01*
G01X1536791D02*
Y264803D01*
G01Y271181D02*
Y269803D01*
G01Y276181D02*
Y274803D01*
G01Y281181D02*
Y279803D01*
G01Y286181D02*
Y284803D01*
G01Y291181D02*
Y289803D01*
G01X1535610Y261156D02*
Y261299D01*
G01Y266156D02*
Y266299D01*
G01Y271156D02*
Y271299D01*
G01Y276156D02*
Y276299D01*
G01Y281156D02*
Y281299D01*
G01Y286156D02*
Y286299D01*
G01Y291156D02*
Y291299D01*
G01Y289311D02*
Y291673D01*
G01Y284311D02*
Y286673D01*
G01Y279311D02*
Y281673D01*
G01Y274311D02*
Y276673D01*
G01Y269311D02*
Y271673D01*
G01Y264311D02*
Y266673D01*
G01X1534626D02*
Y264311D01*
G01Y271673D02*
Y269311D01*
G01Y276673D02*
Y274311D01*
G01Y281673D02*
Y279311D01*
G01Y286673D02*
Y284311D01*
G01Y291673D02*
Y289311D01*
G01X1533858Y306398D02*
Y297854D01*
G01X1531299Y302894D02*
Y301201D01*
G01X1528937D02*
Y302894D01*
G01X1526378Y297854D02*
Y306398D01*
G01X1535610Y286152D02*
Y286155D01*
G01Y281152D02*
Y281155D01*
G01Y276152D02*
Y276155D01*
G01Y271152D02*
Y271155D01*
G01X1528937Y302894D02*
X1526627Y307123D01*
G01X1531299Y301201D02*
X1532603Y299232D01*
G01X1524409Y295492D02*
X1525591Y294311D01*
G01X1527559Y307579D02*
X1532677D01*
G01X1528937Y302894D02*
X1531299D01*
G01X1528937Y301201D02*
X1531299D01*
G01X1537008Y297854D02*
X1533858D01*
G01X1524409Y295492D02*
X1532283D01*
G01X1525591Y294311D02*
X1531102D01*
G01X1535610Y291673D02*
X1534626D01*
G01X1534628Y291181D02*
X1539961D01*
G01Y291142D02*
X1535613D01*
G01X1539961Y289803D02*
X1534628D01*
G01X1534626Y289311D02*
X1535610D01*
G01Y286673D02*
X1534626D01*
G01X1534628Y286181D02*
X1539961D01*
G01Y286142D02*
X1535613D01*
G01X1539961Y284803D02*
X1534628D01*
G01X1534626Y284311D02*
X1535610D01*
G01Y281673D02*
X1534626D01*
G01X1534628Y281181D02*
X1539961D01*
G01Y281142D02*
X1535613D01*
G01X1539961Y279803D02*
X1534628D01*
G01X1534626Y279311D02*
X1535610D01*
G01Y276673D02*
X1534626D01*
G01X1534628Y276181D02*
X1539961D01*
G01Y276142D02*
X1535613D01*
G01X1539961Y274803D02*
X1534628D01*
G01X1534626Y274311D02*
X1535610D01*
G01Y271673D02*
X1534626D01*
G01X1534628Y271181D02*
X1539961D01*
G01Y271142D02*
X1535613D01*
G01X1539961Y269803D02*
X1534628D01*
G01X1534626Y269311D02*
X1535610D01*
G01Y266673D02*
X1534626D01*
G01X1534628Y266181D02*
X1539961D01*
G01Y266142D02*
X1535613D01*
G01X1539961Y264803D02*
X1534628D01*
G01X1534626Y264311D02*
X1535610D01*
G01Y261673D02*
X1534626D01*
G01X1534628Y261181D02*
X1539961D01*
G01Y261142D02*
X1535613D01*
G01X1534626Y291377D02*
X1535581Y291378D01*
G01X1535610Y289607D02*
X1534626Y289606D01*
G01Y286377D02*
X1535581Y286378D01*
G01X1535610Y284607D02*
X1534626Y284606D01*
G01Y281377D02*
X1535581Y281378D01*
G01X1535610Y279607D02*
X1534626Y279606D01*
G01Y276377D02*
X1535581Y276378D01*
G01X1535610Y274607D02*
X1534626Y274606D01*
G01Y271377D02*
X1535581Y271378D01*
G01X1535610Y269607D02*
X1534626Y269606D01*
G01Y266377D02*
X1535581Y266378D01*
G01X1535610Y264607D02*
X1534626Y264606D01*
G01Y261377D02*
X1535581Y261378D01*
G01X1532996Y378885D02*
G03X1566807I16906J-13531D01*
G01X1532996D02*
G03X1566807I16906J-13531D01*
G01X1534055Y316673D02*
G03X1533465Y317264I-591J0D01*
G01X1526772D02*
G03X1526181Y316673I0J-591D01*
G01X1528937Y315492D02*
G03Y313524I0J-984D01*
G01X1531299D02*
G03Y315492I0J984D01*
G01X1540945Y316083D02*
G03X1538976Y318051I-1968J0D01*
G01X1534055Y310571D02*
Y316673D01*
G01X1526181Y310571D02*
Y316673D01*
G01X1533465Y317264D02*
X1526772D01*
G01X1531299Y315492D02*
X1528937D01*
G01Y313524D02*
X1531299D01*
G01X1534055Y312146D02*
X1526181D01*
G01Y310571D02*
X1534055D01*
G01X1559882Y392016D02*
G03X1566807Y378885I37662J11471D01*
G01X1559882Y392016D02*
G03X1539921I-9980J-3039D01*
G01X1532996Y378885D02*
G03X1539921Y392016I-30737J24602D01*
G01X1559882D02*
G03X1566807Y378885I37662J11471D01*
G01X1559882Y392016D02*
G03X1539921I-9980J-3039D01*
G01X1532996Y378885D02*
G03X1539921Y392016I-30737J24602D01*
G01X1526181Y592067D02*
G03X1526772Y591476I591J0D01*
G01X1533465D02*
G03X1534055Y592067I-1J591D01*
G01X1531299Y593248D02*
G03Y595217I0J985D01*
G01X1528937D02*
G03Y593248I0J-985D01*
G01X1538976Y590689D02*
G03X1540945Y592657I0J1969D01*
G01D02*
Y608406D01*
G01X1534055Y598169D02*
Y592067D01*
G01X1526181Y598169D02*
Y592067D01*
G01X1534055Y598169D02*
X1526181D01*
G01Y596594D02*
X1534055D01*
G01X1531299Y595217D02*
X1528937D01*
G01Y593248D02*
X1531299D01*
G01X1533465Y591476D02*
X1526772D01*
G01X1535598Y618929D02*
X1535609Y618913D01*
G01X1535573Y618937D02*
X1535598Y618929D01*
G01Y623929D02*
X1535609Y623913D01*
G01X1535573Y623937D02*
X1535598Y623929D01*
G01Y628929D02*
X1535609Y628913D01*
G01X1535573Y628937D02*
X1535598Y628929D01*
G01Y633929D02*
X1535609Y633913D01*
G01X1535573Y633937D02*
X1535598Y633929D01*
G01Y638929D02*
X1535609Y638913D01*
G01X1535573Y638937D02*
X1535598Y638929D01*
G01Y643929D02*
X1535609Y643913D01*
G01X1535573Y643937D02*
X1535598Y643929D01*
G01X1535611Y618904D02*
X1535610Y618911D01*
G01X1535611Y618900D02*
Y618904D01*
G01X1535613Y618898D02*
X1535611Y618900D01*
G01Y623904D02*
X1535610Y623911D01*
G01X1535611Y623900D02*
Y623904D01*
G01X1535613Y623898D02*
X1535611Y623900D01*
G01Y628904D02*
X1535610Y628911D01*
G01X1535611Y628900D02*
Y628904D01*
G01X1535613Y628898D02*
X1535611Y628900D01*
G01Y633904D02*
X1535610Y633911D01*
G01X1535611Y633900D02*
Y633904D01*
G01X1535613Y633898D02*
X1535611Y633900D01*
G01Y638904D02*
X1535610Y638911D01*
G01X1535611Y638900D02*
Y638904D01*
G01X1535613Y638898D02*
X1535611Y638900D01*
G01Y643904D02*
X1535610Y643911D01*
G01X1535611Y643900D02*
Y643904D01*
G01X1535613Y643898D02*
X1535611Y643900D01*
G01X1534626Y618944D02*
Y618954D01*
G01X1534627Y618939D02*
X1534626Y618944D01*
G01X1534628Y618937D02*
X1534627Y618939D01*
G01X1534626Y623944D02*
Y623954D01*
G01X1534627Y623939D02*
X1534626Y623944D01*
G01X1534628Y623937D02*
X1534627Y623939D01*
G01X1534626Y628944D02*
Y628954D01*
G01X1534627Y628939D02*
X1534626Y628944D01*
G01X1534628Y628937D02*
X1534627Y628939D01*
G01X1534626Y633944D02*
Y633954D01*
G01X1534627Y633939D02*
X1534626Y633944D01*
G01X1534628Y633937D02*
X1534627Y633939D01*
G01X1535602Y619081D02*
X1535610Y619055D01*
G01X1535593Y619107D02*
X1535602Y619081D01*
G01X1535581Y619134D02*
X1535593Y619107D01*
G01X1535602Y624081D02*
X1535610Y624055D01*
G01X1535593Y624107D02*
X1535602Y624081D01*
G01X1535581Y624134D02*
X1535593Y624107D01*
G01X1535611Y647552D02*
X1535610Y647543D01*
G01X1535611Y647557D02*
Y647552D01*
G01X1535613Y647559D02*
X1535611Y647557D01*
G01Y642552D02*
X1535610Y642543D01*
G01X1535611Y642557D02*
Y642552D01*
G01X1535613Y642559D02*
X1535611Y642557D01*
G01Y637552D02*
X1535610Y637543D01*
G01X1535611Y637557D02*
Y637552D01*
G01X1535613Y637559D02*
X1535611Y637557D01*
G01Y632552D02*
X1535610Y632543D01*
G01X1535611Y632557D02*
Y632552D01*
G01X1535613Y632559D02*
X1535611Y632557D01*
G01Y627552D02*
X1535610Y627543D01*
G01X1535611Y627557D02*
Y627552D01*
G01X1535613Y627559D02*
X1535611Y627557D01*
G01Y622552D02*
X1535610Y622543D01*
G01X1535611Y622557D02*
Y622552D01*
G01X1535613Y622559D02*
X1535611Y622557D01*
G01Y617552D02*
X1535610Y617543D01*
G01X1535611Y617557D02*
Y617552D01*
G01X1535613Y617559D02*
X1535611Y617557D01*
G01X1534626Y638944D02*
Y638954D01*
G01X1534627Y638939D02*
X1534626Y638944D01*
G01X1534628Y638937D02*
X1534627Y638939D01*
G01X1534626Y643944D02*
Y643954D01*
G01X1534627Y643939D02*
X1534626Y643944D01*
G01X1534628Y643937D02*
X1534627Y643939D01*
G01X1535602Y629081D02*
X1535610Y629055D01*
G01X1535593Y629107D02*
X1535602Y629081D01*
G01X1535581Y629134D02*
X1535593Y629107D01*
G01X1535602Y634081D02*
X1535610Y634055D01*
G01X1535593Y634107D02*
X1535602Y634081D01*
G01X1535581Y634134D02*
X1535593Y634107D01*
G01X1535602Y639081D02*
X1535610Y639055D01*
G01X1535593Y639107D02*
X1535602Y639081D01*
G01X1535581Y639134D02*
X1535593Y639107D01*
G01X1535602Y644081D02*
X1535610Y644055D01*
G01X1535593Y644107D02*
X1535602Y644081D01*
G01X1535581Y644134D02*
X1535593Y644107D01*
G01Y618932D02*
X1535574Y618937D01*
G01X1535607Y618918D02*
X1535593Y618932D01*
G01X1535613Y618898D02*
X1535607Y618918D01*
G01X1535593Y623932D02*
X1535574Y623937D01*
G01X1535607Y623918D02*
X1535593Y623932D01*
G01X1535613Y623898D02*
X1535607Y623918D01*
G01X1535593Y628932D02*
X1535574Y628937D01*
G01X1535607Y628918D02*
X1535593Y628932D01*
G01X1535613Y628898D02*
X1535607Y628918D01*
G01X1535593Y633932D02*
X1535574Y633937D01*
G01X1535607Y633918D02*
X1535593Y633932D01*
G01X1535613Y633898D02*
X1535607Y633918D01*
G01X1535593Y638932D02*
X1535574Y638937D01*
G01X1535607Y638918D02*
X1535593Y638932D01*
G01X1535613Y638898D02*
X1535607Y638918D01*
G01X1535593Y643932D02*
X1535574Y643937D01*
G01X1535607Y643918D02*
X1535593Y643932D01*
G01X1535613Y643898D02*
X1535607Y643918D01*
G01X1535577Y619035D02*
X1535581Y619134D01*
G01X1535572Y618963D02*
X1535577Y619035D01*
G01X1535574Y618937D02*
X1535572Y618963D01*
G01X1535577Y624035D02*
X1535581Y624134D01*
G01X1535572Y623963D02*
X1535577Y624035D01*
G01X1535574Y623937D02*
X1535572Y623963D01*
G01X1535577Y629035D02*
X1535581Y629134D01*
G01X1535572Y628963D02*
X1535577Y629035D01*
G01X1535574Y628937D02*
X1535572Y628963D01*
G01X1535577Y634035D02*
X1535581Y634134D01*
G01X1535572Y633963D02*
X1535577Y634035D01*
G01X1535574Y633937D02*
X1535572Y633963D01*
G01X1535577Y639035D02*
X1535581Y639134D01*
G01X1535572Y638963D02*
X1535577Y639035D01*
G01X1535574Y638937D02*
X1535572Y638963D01*
G01X1535577Y644035D02*
X1535581Y644134D01*
G01X1535572Y643963D02*
X1535577Y644035D01*
G01X1535574Y643937D02*
X1535572Y643963D01*
G01X1534627Y647557D02*
X1534628Y647559D01*
G01X1534626Y647552D02*
X1534627Y647557D01*
G01X1534626Y647543D02*
Y647552D01*
G01X1534627Y642557D02*
X1534628Y642559D01*
G01X1534626Y642552D02*
X1534627Y642557D01*
G01X1534626Y642543D02*
Y642552D01*
G01X1534627Y637557D02*
X1534628Y637559D01*
G01X1534626Y637552D02*
X1534627Y637557D01*
G01X1534626Y637543D02*
Y637552D01*
G01X1534627Y632557D02*
X1534628Y632559D01*
G01X1534626Y632552D02*
X1534627Y632557D01*
G01X1534626Y632543D02*
Y632552D01*
G01X1534627Y627557D02*
X1534628Y627559D01*
G01X1534626Y627552D02*
X1534627Y627557D01*
G01X1534626Y627543D02*
Y627552D01*
G01X1534627Y622557D02*
X1534628Y622559D01*
G01X1534626Y622552D02*
X1534627Y622557D01*
G01X1534626Y622543D02*
Y622552D01*
G01X1534627Y617557D02*
X1534628Y617559D01*
G01X1534626Y617552D02*
X1534627Y617557D01*
G01X1534626Y617543D02*
Y617552D01*
G01X1531220Y606437D02*
G03I-1102J0D01*
G01X1532677Y601161D02*
G03X1533858Y602343I0J1181D01*
G01X1526378D02*
G03X1527559Y601161I1181J-1D01*
G01X1531693Y606437D02*
G03I-1575J0D01*
G01X1532603Y609508D02*
X1531299Y607539D01*
G01X1526627Y601617D02*
X1528937Y605846D01*
G01X1535610Y618911D02*
X1535611Y618920D01*
G01X1535610Y623911D02*
X1535611Y623920D01*
G01X1535610Y628911D02*
X1535611Y628920D01*
G01X1535610Y633911D02*
X1535611Y633920D01*
G01X1535610Y638911D02*
X1535611Y638920D01*
G01X1535610Y643911D02*
X1535611Y643920D01*
G01X1539961Y647559D02*
Y648937D01*
G01Y642559D02*
Y643937D01*
G01Y637559D02*
Y638937D01*
G01Y632559D02*
Y633937D01*
G01Y627559D02*
Y628937D01*
G01Y622559D02*
Y623937D01*
G01Y617559D02*
Y618937D01*
G01X1537598Y749744D02*
Y611752D01*
G01X1537008Y751988D02*
Y609508D01*
G01X1536791Y618937D02*
Y617559D01*
G01Y623937D02*
Y622559D01*
G01Y628937D02*
Y627559D01*
G01Y633937D02*
Y632559D01*
G01Y638937D02*
Y637559D01*
G01Y643937D02*
Y642559D01*
G01Y648937D02*
Y647559D01*
G01X1535610Y647067D02*
Y649429D01*
G01Y642067D02*
Y644429D01*
G01Y637067D02*
Y639429D01*
G01Y632067D02*
Y634429D01*
G01Y627067D02*
Y629429D01*
G01Y622067D02*
Y624429D01*
G01Y617067D02*
Y619429D01*
G01X1534626D02*
Y617067D01*
G01Y624429D02*
Y622067D01*
G01Y629429D02*
Y627067D01*
G01Y634429D02*
Y632067D01*
G01Y639429D02*
Y637067D01*
G01Y644429D02*
Y642067D01*
G01Y649429D02*
Y647067D01*
G01X1533858Y610886D02*
Y602343D01*
G01X1532283Y649705D02*
Y613248D01*
G01X1531299Y607539D02*
Y605846D01*
G01X1531102Y650886D02*
Y614429D01*
G01X1528937Y605846D02*
Y607539D01*
G01X1526378Y602343D02*
Y610886D01*
G01X1525591Y614429D02*
Y747067D01*
G01X1524409Y613248D02*
Y748248D01*
G01X1525591Y614429D02*
X1524409Y613248D01*
G01X1531299Y605846D02*
X1533609Y601617D01*
G01X1528937Y607539D02*
X1527633Y609508D01*
G01X1537598Y611752D02*
X1540945Y608406D01*
G01X1531102Y614429D02*
X1532283Y613248D01*
G01X1539961Y647559D02*
X1534628D01*
G01X1534626Y647067D02*
X1535610D01*
G01Y644429D02*
X1534626D01*
G01X1534628Y643937D02*
X1539961D01*
G01Y643898D02*
X1535613D01*
G01X1539961Y642559D02*
X1534628D01*
G01X1534626Y642067D02*
X1535610D01*
G01Y639429D02*
X1534626D01*
G01X1534628Y638937D02*
X1539961D01*
G01Y638898D02*
X1535613D01*
G01X1539961Y637559D02*
X1534628D01*
G01X1534626Y637067D02*
X1535610D01*
G01Y634429D02*
X1534626D01*
G01X1534628Y633937D02*
X1539961D01*
G01Y633898D02*
X1535613D01*
G01X1539961Y632559D02*
X1534628D01*
G01X1534626Y632067D02*
X1535610D01*
G01Y629429D02*
X1534626D01*
G01X1534628Y628937D02*
X1539961D01*
G01Y628898D02*
X1535613D01*
G01X1539961Y627559D02*
X1534628D01*
G01X1534626Y627067D02*
X1535610D01*
G01Y624429D02*
X1534626D01*
G01X1534628Y623937D02*
X1539961D01*
G01Y623898D02*
X1535613D01*
G01X1539961Y622559D02*
X1534628D01*
G01X1534626Y622067D02*
X1535610D01*
G01Y619429D02*
X1534626D01*
G01X1534628Y618937D02*
X1539961D01*
G01Y618898D02*
X1535613D01*
G01X1539961Y617559D02*
X1534628D01*
G01X1534626Y617067D02*
X1535610D01*
G01Y647363D02*
X1534626Y647362D01*
G01Y644133D02*
X1535581Y644134D01*
G01X1535610Y642363D02*
X1534626Y642362D01*
G01Y639133D02*
X1535581Y639134D01*
G01X1535610Y637363D02*
X1534626Y637362D01*
G01Y634133D02*
X1535581Y634134D01*
G01X1535610Y632363D02*
X1534626Y632362D01*
G01Y629133D02*
X1535581Y629134D01*
G01X1535610Y627363D02*
X1534626Y627362D01*
G01Y624133D02*
X1535581Y624134D01*
G01X1535610Y622363D02*
X1534626Y622362D01*
G01Y619133D02*
X1535581Y619134D01*
G01X1535610Y617363D02*
X1534626Y617362D01*
G01X1531102Y614429D02*
X1525591D01*
G01X1532283Y613248D02*
X1524409D01*
G01X1533858Y610886D02*
X1537008D01*
G01X1531299Y607539D02*
X1528937D01*
G01X1531299Y605846D02*
X1528937D01*
G01X1532677Y601161D02*
X1527559D01*
G01X1535598Y648929D02*
X1535609Y648913D01*
G01X1535573Y648937D02*
X1535598Y648929D01*
G01Y673929D02*
X1535609Y673913D01*
G01X1535573Y673937D02*
X1535598Y673929D01*
G01Y678929D02*
X1535609Y678913D01*
G01X1535573Y678937D02*
X1535598Y678929D01*
G01Y683929D02*
X1535609Y683913D01*
G01X1535573Y683937D02*
X1535598Y683929D01*
G01Y688929D02*
X1535609Y688913D01*
G01X1535573Y688937D02*
X1535598Y688929D01*
G01Y693929D02*
X1535609Y693913D01*
G01X1535573Y693937D02*
X1535598Y693929D01*
G01X1535611Y648904D02*
X1535610Y648911D01*
G01X1535611Y648900D02*
Y648904D01*
G01X1535613Y648898D02*
X1535611Y648900D01*
G01Y673904D02*
X1535610Y673911D01*
G01X1535611Y673900D02*
Y673904D01*
G01X1535613Y673898D02*
X1535611Y673900D01*
G01Y678904D02*
X1535610Y678911D01*
G01X1535611Y678900D02*
Y678904D01*
G01X1535613Y678898D02*
X1535611Y678900D01*
G01Y683904D02*
X1535610Y683911D01*
G01X1535611Y683900D02*
Y683904D01*
G01X1535613Y683898D02*
X1535611Y683900D01*
G01Y688904D02*
X1535610Y688911D01*
G01X1535611Y688900D02*
Y688904D01*
G01X1535613Y688898D02*
X1535611Y688900D01*
G01Y693904D02*
X1535610Y693911D01*
G01X1535611Y693900D02*
Y693904D01*
G01X1535613Y693898D02*
X1535611Y693900D01*
G01Y692552D02*
X1535610Y692543D01*
G01X1535611Y692557D02*
Y692552D01*
G01X1535613Y692559D02*
X1535611Y692557D01*
G01Y687552D02*
X1535610Y687543D01*
G01X1535611Y687557D02*
Y687552D01*
G01X1535613Y687559D02*
X1535611Y687557D01*
G01Y682552D02*
X1535610Y682543D01*
G01X1535611Y682557D02*
Y682552D01*
G01X1535613Y682559D02*
X1535611Y682557D01*
G01Y677552D02*
X1535610Y677543D01*
G01X1535611Y677557D02*
Y677552D01*
G01X1535613Y677559D02*
X1535611Y677557D01*
G01Y672552D02*
X1535610Y672543D01*
G01X1535611Y672557D02*
Y672552D01*
G01X1535613Y672559D02*
X1535611Y672557D01*
G01X1534626Y648944D02*
Y648954D01*
G01X1534627Y648939D02*
X1534626Y648944D01*
G01X1534628Y648937D02*
X1534627Y648939D01*
G01X1534626Y673944D02*
Y673954D01*
G01X1534627Y673939D02*
X1534626Y673944D01*
G01X1534628Y673937D02*
X1534627Y673939D01*
G01X1534626Y678944D02*
Y678954D01*
G01X1534627Y678939D02*
X1534626Y678944D01*
G01X1534628Y678937D02*
X1534627Y678939D01*
G01X1534626Y683944D02*
Y683954D01*
G01X1534627Y683939D02*
X1534626Y683944D01*
G01X1534628Y683937D02*
X1534627Y683939D01*
G01X1534626Y688944D02*
Y688954D01*
G01X1534627Y688939D02*
X1534626Y688944D01*
G01X1534628Y688937D02*
X1534627Y688939D01*
G01X1534626Y693944D02*
Y693954D01*
G01X1534627Y693939D02*
X1534626Y693944D01*
G01X1534628Y693937D02*
X1534627Y693939D01*
G01X1535602Y649081D02*
X1535610Y649055D01*
G01X1535593Y649107D02*
X1535602Y649081D01*
G01X1535581Y649134D02*
X1535593Y649107D01*
G01X1535602Y674081D02*
X1535610Y674055D01*
G01X1535593Y674107D02*
X1535602Y674081D01*
G01X1535581Y674134D02*
X1535593Y674107D01*
G01X1535602Y679081D02*
X1535610Y679055D01*
G01X1535593Y679107D02*
X1535602Y679081D01*
G01X1535581Y679134D02*
X1535593Y679107D01*
G01X1535602Y684081D02*
X1535610Y684055D01*
G01X1535593Y684107D02*
X1535602Y684081D01*
G01X1535581Y684134D02*
X1535593Y684107D01*
G01X1535602Y689081D02*
X1535610Y689055D01*
G01X1535593Y689107D02*
X1535602Y689081D01*
G01X1535581Y689134D02*
X1535593Y689107D01*
G01X1535602Y694081D02*
X1535610Y694055D01*
G01X1535593Y694107D02*
X1535602Y694081D01*
G01X1535581Y694134D02*
X1535593Y694107D01*
G01Y648932D02*
X1535574Y648937D01*
G01X1535607Y648918D02*
X1535593Y648932D01*
G01X1535613Y648898D02*
X1535607Y648918D01*
G01X1535593Y673932D02*
X1535574Y673937D01*
G01X1535607Y673918D02*
X1535593Y673932D01*
G01X1535613Y673898D02*
X1535607Y673918D01*
G01X1535593Y678932D02*
X1535574Y678937D01*
G01X1535607Y678918D02*
X1535593Y678932D01*
G01X1535613Y678898D02*
X1535607Y678918D01*
G01X1535593Y683932D02*
X1535574Y683937D01*
G01X1535607Y683918D02*
X1535593Y683932D01*
G01X1535613Y683898D02*
X1535607Y683918D01*
G01X1535593Y688932D02*
X1535574Y688937D01*
G01X1535607Y688918D02*
X1535593Y688932D01*
G01X1535613Y688898D02*
X1535607Y688918D01*
G01X1535593Y693932D02*
X1535574Y693937D01*
G01X1535607Y693918D02*
X1535593Y693932D01*
G01X1535613Y693898D02*
X1535607Y693918D01*
G01X1535577Y649035D02*
X1535581Y649134D01*
G01X1535572Y648963D02*
X1535577Y649035D01*
G01X1535574Y648937D02*
X1535572Y648963D01*
G01X1535577Y674035D02*
X1535581Y674134D01*
G01X1535572Y673963D02*
X1535577Y674035D01*
G01X1535574Y673937D02*
X1535572Y673963D01*
G01X1535577Y679035D02*
X1535581Y679134D01*
G01X1535572Y678963D02*
X1535577Y679035D01*
G01X1535574Y678937D02*
X1535572Y678963D01*
G01X1535577Y684035D02*
X1535581Y684134D01*
G01X1535572Y683963D02*
X1535577Y684035D01*
G01X1535574Y683937D02*
X1535572Y683963D01*
G01X1535577Y689035D02*
X1535581Y689134D01*
G01X1535572Y688963D02*
X1535577Y689035D01*
G01X1535574Y688937D02*
X1535572Y688963D01*
G01X1535577Y694035D02*
X1535581Y694134D01*
G01X1535572Y693963D02*
X1535577Y694035D01*
G01X1535574Y693937D02*
X1535572Y693963D01*
G01X1534627Y692557D02*
X1534628Y692559D01*
G01X1534626Y692552D02*
X1534627Y692557D01*
G01X1534626Y692543D02*
Y692552D01*
G01X1534627Y687557D02*
X1534628Y687559D01*
G01X1534626Y687552D02*
X1534627Y687557D01*
G01X1534626Y687543D02*
Y687552D01*
G01X1534627Y682557D02*
X1534628Y682559D01*
G01X1534626Y682552D02*
X1534627Y682557D01*
G01X1534626Y682543D02*
Y682552D01*
G01X1534627Y677557D02*
X1534628Y677559D01*
G01X1534626Y677552D02*
X1534627Y677557D01*
G01X1534626Y677543D02*
Y677552D01*
G01X1534627Y672557D02*
X1534628Y672559D01*
G01X1534626Y672552D02*
X1534627Y672557D01*
G01X1534626Y672543D02*
Y672552D01*
G01X1535610Y648911D02*
X1535611Y648920D01*
G01X1535610Y673911D02*
X1535611Y673920D01*
G01X1535610Y678911D02*
X1535611Y678920D01*
G01X1535610Y683911D02*
X1535611Y683920D01*
G01X1535610Y688911D02*
X1535611Y688920D01*
G01X1535610Y693911D02*
X1535611Y693920D01*
G01X1539961Y692559D02*
Y693937D01*
G01Y687559D02*
Y688937D01*
G01Y682559D02*
Y683937D01*
G01Y677559D02*
Y678937D01*
G01Y672559D02*
Y673937D01*
G01X1536791D02*
Y672559D01*
G01Y678937D02*
Y677559D01*
G01Y683937D02*
Y682559D01*
G01Y688937D02*
Y687559D01*
G01Y693937D02*
Y692559D01*
G01X1536220Y671791D02*
Y649705D01*
G01X1535610Y692067D02*
Y694429D01*
G01Y687067D02*
Y689429D01*
G01Y682067D02*
Y684429D01*
G01Y677067D02*
Y679429D01*
G01Y672067D02*
Y674429D01*
G01X1535039Y670610D02*
Y650886D01*
G01X1534626Y674429D02*
Y672067D01*
G01Y679429D02*
Y677067D01*
G01Y684429D02*
Y682067D01*
G01Y689429D02*
Y687067D01*
G01Y694429D02*
Y692067D01*
G01X1532283Y748248D02*
Y671791D01*
G01X1531102Y747067D02*
Y670610D01*
G01X1535039D02*
X1536220Y671791D01*
G01X1531102Y670610D02*
X1532283Y671791D01*
G01X1535039Y650886D02*
X1536220Y649705D01*
G01X1531102Y650886D02*
X1532283Y649705D01*
G01X1535610Y694429D02*
X1534626D01*
G01X1534628Y693937D02*
X1539961D01*
G01Y693898D02*
X1535613D01*
G01X1539961Y692559D02*
X1534628D01*
G01X1534626Y692067D02*
X1535610D01*
G01Y689429D02*
X1534626D01*
G01X1534628Y688937D02*
X1539961D01*
G01Y688898D02*
X1535613D01*
G01X1539961Y687559D02*
X1534628D01*
G01X1534626Y687067D02*
X1535610D01*
G01Y684429D02*
X1534626D01*
G01X1534628Y683937D02*
X1539961D01*
G01Y683898D02*
X1535613D01*
G01X1539961Y682559D02*
X1534628D01*
G01X1534626Y682067D02*
X1535610D01*
G01Y679429D02*
X1534626D01*
G01X1534628Y678937D02*
X1539961D01*
G01Y678898D02*
X1535613D01*
G01X1539961Y677559D02*
X1534628D01*
G01X1534626Y677067D02*
X1535610D01*
G01Y674429D02*
X1534626D01*
G01X1534628Y673937D02*
X1539961D01*
G01Y673898D02*
X1535613D01*
G01X1539961Y672559D02*
X1534628D01*
G01X1534626Y672067D02*
X1535610D01*
G01X1532283Y671791D02*
X1536220D01*
G01X1531102Y670610D02*
X1535039D01*
G01Y650886D02*
X1531102D01*
G01X1536220Y649705D02*
X1532283D01*
G01X1535610Y649429D02*
X1534626D01*
G01X1534628Y648937D02*
X1539961D01*
G01Y648898D02*
X1535613D01*
G01X1534626Y694133D02*
X1535581Y694134D01*
G01X1535610Y692363D02*
X1534626Y692362D01*
G01Y689133D02*
X1535581Y689134D01*
G01X1535610Y687363D02*
X1534626Y687362D01*
G01Y684133D02*
X1535581Y684134D01*
G01X1535610Y682363D02*
X1534626Y682362D01*
G01Y679133D02*
X1535581Y679134D01*
G01X1535610Y677363D02*
X1534626Y677362D01*
G01Y674133D02*
X1535581Y674134D01*
G01X1535610Y672363D02*
X1534626Y672362D01*
G01Y649133D02*
X1535581Y649134D01*
G01X1535598Y698929D02*
X1535609Y698913D01*
G01X1535573Y698937D02*
X1535598Y698929D01*
G01Y703929D02*
X1535609Y703913D01*
G01X1535573Y703937D02*
X1535598Y703929D01*
G01Y708929D02*
X1535609Y708913D01*
G01X1535573Y708937D02*
X1535598Y708929D01*
G01Y713929D02*
X1535609Y713913D01*
G01X1535573Y713937D02*
X1535598Y713929D01*
G01Y718929D02*
X1535609Y718913D01*
G01X1535573Y718937D02*
X1535598Y718929D01*
G01Y723929D02*
X1535609Y723913D01*
G01X1535573Y723937D02*
X1535598Y723929D01*
G01Y728929D02*
X1535609Y728913D01*
G01X1535573Y728937D02*
X1535598Y728929D01*
G01Y733929D02*
X1535609Y733913D01*
G01X1535573Y733937D02*
X1535598Y733929D01*
G01Y738929D02*
X1535609Y738913D01*
G01X1535573Y738937D02*
X1535598Y738929D01*
G01Y743929D02*
X1535609Y743913D01*
G01X1535573Y743937D02*
X1535598Y743929D01*
G01X1535611Y698904D02*
X1535610Y698911D01*
G01X1535611Y698900D02*
Y698904D01*
G01X1535613Y698898D02*
X1535611Y698900D01*
G01Y703904D02*
X1535610Y703911D01*
G01X1535611Y703900D02*
Y703904D01*
G01X1535613Y703898D02*
X1535611Y703900D01*
G01Y708904D02*
X1535610Y708911D01*
G01X1535611Y708900D02*
Y708904D01*
G01X1535613Y708898D02*
X1535611Y708900D01*
G01Y713904D02*
X1535610Y713911D01*
G01X1535611Y713900D02*
Y713904D01*
G01X1535613Y713898D02*
X1535611Y713900D01*
G01Y718904D02*
X1535610Y718911D01*
G01X1535611Y718900D02*
Y718904D01*
G01X1535613Y718898D02*
X1535611Y718900D01*
G01Y723904D02*
X1535610Y723911D01*
G01X1535611Y723900D02*
Y723904D01*
G01X1535613Y723898D02*
X1535611Y723900D01*
G01Y728904D02*
X1535610Y728911D01*
G01X1535611Y728900D02*
Y728904D01*
G01X1535613Y728898D02*
X1535611Y728900D01*
G01Y733904D02*
X1535610Y733911D01*
G01X1535611Y733900D02*
Y733904D01*
G01X1535613Y733898D02*
X1535611Y733900D01*
G01Y738904D02*
X1535610Y738911D01*
G01X1535611Y738900D02*
Y738904D01*
G01X1535613Y738898D02*
X1535611Y738900D01*
G01Y743904D02*
X1535610Y743911D01*
G01X1535611Y743900D02*
Y743904D01*
G01X1535613Y743898D02*
X1535611Y743900D01*
G01Y742552D02*
X1535610Y742543D01*
G01X1535611Y742557D02*
Y742552D01*
G01X1535613Y742559D02*
X1535611Y742557D01*
G01Y737552D02*
X1535610Y737543D01*
G01X1535611Y737557D02*
Y737552D01*
G01X1535613Y737559D02*
X1535611Y737557D01*
G01Y732552D02*
X1535610Y732543D01*
G01X1535611Y732557D02*
Y732552D01*
G01X1535613Y732559D02*
X1535611Y732557D01*
G01Y727552D02*
X1535610Y727543D01*
G01X1535611Y727557D02*
Y727552D01*
G01X1535613Y727559D02*
X1535611Y727557D01*
G01Y722552D02*
X1535610Y722543D01*
G01X1535611Y722557D02*
Y722552D01*
G01X1535613Y722559D02*
X1535611Y722557D01*
G01Y717552D02*
X1535610Y717543D01*
G01X1535611Y717557D02*
Y717552D01*
G01X1535613Y717559D02*
X1535611Y717557D01*
G01Y712552D02*
X1535610Y712543D01*
G01X1535611Y712557D02*
Y712552D01*
G01X1535613Y712559D02*
X1535611Y712557D01*
G01Y707552D02*
X1535610Y707543D01*
G01X1535611Y707557D02*
Y707552D01*
G01X1535613Y707559D02*
X1535611Y707557D01*
G01Y702552D02*
X1535610Y702543D01*
G01X1535611Y702557D02*
Y702552D01*
G01X1535613Y702559D02*
X1535611Y702557D01*
G01Y697552D02*
X1535610Y697543D01*
G01X1535611Y697557D02*
Y697552D01*
G01X1535613Y697559D02*
X1535611Y697557D01*
G01X1534626Y698944D02*
Y698954D01*
G01X1534627Y698939D02*
X1534626Y698944D01*
G01X1534628Y698937D02*
X1534627Y698939D01*
G01X1534626Y703944D02*
Y703954D01*
G01X1534627Y703939D02*
X1534626Y703944D01*
G01X1534628Y703937D02*
X1534627Y703939D01*
G01X1534626Y708944D02*
Y708954D01*
G01X1534627Y708939D02*
X1534626Y708944D01*
G01X1534628Y708937D02*
X1534627Y708939D01*
G01X1534626Y713944D02*
Y713954D01*
G01X1534627Y713939D02*
X1534626Y713944D01*
G01X1534628Y713937D02*
X1534627Y713939D01*
G01X1534626Y718944D02*
Y718954D01*
G01X1534627Y718939D02*
X1534626Y718944D01*
G01X1534628Y718937D02*
X1534627Y718939D01*
G01X1534626Y723944D02*
Y723954D01*
G01X1534627Y723939D02*
X1534626Y723944D01*
G01X1534628Y723937D02*
X1534627Y723939D01*
G01X1534626Y728944D02*
Y728954D01*
G01X1534627Y728939D02*
X1534626Y728944D01*
G01X1534628Y728937D02*
X1534627Y728939D01*
G01X1534626Y733944D02*
Y733954D01*
G01X1534627Y733939D02*
X1534626Y733944D01*
G01X1534628Y733937D02*
X1534627Y733939D01*
G01X1534626Y738944D02*
Y738954D01*
G01X1534627Y738939D02*
X1534626Y738944D01*
G01X1534628Y738937D02*
X1534627Y738939D01*
G01X1534626Y743944D02*
Y743954D01*
G01X1534627Y743939D02*
X1534626Y743944D01*
G01X1534628Y743937D02*
X1534627Y743939D01*
G01X1535602Y699081D02*
X1535610Y699055D01*
G01X1535593Y699107D02*
X1535602Y699081D01*
G01X1535581Y699134D02*
X1535593Y699107D01*
G01X1535602Y704081D02*
X1535610Y704055D01*
G01X1535593Y704107D02*
X1535602Y704081D01*
G01X1535581Y704134D02*
X1535593Y704107D01*
G01X1535602Y709081D02*
X1535610Y709055D01*
G01X1535593Y709107D02*
X1535602Y709081D01*
G01X1535581Y709134D02*
X1535593Y709107D01*
G01X1535602Y714081D02*
X1535610Y714055D01*
G01X1535593Y714107D02*
X1535602Y714081D01*
G01X1535581Y714134D02*
X1535593Y714107D01*
G01X1535602Y719081D02*
X1535610Y719055D01*
G01X1535593Y719107D02*
X1535602Y719081D01*
G01X1535581Y719134D02*
X1535593Y719107D01*
G01X1535602Y724081D02*
X1535610Y724055D01*
G01X1535593Y724107D02*
X1535602Y724081D01*
G01X1535581Y724134D02*
X1535593Y724107D01*
G01X1535602Y729081D02*
X1535610Y729055D01*
G01X1535593Y729107D02*
X1535602Y729081D01*
G01X1535581Y729134D02*
X1535593Y729107D01*
G01X1535602Y734081D02*
X1535610Y734055D01*
G01X1535593Y734107D02*
X1535602Y734081D01*
G01X1535581Y734134D02*
X1535593Y734107D01*
G01X1535602Y739081D02*
X1535610Y739055D01*
G01X1535593Y739107D02*
X1535602Y739081D01*
G01X1535581Y739134D02*
X1535593Y739107D01*
G01X1535602Y744081D02*
X1535610Y744055D01*
G01X1535593Y744107D02*
X1535602Y744081D01*
G01X1535581Y744134D02*
X1535593Y744107D01*
G01Y698932D02*
X1535574Y698937D01*
G01X1535607Y698918D02*
X1535593Y698932D01*
G01X1535613Y698898D02*
X1535607Y698918D01*
G01X1535593Y703932D02*
X1535574Y703937D01*
G01X1535607Y703918D02*
X1535593Y703932D01*
G01X1535613Y703898D02*
X1535607Y703918D01*
G01X1535593Y708932D02*
X1535574Y708937D01*
G01X1535607Y708918D02*
X1535593Y708932D01*
G01X1535613Y708898D02*
X1535607Y708918D01*
G01X1535593Y713932D02*
X1535574Y713937D01*
G01X1535607Y713918D02*
X1535593Y713932D01*
G01X1535613Y713898D02*
X1535607Y713918D01*
G01X1535593Y718932D02*
X1535574Y718937D01*
G01X1535607Y718918D02*
X1535593Y718932D01*
G01X1535613Y718898D02*
X1535607Y718918D01*
G01X1535593Y723932D02*
X1535574Y723937D01*
G01X1535607Y723918D02*
X1535593Y723932D01*
G01X1535613Y723898D02*
X1535607Y723918D01*
G01X1535593Y728932D02*
X1535574Y728937D01*
G01X1535607Y728918D02*
X1535593Y728932D01*
G01X1535613Y728898D02*
X1535607Y728918D01*
G01X1535593Y733932D02*
X1535574Y733937D01*
G01X1535607Y733918D02*
X1535593Y733932D01*
G01X1535613Y733898D02*
X1535607Y733918D01*
G01X1535593Y738932D02*
X1535574Y738937D01*
G01X1535607Y738918D02*
X1535593Y738932D01*
G01X1535613Y738898D02*
X1535607Y738918D01*
G01X1535593Y743932D02*
X1535574Y743937D01*
G01X1535607Y743918D02*
X1535593Y743932D01*
G01X1535613Y743898D02*
X1535607Y743918D01*
G01X1535577Y699035D02*
X1535581Y699134D01*
G01X1535572Y698963D02*
X1535577Y699035D01*
G01X1535574Y698937D02*
X1535572Y698963D01*
G01X1535577Y704035D02*
X1535581Y704134D01*
G01X1535572Y703963D02*
X1535577Y704035D01*
G01X1535574Y703937D02*
X1535572Y703963D01*
G01X1535577Y709035D02*
X1535581Y709134D01*
G01X1535572Y708963D02*
X1535577Y709035D01*
G01X1535574Y708937D02*
X1535572Y708963D01*
G01X1535577Y714035D02*
X1535581Y714134D01*
G01X1535572Y713963D02*
X1535577Y714035D01*
G01X1535574Y713937D02*
X1535572Y713963D01*
G01X1535577Y719035D02*
X1535581Y719134D01*
G01X1535572Y718963D02*
X1535577Y719035D01*
G01X1535574Y718937D02*
X1535572Y718963D01*
G01X1535577Y724035D02*
X1535581Y724134D01*
G01X1535572Y723963D02*
X1535577Y724035D01*
G01X1535574Y723937D02*
X1535572Y723963D01*
G01X1535577Y729035D02*
X1535581Y729134D01*
G01X1535572Y728963D02*
X1535577Y729035D01*
G01X1535574Y728937D02*
X1535572Y728963D01*
G01X1535577Y734035D02*
X1535581Y734134D01*
G01X1535572Y733963D02*
X1535577Y734035D01*
G01X1535574Y733937D02*
X1535572Y733963D01*
G01X1535577Y739035D02*
X1535581Y739134D01*
G01X1535572Y738963D02*
X1535577Y739035D01*
G01X1535574Y738937D02*
X1535572Y738963D01*
G01X1535577Y744035D02*
X1535581Y744134D01*
G01X1535572Y743963D02*
X1535577Y744035D01*
G01X1535574Y743937D02*
X1535572Y743963D01*
G01X1534627Y742557D02*
X1534628Y742559D01*
G01X1534626Y742552D02*
X1534627Y742557D01*
G01X1534626Y742543D02*
Y742552D01*
G01X1534627Y737557D02*
X1534628Y737559D01*
G01X1534626Y737552D02*
X1534627Y737557D01*
G01X1534626Y737543D02*
Y737552D01*
G01X1534627Y732557D02*
X1534628Y732559D01*
G01X1534626Y732552D02*
X1534627Y732557D01*
G01X1534626Y732543D02*
Y732552D01*
G01X1534627Y727557D02*
X1534628Y727559D01*
G01X1534626Y727552D02*
X1534627Y727557D01*
G01X1534626Y727543D02*
Y727552D01*
G01X1534627Y722557D02*
X1534628Y722559D01*
G01X1534626Y722552D02*
X1534627Y722557D01*
G01X1534626Y722543D02*
Y722552D01*
G01X1534627Y717557D02*
X1534628Y717559D01*
G01X1534626Y717552D02*
X1534627Y717557D01*
G01X1534626Y717543D02*
Y717552D01*
G01X1534627Y712557D02*
X1534628Y712559D01*
G01X1534626Y712552D02*
X1534627Y712557D01*
G01X1534626Y712543D02*
Y712552D01*
G01X1534627Y707557D02*
X1534628Y707559D01*
G01X1534626Y707552D02*
X1534627Y707557D01*
G01X1534626Y707543D02*
Y707552D01*
G01X1534627Y702557D02*
X1534628Y702559D01*
G01X1534626Y702552D02*
X1534627Y702557D01*
G01X1534626Y702543D02*
Y702552D01*
G01X1534627Y697557D02*
X1534628Y697559D01*
G01X1534626Y697552D02*
X1534627Y697557D01*
G01X1534626Y697543D02*
Y697552D01*
G01X1535610Y698911D02*
X1535611Y698920D01*
G01X1535610Y703911D02*
X1535611Y703920D01*
G01X1535610Y708911D02*
X1535611Y708920D01*
G01X1535610Y713911D02*
X1535611Y713920D01*
G01X1535610Y718911D02*
X1535611Y718920D01*
G01X1535610Y723911D02*
X1535611Y723920D01*
G01X1535610Y728911D02*
X1535611Y728920D01*
G01X1535610Y733911D02*
X1535611Y733920D01*
G01X1535610Y738911D02*
X1535611Y738920D01*
G01X1535610Y743911D02*
X1535611Y743920D01*
G01X1539961Y742559D02*
Y743937D01*
G01Y737559D02*
Y738937D01*
G01Y732559D02*
Y733937D01*
G01Y727559D02*
Y728937D01*
G01Y722559D02*
Y723937D01*
G01Y717559D02*
Y718937D01*
G01Y712559D02*
Y713937D01*
G01Y707559D02*
Y708937D01*
G01Y702559D02*
Y703937D01*
G01Y697559D02*
Y698937D01*
G01X1536791D02*
Y697559D01*
G01Y703937D02*
Y702559D01*
G01Y708937D02*
Y707559D01*
G01Y713937D02*
Y712559D01*
G01Y718937D02*
Y717559D01*
G01Y723937D02*
Y722559D01*
G01Y728937D02*
Y727559D01*
G01Y733937D02*
Y732559D01*
G01Y738937D02*
Y737559D01*
G01Y743937D02*
Y742559D01*
G01X1535610Y742067D02*
Y744429D01*
G01Y737067D02*
Y739429D01*
G01Y732067D02*
Y734429D01*
G01Y727067D02*
Y729429D01*
G01Y722067D02*
Y724429D01*
G01Y717067D02*
Y719429D01*
G01Y712067D02*
Y714429D01*
G01Y707067D02*
Y709429D01*
G01Y702067D02*
Y704429D01*
G01Y697067D02*
Y699429D01*
G01X1534626D02*
Y697067D01*
G01Y704429D02*
Y702067D01*
G01Y709429D02*
Y707067D01*
G01Y714429D02*
Y712067D01*
G01Y719429D02*
Y717067D01*
G01Y724429D02*
Y722067D01*
G01Y729429D02*
Y727067D01*
G01Y734429D02*
Y732067D01*
G01Y739429D02*
Y737067D01*
G01Y744429D02*
Y742067D01*
G01X1535610Y744429D02*
X1534626D01*
G01X1534628Y743937D02*
X1539961D01*
G01Y743898D02*
X1535613D01*
G01X1539961Y742559D02*
X1534628D01*
G01X1534626Y742067D02*
X1535610D01*
G01Y739429D02*
X1534626D01*
G01X1534628Y738937D02*
X1539961D01*
G01Y738898D02*
X1535613D01*
G01X1539961Y737559D02*
X1534628D01*
G01X1534626Y737067D02*
X1535610D01*
G01Y734429D02*
X1534626D01*
G01X1534628Y733937D02*
X1539961D01*
G01Y733898D02*
X1535613D01*
G01X1539961Y732559D02*
X1534628D01*
G01X1534626Y732067D02*
X1535610D01*
G01Y729429D02*
X1534626D01*
G01X1534628Y728937D02*
X1539961D01*
G01Y728898D02*
X1535613D01*
G01X1539961Y727559D02*
X1534628D01*
G01X1534626Y727067D02*
X1535610D01*
G01Y724429D02*
X1534626D01*
G01X1534628Y723937D02*
X1539961D01*
G01Y723898D02*
X1535613D01*
G01X1539961Y722559D02*
X1534628D01*
G01X1534626Y722067D02*
X1535610D01*
G01Y719429D02*
X1534626D01*
G01X1534628Y718937D02*
X1539961D01*
G01Y718898D02*
X1535613D01*
G01X1539961Y717559D02*
X1534628D01*
G01X1534626Y717067D02*
X1535610D01*
G01Y714429D02*
X1534626D01*
G01X1534628Y713937D02*
X1539961D01*
G01Y713898D02*
X1535613D01*
G01X1539961Y712559D02*
X1534628D01*
G01X1534626Y712067D02*
X1535610D01*
G01Y709429D02*
X1534626D01*
G01X1534628Y708937D02*
X1539961D01*
G01Y708898D02*
X1535613D01*
G01X1539961Y707559D02*
X1534628D01*
G01X1534626Y707067D02*
X1535610D01*
G01X1534626Y744133D02*
X1535581Y744134D01*
G01X1535610Y742363D02*
X1534626Y742362D01*
G01Y739133D02*
X1535581Y739134D01*
G01X1535610Y737363D02*
X1534626Y737362D01*
G01Y734133D02*
X1535581Y734134D01*
G01X1535610Y732363D02*
X1534626Y732362D01*
G01Y729133D02*
X1535581Y729134D01*
G01X1535610Y727363D02*
X1534626Y727362D01*
G01Y724133D02*
X1535581Y724134D01*
G01X1535610Y722363D02*
X1534626Y722362D01*
G01Y719133D02*
X1535581Y719134D01*
G01X1535610Y717363D02*
X1534626Y717362D01*
G01Y714133D02*
X1535581Y714134D01*
G01X1535610Y712363D02*
X1534626Y712362D01*
G01Y709133D02*
X1535581Y709134D01*
G01X1535610Y707363D02*
X1534626Y707362D01*
G01X1535610Y704429D02*
X1534626D01*
G01X1534628Y703937D02*
X1539961D01*
G01Y703898D02*
X1535613D01*
G01X1539961Y702559D02*
X1534628D01*
G01X1534626Y702067D02*
X1535610D01*
G01Y699429D02*
X1534626D01*
G01X1534628Y698937D02*
X1539961D01*
G01Y698898D02*
X1535613D01*
G01X1539961Y697559D02*
X1534628D01*
G01X1534626Y697067D02*
X1535610D01*
G01X1534626Y704133D02*
X1535581Y704134D01*
G01X1535610Y702363D02*
X1534626Y702362D01*
G01Y699133D02*
X1535581Y699134D01*
G01X1535610Y697363D02*
X1534626Y697362D01*
G01X1534055Y769429D02*
G03X1533465Y770020I-591J0D01*
G01X1526772D02*
G03X1526181Y769429I0J-591D01*
G01X1528937Y768248D02*
G03Y766280I0J-984D01*
G01X1531299D02*
G03Y768248I0J984D01*
G01X1540945Y768839D02*
G03X1538976Y770807I-1968J0D01*
G01X1527559Y760335D02*
G03X1526378Y759154I0J-1181D01*
G01X1533858D02*
G03X1532677Y760335I-1181J0D01*
G01X1532008Y755059D02*
G03I-1890J0D01*
G01X1532480D02*
G03I-2362J0D01*
G01X1540945Y753091D02*
Y768839D01*
G01X1534055Y763327D02*
Y769429D01*
G01X1533858Y759154D02*
Y750610D01*
G01X1531299Y755650D02*
Y753957D01*
G01X1528937D02*
Y755650D01*
G01X1526378Y750610D02*
Y759154D01*
G01X1526181Y763327D02*
Y769429D01*
G01X1528937Y755650D02*
X1526627Y759879D01*
G01X1527633Y751988D02*
X1528937Y753957D01*
G01X1533609Y759879D02*
X1531299Y755650D01*
G01Y753957D02*
X1532603Y751988D01*
G01X1540945Y753091D02*
X1537598Y749744D01*
G01X1531102Y747067D02*
X1532283Y748248D01*
G01X1524409D02*
X1525591Y747067D01*
G01X1533465Y770020D02*
X1526772D01*
G01X1531299Y768248D02*
X1528937D01*
G01Y766280D02*
X1531299D01*
G01X1534055Y764902D02*
X1526181D01*
G01Y763327D02*
X1534055D01*
G01X1527559Y760335D02*
X1532677D01*
G01X1528937Y755650D02*
X1531299D01*
G01X1528937Y753957D02*
X1531299D01*
G01X1537008Y750610D02*
X1533858D01*
G01X1524409Y748248D02*
X1532283D01*
G01X1525591Y747067D02*
X1531102D01*
G01X1532996Y831641D02*
G03X1566807I16906J-13531D01*
G01X1559882Y844772D02*
G03X1566807Y831641I37662J11471D01*
G01X1532996D02*
G03X1539921Y844772I-30737J24602D01*
G01X1559882D02*
G03X1566807Y831641I37662J11471D01*
G01X1532996D02*
G03X1566807I16906J-13531D01*
G01X1532996D02*
G03X1539921Y844772I-30737J24602D01*
G01X1559882D02*
G03X1539921I-9980J-3039D01*
G01X1559882D02*
G03X1539921I-9980J-3040D01*
G01X1535611Y1080308D02*
X1535610Y1080299D01*
G01X1535611Y1080313D02*
Y1080308D01*
G01X1535613Y1080315D02*
X1535611Y1080313D01*
G01Y1075308D02*
X1535610Y1075299D01*
G01X1535611Y1075313D02*
Y1075308D01*
G01X1535613Y1075315D02*
X1535611Y1075313D01*
G01Y1070308D02*
X1535610Y1070299D01*
G01X1535611Y1070313D02*
Y1070308D01*
G01X1535613Y1070315D02*
X1535611Y1070313D01*
G01X1535598Y1071685D02*
X1535609Y1071669D01*
G01X1535573Y1071693D02*
X1535598Y1071685D01*
G01Y1076685D02*
X1535609Y1076669D01*
G01X1535573Y1076693D02*
X1535598Y1076685D01*
G01Y1081685D02*
X1535609Y1081669D01*
G01X1535573Y1081693D02*
X1535598Y1081685D01*
G01X1535577Y1071791D02*
X1535581Y1071890D01*
G01X1535572Y1071719D02*
X1535577Y1071791D01*
G01X1535574Y1071693D02*
X1535572Y1071719D01*
G01X1535577Y1076791D02*
X1535581Y1076890D01*
G01X1535572Y1076719D02*
X1535577Y1076791D01*
G01X1535574Y1076693D02*
X1535572Y1076719D01*
G01X1535577Y1081791D02*
X1535581Y1081890D01*
G01X1535572Y1081719D02*
X1535577Y1081791D01*
G01X1535574Y1081693D02*
X1535572Y1081719D01*
G01X1534627Y1080313D02*
X1534628Y1080315D01*
G01X1534626Y1080308D02*
X1534627Y1080313D01*
G01X1534626Y1080299D02*
Y1080308D01*
G01X1534627Y1075313D02*
X1534628Y1075315D01*
G01X1534626Y1075308D02*
X1534627Y1075313D01*
G01X1534626Y1075299D02*
Y1075308D01*
G01X1534627Y1070313D02*
X1534628Y1070315D01*
G01X1534626Y1070308D02*
X1534627Y1070313D01*
G01X1534626Y1070299D02*
Y1070308D01*
G01X1535611Y1071660D02*
X1535610Y1071667D01*
G01X1535611Y1071656D02*
Y1071660D01*
G01X1535613Y1071654D02*
X1535611Y1071656D01*
G01Y1076660D02*
X1535610Y1076667D01*
G01X1535611Y1076656D02*
Y1076660D01*
G01X1535613Y1076654D02*
X1535611Y1076656D01*
G01Y1081660D02*
X1535610Y1081667D01*
G01X1535611Y1081656D02*
Y1081660D01*
G01X1535613Y1081654D02*
X1535611Y1081656D01*
G01X1534626Y1071700D02*
Y1071709D01*
G01X1534627Y1071695D02*
X1534626Y1071700D01*
G01X1534628Y1071693D02*
X1534627Y1071695D01*
G01X1534626Y1076700D02*
Y1076709D01*
G01X1534627Y1076695D02*
X1534626Y1076700D01*
G01X1534628Y1076693D02*
X1534627Y1076695D01*
G01X1534626Y1081700D02*
Y1081709D01*
G01X1534627Y1081695D02*
X1534626Y1081700D01*
G01X1534628Y1081693D02*
X1534627Y1081695D01*
G01X1535602Y1071837D02*
X1535610Y1071811D01*
G01X1535593Y1071863D02*
X1535602Y1071837D01*
G01X1535581Y1071890D02*
X1535593Y1071863D01*
G01X1535602Y1076837D02*
X1535610Y1076811D01*
G01X1535593Y1076863D02*
X1535602Y1076837D01*
G01X1535581Y1076890D02*
X1535593Y1076863D01*
G01Y1071688D02*
X1535574Y1071693D01*
G01X1535607Y1071674D02*
X1535593Y1071688D01*
G01X1535613Y1071654D02*
X1535607Y1071674D01*
G01X1535593Y1076688D02*
X1535574Y1076693D01*
G01X1535607Y1076674D02*
X1535593Y1076688D01*
G01X1535613Y1076654D02*
X1535607Y1076674D01*
G01X1535593Y1081688D02*
X1535574Y1081693D01*
G01X1535607Y1081674D02*
X1535593Y1081688D01*
G01X1535613Y1081654D02*
X1535607Y1081674D01*
G01X1535602Y1081837D02*
X1535610Y1081811D01*
G01X1535593Y1081863D02*
X1535602Y1081837D01*
G01X1535581Y1081890D02*
X1535593Y1081863D01*
G01X1526181Y1044823D02*
G03X1526772Y1044232I591J0D01*
G01X1533465D02*
G03X1534055Y1044823I-1J591D01*
G01X1531299Y1046004D02*
G03Y1047972I0J984D01*
G01X1528937D02*
G03Y1046004I0J-984D01*
G01X1531220Y1059193D02*
G03I-1102J0D01*
G01X1532677Y1053917D02*
G03X1533858Y1055098I0J1181D01*
G01X1526378D02*
G03X1527559Y1053917I1181J0D01*
G01X1531693Y1059193D02*
G03I-1575J0D01*
G01X1538976Y1043445D02*
G03X1540945Y1045413I0J1969D01*
G01X1531299Y1058602D02*
X1533609Y1054373D01*
G01X1528937Y1060295D02*
X1527633Y1062264D01*
G01X1537598Y1064508D02*
X1540945Y1061161D01*
G01X1531102Y1067185D02*
X1532283Y1066004D01*
G01X1535610Y1071667D02*
X1535611Y1071676D01*
G01X1535610Y1076667D02*
X1535611Y1076676D01*
G01X1535610Y1081667D02*
X1535611Y1081676D01*
G01X1540945Y1045413D02*
Y1061161D01*
G01X1539961Y1080315D02*
Y1081693D01*
G01Y1075315D02*
Y1076693D01*
G01Y1070315D02*
Y1071693D01*
G01X1537598Y1202500D02*
Y1064508D01*
G01X1537008Y1204744D02*
Y1062264D01*
G01X1536791Y1071693D02*
Y1070315D01*
G01Y1076693D02*
Y1075315D01*
G01Y1081693D02*
Y1080315D01*
G01X1535610Y1079823D02*
Y1082185D01*
G01Y1074823D02*
Y1077185D01*
G01Y1069823D02*
Y1072185D01*
G01Y1071667D02*
Y1071811D01*
G01Y1076667D02*
Y1076811D01*
G01Y1081667D02*
Y1081811D01*
G01X1534626Y1072185D02*
Y1069823D01*
G01Y1077185D02*
Y1074823D01*
G01Y1082185D02*
Y1079823D01*
G01X1534055Y1050925D02*
Y1044823D01*
G01X1533858Y1063642D02*
Y1055098D01*
G01X1532283Y1102461D02*
Y1066004D01*
G01X1531299Y1060295D02*
Y1058602D01*
G01X1531102Y1103642D02*
Y1067185D01*
G01X1528937Y1058602D02*
Y1060295D01*
G01X1526378Y1055098D02*
Y1063642D01*
G01X1526181Y1050925D02*
Y1044823D01*
G01X1525591Y1067185D02*
Y1199823D01*
G01X1524409Y1066004D02*
Y1201004D01*
G01X1535610Y1082185D02*
X1534626D01*
G01X1534628Y1081693D02*
X1539961D01*
G01Y1081654D02*
X1535613D01*
G01X1539961Y1080315D02*
X1534628D01*
G01X1534626Y1079823D02*
X1535610D01*
G01Y1077185D02*
X1534626D01*
G01X1534628Y1076693D02*
X1539961D01*
G01Y1076654D02*
X1535613D01*
G01X1539961Y1075315D02*
X1534628D01*
G01X1534626Y1074823D02*
X1535610D01*
G01Y1072185D02*
X1534626D01*
G01X1534628Y1071693D02*
X1539961D01*
G01Y1071654D02*
X1535613D01*
G01X1539961Y1070315D02*
X1534628D01*
G01X1534626Y1069823D02*
X1535610D01*
G01X1531102Y1067185D02*
X1525591D01*
G01X1532283Y1066004D02*
X1524409D01*
G01X1534626Y1081889D02*
X1535581Y1081890D01*
G01X1535610Y1080119D02*
X1534626Y1080118D01*
G01Y1076889D02*
X1535581Y1076890D01*
G01X1535610Y1075119D02*
X1534626Y1075118D01*
G01Y1071889D02*
X1535581Y1071890D01*
G01X1535610Y1070119D02*
X1534626Y1070118D01*
G01X1532603Y1062264D02*
X1531299Y1060295D01*
G01X1526627Y1054373D02*
X1528937Y1058602D01*
G01X1533858Y1063642D02*
X1537008D01*
G01X1531299Y1060295D02*
X1528937D01*
G01X1531299Y1058602D02*
X1528937D01*
G01X1532677Y1053917D02*
X1527559D01*
G01X1534055Y1050925D02*
X1526181D01*
G01Y1049350D02*
X1534055D01*
G01X1531299Y1047972D02*
X1528937D01*
G01Y1046004D02*
X1531299D01*
G01X1533465Y1044232D02*
X1526772D01*
G01X1525591Y1067185D02*
X1524409Y1066004D01*
G01X1535611Y1130308D02*
X1535610Y1130299D01*
G01X1535611Y1130313D02*
Y1130308D01*
G01X1535613Y1130315D02*
X1535611Y1130313D01*
G01Y1125308D02*
X1535610Y1125299D01*
G01X1535611Y1125313D02*
Y1125308D01*
G01X1535613Y1125315D02*
X1535611Y1125313D01*
G01Y1100308D02*
X1535610Y1100299D01*
G01X1535611Y1100313D02*
Y1100308D01*
G01X1535613Y1100315D02*
X1535611Y1100313D01*
G01Y1095308D02*
X1535610Y1095299D01*
G01X1535611Y1095313D02*
Y1095308D01*
G01X1535613Y1095315D02*
X1535611Y1095313D01*
G01Y1090308D02*
X1535610Y1090299D01*
G01X1535611Y1090313D02*
Y1090308D01*
G01X1535613Y1090315D02*
X1535611Y1090313D01*
G01Y1085308D02*
X1535610Y1085299D01*
G01X1535611Y1085313D02*
Y1085308D01*
G01X1535613Y1085315D02*
X1535611Y1085313D01*
G01X1535598Y1086685D02*
X1535609Y1086669D01*
G01X1535573Y1086693D02*
X1535598Y1086685D01*
G01Y1091685D02*
X1535609Y1091669D01*
G01X1535573Y1091693D02*
X1535598Y1091685D01*
G01Y1096685D02*
X1535609Y1096669D01*
G01X1535573Y1096693D02*
X1535598Y1096685D01*
G01Y1101685D02*
X1535609Y1101669D01*
G01X1535573Y1101693D02*
X1535598Y1101685D01*
G01Y1126685D02*
X1535609Y1126669D01*
G01X1535573Y1126693D02*
X1535598Y1126685D01*
G01X1535577Y1086791D02*
X1535581Y1086890D01*
G01X1535572Y1086719D02*
X1535577Y1086791D01*
G01X1535574Y1086693D02*
X1535572Y1086719D01*
G01X1535577Y1091791D02*
X1535581Y1091890D01*
G01X1535572Y1091719D02*
X1535577Y1091791D01*
G01X1535574Y1091693D02*
X1535572Y1091719D01*
G01X1535577Y1096791D02*
X1535581Y1096890D01*
G01X1535572Y1096719D02*
X1535577Y1096791D01*
G01X1535574Y1096693D02*
X1535572Y1096719D01*
G01X1535577Y1101791D02*
X1535581Y1101890D01*
G01X1535572Y1101719D02*
X1535577Y1101791D01*
G01X1535574Y1101693D02*
X1535572Y1101719D01*
G01X1535577Y1126791D02*
X1535581Y1126890D01*
G01X1535572Y1126719D02*
X1535577Y1126791D01*
G01X1535574Y1126693D02*
X1535572Y1126719D01*
G01X1534627Y1130313D02*
X1534628Y1130315D01*
G01X1534626Y1130308D02*
X1534627Y1130313D01*
G01X1534626Y1130299D02*
Y1130308D01*
G01X1534627Y1125313D02*
X1534628Y1125315D01*
G01X1534626Y1125308D02*
X1534627Y1125313D01*
G01X1534626Y1125299D02*
Y1125308D01*
G01X1534627Y1100313D02*
X1534628Y1100315D01*
G01X1534626Y1100308D02*
X1534627Y1100313D01*
G01X1534626Y1100299D02*
Y1100308D01*
G01X1534627Y1095313D02*
X1534628Y1095315D01*
G01X1534626Y1095308D02*
X1534627Y1095313D01*
G01X1534626Y1095299D02*
Y1095308D01*
G01X1534627Y1090313D02*
X1534628Y1090315D01*
G01X1534626Y1090308D02*
X1534627Y1090313D01*
G01X1534626Y1090299D02*
Y1090308D01*
G01X1534627Y1085313D02*
X1534628Y1085315D01*
G01X1534626Y1085308D02*
X1534627Y1085313D01*
G01X1534626Y1085299D02*
Y1085308D01*
G01X1535611Y1086660D02*
X1535610Y1086667D01*
G01X1535611Y1086656D02*
Y1086660D01*
G01X1535613Y1086654D02*
X1535611Y1086656D01*
G01Y1091660D02*
X1535610Y1091667D01*
G01X1535611Y1091656D02*
Y1091660D01*
G01X1535613Y1091654D02*
X1535611Y1091656D01*
G01X1535593Y1086688D02*
X1535574Y1086693D01*
G01X1535607Y1086674D02*
X1535593Y1086688D01*
G01X1535613Y1086654D02*
X1535607Y1086674D01*
G01X1535593Y1091688D02*
X1535574Y1091693D01*
G01X1535607Y1091674D02*
X1535593Y1091688D01*
G01X1535613Y1091654D02*
X1535607Y1091674D01*
G01X1535593Y1096688D02*
X1535574Y1096693D01*
G01X1535607Y1096674D02*
X1535593Y1096688D01*
G01X1535613Y1096654D02*
X1535607Y1096674D01*
G01X1535593Y1101688D02*
X1535574Y1101693D01*
G01X1535607Y1101674D02*
X1535593Y1101688D01*
G01X1535613Y1101654D02*
X1535607Y1101674D01*
G01X1535593Y1126688D02*
X1535574Y1126693D01*
G01X1535607Y1126674D02*
X1535593Y1126688D01*
G01X1535613Y1126654D02*
X1535607Y1126674D01*
G01X1535611Y1096660D02*
X1535610Y1096667D01*
G01X1535611Y1096656D02*
Y1096660D01*
G01X1535613Y1096654D02*
X1535611Y1096656D01*
G01Y1101660D02*
X1535610Y1101667D01*
G01X1535611Y1101656D02*
Y1101660D01*
G01X1535613Y1101654D02*
X1535611Y1101656D01*
G01Y1126660D02*
X1535610Y1126667D01*
G01X1535611Y1126656D02*
Y1126660D01*
G01X1535613Y1126654D02*
X1535611Y1126656D01*
G01X1534626Y1086700D02*
Y1086709D01*
G01X1534627Y1086695D02*
X1534626Y1086700D01*
G01X1534628Y1086693D02*
X1534627Y1086695D01*
G01X1534626Y1091700D02*
Y1091709D01*
G01X1534627Y1091695D02*
X1534626Y1091700D01*
G01X1534628Y1091693D02*
X1534627Y1091695D01*
G01X1534626Y1096700D02*
Y1096709D01*
G01X1534627Y1096695D02*
X1534626Y1096700D01*
G01X1534628Y1096693D02*
X1534627Y1096695D01*
G01X1534626Y1101700D02*
Y1101709D01*
G01X1534627Y1101695D02*
X1534626Y1101700D01*
G01X1534628Y1101693D02*
X1534627Y1101695D01*
G01X1534626Y1126700D02*
Y1126709D01*
G01X1534627Y1126695D02*
X1534626Y1126700D01*
G01X1534628Y1126693D02*
X1534627Y1126695D01*
G01X1535602Y1086837D02*
X1535610Y1086811D01*
G01X1535593Y1086863D02*
X1535602Y1086837D01*
G01X1535581Y1086890D02*
X1535593Y1086863D01*
G01X1535602Y1091837D02*
X1535610Y1091811D01*
G01X1535593Y1091863D02*
X1535602Y1091837D01*
G01X1535581Y1091890D02*
X1535593Y1091863D01*
G01X1535602Y1096837D02*
X1535610Y1096811D01*
G01X1535593Y1096863D02*
X1535602Y1096837D01*
G01X1535581Y1096890D02*
X1535593Y1096863D01*
G01X1535602Y1101837D02*
X1535610Y1101811D01*
G01X1535593Y1101863D02*
X1535602Y1101837D01*
G01X1535581Y1101890D02*
X1535593Y1101863D01*
G01X1535602Y1126837D02*
X1535610Y1126811D01*
G01X1535593Y1126863D02*
X1535602Y1126837D01*
G01X1535581Y1126890D02*
X1535593Y1126863D01*
G01X1535039Y1103642D02*
X1536220Y1102461D01*
G01X1531102Y1103642D02*
X1532283Y1102461D01*
G01X1535610Y1086667D02*
X1535611Y1086676D01*
G01X1535610Y1091667D02*
X1535611Y1091676D01*
G01X1535610Y1096667D02*
X1535611Y1096676D01*
G01X1535610Y1101667D02*
X1535611Y1101676D01*
G01X1535610Y1126667D02*
X1535611Y1126676D01*
G01X1539961Y1130315D02*
Y1131693D01*
G01Y1125315D02*
Y1126693D01*
G01Y1100315D02*
Y1101693D01*
G01Y1095315D02*
Y1096693D01*
G01Y1090315D02*
Y1091693D01*
G01Y1085315D02*
Y1086693D01*
G01X1536791D02*
Y1085315D01*
G01Y1091693D02*
Y1090315D01*
G01Y1096693D02*
Y1095315D01*
G01Y1101693D02*
Y1100315D01*
G01Y1126693D02*
Y1125315D01*
G01Y1131693D02*
Y1130315D01*
G01X1536220Y1124547D02*
Y1102461D01*
G01X1535610Y1129823D02*
Y1132185D01*
G01Y1124823D02*
Y1127185D01*
G01Y1099823D02*
Y1102185D01*
G01Y1094823D02*
Y1097185D01*
G01Y1089823D02*
Y1092185D01*
G01Y1084823D02*
Y1087185D01*
G01Y1086667D02*
Y1086811D01*
G01Y1091667D02*
Y1091811D01*
G01Y1096667D02*
Y1096811D01*
G01Y1101667D02*
Y1101811D01*
G01Y1126667D02*
Y1126811D01*
G01X1535039Y1123366D02*
Y1103642D01*
G01X1534626Y1087185D02*
Y1084823D01*
G01Y1092185D02*
Y1089823D01*
G01Y1097185D02*
Y1094823D01*
G01Y1102185D02*
Y1099823D01*
G01Y1127185D02*
Y1124823D01*
G01Y1132185D02*
Y1129823D01*
G01X1532283Y1201004D02*
Y1124547D01*
G01X1531102Y1199823D02*
Y1123366D01*
G01X1539961Y1130315D02*
X1534628D01*
G01X1534626Y1129823D02*
X1535610D01*
G01Y1127185D02*
X1534626D01*
G01X1534628Y1126693D02*
X1539961D01*
G01Y1126654D02*
X1535613D01*
G01X1539961Y1125315D02*
X1534628D01*
G01X1534626Y1124823D02*
X1535610D01*
G01X1532283Y1124547D02*
X1536220D01*
G01X1531102Y1123366D02*
X1535039D01*
G01Y1103642D02*
X1531102D01*
G01X1536220Y1102461D02*
X1532283D01*
G01X1535610Y1102185D02*
X1534626D01*
G01X1534628Y1101693D02*
X1539961D01*
G01Y1101654D02*
X1535613D01*
G01X1539961Y1100315D02*
X1534628D01*
G01X1534626Y1099823D02*
X1535610D01*
G01Y1097185D02*
X1534626D01*
G01X1534628Y1096693D02*
X1539961D01*
G01Y1096654D02*
X1535613D01*
G01X1539961Y1095315D02*
X1534628D01*
G01X1534626Y1094823D02*
X1535610D01*
G01Y1092185D02*
X1534626D01*
G01X1534628Y1091693D02*
X1539961D01*
G01Y1091654D02*
X1535613D01*
G01X1539961Y1090315D02*
X1534628D01*
G01X1534626Y1089823D02*
X1535610D01*
G01Y1087185D02*
X1534626D01*
G01X1534628Y1086693D02*
X1539961D01*
G01Y1086654D02*
X1535613D01*
G01X1539961Y1085315D02*
X1534628D01*
G01X1534626Y1084823D02*
X1535610D01*
G01Y1130119D02*
X1534626Y1130118D01*
G01Y1126889D02*
X1535581Y1126890D01*
G01X1535610Y1125119D02*
X1534626Y1125118D01*
G01Y1101889D02*
X1535581Y1101890D01*
G01X1535610Y1100119D02*
X1534626Y1100118D01*
G01Y1096889D02*
X1535581Y1096890D01*
G01X1535610Y1095119D02*
X1534626Y1095118D01*
G01Y1091889D02*
X1535581Y1091890D01*
G01X1535610Y1090119D02*
X1534626Y1090118D01*
G01Y1086889D02*
X1535581Y1086890D01*
G01X1535610Y1085119D02*
X1534626Y1085118D01*
G01X1535039Y1123366D02*
X1536220Y1124547D01*
G01X1531102Y1123366D02*
X1532283Y1124547D01*
G01X1535611Y1175308D02*
X1535610Y1175299D01*
G01X1535611Y1175313D02*
Y1175308D01*
G01X1535613Y1175315D02*
X1535611Y1175313D01*
G01Y1170308D02*
X1535610Y1170299D01*
G01X1535611Y1170313D02*
Y1170308D01*
G01X1535613Y1170315D02*
X1535611Y1170313D01*
G01Y1165308D02*
X1535610Y1165299D01*
G01X1535611Y1165313D02*
Y1165308D01*
G01X1535613Y1165315D02*
X1535611Y1165313D01*
G01Y1160308D02*
X1535610Y1160299D01*
G01X1535611Y1160313D02*
Y1160308D01*
G01X1535613Y1160315D02*
X1535611Y1160313D01*
G01Y1155308D02*
X1535610Y1155299D01*
G01X1535611Y1155313D02*
Y1155308D01*
G01X1535613Y1155315D02*
X1535611Y1155313D01*
G01Y1150308D02*
X1535610Y1150299D01*
G01X1535611Y1150313D02*
Y1150308D01*
G01X1535613Y1150315D02*
X1535611Y1150313D01*
G01Y1145308D02*
X1535610Y1145299D01*
G01X1535611Y1145313D02*
Y1145308D01*
G01X1535613Y1145315D02*
X1535611Y1145313D01*
G01Y1140308D02*
X1535610Y1140299D01*
G01X1535611Y1140313D02*
Y1140308D01*
G01X1535613Y1140315D02*
X1535611Y1140313D01*
G01Y1135308D02*
X1535610Y1135299D01*
G01X1535611Y1135313D02*
Y1135308D01*
G01X1535613Y1135315D02*
X1535611Y1135313D01*
G01X1535598Y1131685D02*
X1535609Y1131669D01*
G01X1535573Y1131693D02*
X1535598Y1131685D01*
G01Y1136685D02*
X1535609Y1136669D01*
G01X1535573Y1136693D02*
X1535598Y1136685D01*
G01Y1141685D02*
X1535609Y1141669D01*
G01X1535573Y1141693D02*
X1535598Y1141685D01*
G01Y1146685D02*
X1535609Y1146669D01*
G01X1535573Y1146693D02*
X1535598Y1146685D01*
G01Y1151685D02*
X1535609Y1151669D01*
G01X1535573Y1151693D02*
X1535598Y1151685D01*
G01Y1156685D02*
X1535609Y1156669D01*
G01X1535573Y1156693D02*
X1535598Y1156685D01*
G01Y1161685D02*
X1535609Y1161669D01*
G01X1535573Y1161693D02*
X1535598Y1161685D01*
G01X1535577Y1131791D02*
X1535581Y1131890D01*
G01X1535572Y1131719D02*
X1535577Y1131791D01*
G01X1535574Y1131693D02*
X1535572Y1131719D01*
G01X1535577Y1136791D02*
X1535581Y1136890D01*
G01X1535572Y1136719D02*
X1535577Y1136791D01*
G01X1535574Y1136693D02*
X1535572Y1136719D01*
G01X1535577Y1141791D02*
X1535581Y1141890D01*
G01X1535572Y1141719D02*
X1535577Y1141791D01*
G01X1535574Y1141693D02*
X1535572Y1141719D01*
G01X1535577Y1146791D02*
X1535581Y1146890D01*
G01X1535572Y1146719D02*
X1535577Y1146791D01*
G01X1535574Y1146693D02*
X1535572Y1146719D01*
G01X1535577Y1151791D02*
X1535581Y1151890D01*
G01X1535572Y1151719D02*
X1535577Y1151791D01*
G01X1535574Y1151693D02*
X1535572Y1151719D01*
G01X1535577Y1156791D02*
X1535581Y1156890D01*
G01X1535572Y1156719D02*
X1535577Y1156791D01*
G01X1535574Y1156693D02*
X1535572Y1156719D01*
G01X1535577Y1161791D02*
X1535581Y1161890D01*
G01X1535572Y1161719D02*
X1535577Y1161791D01*
G01X1535574Y1161693D02*
X1535572Y1161719D01*
G01X1535577Y1166791D02*
X1535581Y1166890D01*
G01X1535572Y1166719D02*
X1535577Y1166791D01*
G01X1535574Y1166693D02*
X1535572Y1166719D01*
G01X1535577Y1171791D02*
X1535581Y1171890D01*
G01X1535572Y1171719D02*
X1535577Y1171791D01*
G01X1535574Y1171693D02*
X1535572Y1171719D01*
G01X1535577Y1176791D02*
X1535581Y1176890D01*
G01X1535572Y1176719D02*
X1535577Y1176791D01*
G01X1535574Y1176693D02*
X1535572Y1176719D01*
G01X1534627Y1175313D02*
X1534628Y1175315D01*
G01X1534626Y1175308D02*
X1534627Y1175313D01*
G01X1534626Y1175299D02*
Y1175308D01*
G01X1534627Y1170313D02*
X1534628Y1170315D01*
G01X1534626Y1170308D02*
X1534627Y1170313D01*
G01X1534626Y1170299D02*
Y1170308D01*
G01X1534627Y1165313D02*
X1534628Y1165315D01*
G01X1534626Y1165308D02*
X1534627Y1165313D01*
G01X1534626Y1165299D02*
Y1165308D01*
G01X1534627Y1160313D02*
X1534628Y1160315D01*
G01X1534626Y1160308D02*
X1534627Y1160313D01*
G01X1534626Y1160299D02*
Y1160308D01*
G01X1534627Y1155313D02*
X1534628Y1155315D01*
G01X1534626Y1155308D02*
X1534627Y1155313D01*
G01X1534626Y1155299D02*
Y1155308D01*
G01X1534627Y1150313D02*
X1534628Y1150315D01*
G01X1534626Y1150308D02*
X1534627Y1150313D01*
G01X1534626Y1150299D02*
Y1150308D01*
G01X1534627Y1145313D02*
X1534628Y1145315D01*
G01X1534626Y1145308D02*
X1534627Y1145313D01*
G01X1534626Y1145299D02*
Y1145308D01*
G01X1534627Y1140313D02*
X1534628Y1140315D01*
G01X1534626Y1140308D02*
X1534627Y1140313D01*
G01X1534626Y1140299D02*
Y1140308D01*
G01X1534627Y1135313D02*
X1534628Y1135315D01*
G01X1534626Y1135308D02*
X1534627Y1135313D01*
G01X1534626Y1135299D02*
Y1135308D01*
G01X1535598Y1166685D02*
X1535609Y1166669D01*
G01X1535573Y1166693D02*
X1535598Y1166685D01*
G01Y1171685D02*
X1535609Y1171669D01*
G01X1535573Y1171693D02*
X1535598Y1171685D01*
G01Y1176685D02*
X1535609Y1176669D01*
G01X1535573Y1176693D02*
X1535598Y1176685D01*
G01X1535593Y1131688D02*
X1535574Y1131693D01*
G01X1535607Y1131674D02*
X1535593Y1131688D01*
G01X1535613Y1131654D02*
X1535607Y1131674D01*
G01X1535611Y1131660D02*
X1535610Y1131667D01*
G01X1535611Y1131656D02*
Y1131660D01*
G01X1535613Y1131654D02*
X1535611Y1131656D01*
G01Y1136660D02*
X1535610Y1136667D01*
G01X1535611Y1136656D02*
Y1136660D01*
G01X1535613Y1136654D02*
X1535611Y1136656D01*
G01Y1141660D02*
X1535610Y1141667D01*
G01X1535611Y1141656D02*
Y1141660D01*
G01X1535613Y1141654D02*
X1535611Y1141656D01*
G01Y1146660D02*
X1535610Y1146667D01*
G01X1535611Y1146656D02*
Y1146660D01*
G01X1535613Y1146654D02*
X1535611Y1146656D01*
G01Y1151660D02*
X1535610Y1151667D01*
G01X1535611Y1151656D02*
Y1151660D01*
G01X1535613Y1151654D02*
X1535611Y1151656D01*
G01Y1156660D02*
X1535610Y1156667D01*
G01X1535611Y1156656D02*
Y1156660D01*
G01X1535613Y1156654D02*
X1535611Y1156656D01*
G01Y1161660D02*
X1535610Y1161667D01*
G01X1535611Y1161656D02*
Y1161660D01*
G01X1535613Y1161654D02*
X1535611Y1161656D01*
G01Y1166660D02*
X1535610Y1166667D01*
G01X1535611Y1166656D02*
Y1166660D01*
G01X1535613Y1166654D02*
X1535611Y1166656D01*
G01Y1171660D02*
X1535610Y1171667D01*
G01X1535611Y1171656D02*
Y1171660D01*
G01X1535613Y1171654D02*
X1535611Y1171656D01*
G01Y1176660D02*
X1535610Y1176667D01*
G01X1535611Y1176656D02*
Y1176660D01*
G01X1535613Y1176654D02*
X1535611Y1176656D01*
G01X1534626Y1131700D02*
Y1131709D01*
G01X1534627Y1131695D02*
X1534626Y1131700D01*
G01X1534628Y1131693D02*
X1534627Y1131695D01*
G01X1534626Y1136700D02*
Y1136709D01*
G01X1534627Y1136695D02*
X1534626Y1136700D01*
G01X1534628Y1136693D02*
X1534627Y1136695D01*
G01X1534626Y1141700D02*
Y1141709D01*
G01X1534627Y1141695D02*
X1534626Y1141700D01*
G01X1534628Y1141693D02*
X1534627Y1141695D01*
G01X1534626Y1146700D02*
Y1146709D01*
G01X1534627Y1146695D02*
X1534626Y1146700D01*
G01X1534628Y1146693D02*
X1534627Y1146695D01*
G01X1534626Y1151700D02*
Y1151709D01*
G01X1534627Y1151695D02*
X1534626Y1151700D01*
G01X1534628Y1151693D02*
X1534627Y1151695D01*
G01X1534626Y1156700D02*
Y1156709D01*
G01X1534627Y1156695D02*
X1534626Y1156700D01*
G01X1534628Y1156693D02*
X1534627Y1156695D01*
G01X1534626Y1161700D02*
Y1161709D01*
G01X1534627Y1161695D02*
X1534626Y1161700D01*
G01X1534628Y1161693D02*
X1534627Y1161695D01*
G01X1534626Y1166700D02*
Y1166709D01*
G01X1534627Y1166695D02*
X1534626Y1166700D01*
G01X1534628Y1166693D02*
X1534627Y1166695D01*
G01X1534626Y1171700D02*
Y1171709D01*
G01X1534627Y1171695D02*
X1534626Y1171700D01*
G01X1534628Y1171693D02*
X1534627Y1171695D01*
G01X1534626Y1176700D02*
Y1176709D01*
G01X1534627Y1176695D02*
X1534626Y1176700D01*
G01X1534628Y1176693D02*
X1534627Y1176695D01*
G01X1535602Y1131837D02*
X1535610Y1131811D01*
G01X1535593Y1131863D02*
X1535602Y1131837D01*
G01X1535581Y1131890D02*
X1535593Y1131863D01*
G01X1535602Y1136837D02*
X1535610Y1136811D01*
G01X1535593Y1136863D02*
X1535602Y1136837D01*
G01X1535581Y1136890D02*
X1535593Y1136863D01*
G01X1535602Y1141837D02*
X1535610Y1141811D01*
G01X1535593Y1141863D02*
X1535602Y1141837D01*
G01X1535581Y1141890D02*
X1535593Y1141863D01*
G01X1535602Y1146837D02*
X1535610Y1146811D01*
G01X1535593Y1146863D02*
X1535602Y1146837D01*
G01X1535581Y1146890D02*
X1535593Y1146863D01*
G01X1535602Y1151837D02*
X1535610Y1151811D01*
G01X1535593Y1151863D02*
X1535602Y1151837D01*
G01X1535581Y1151890D02*
X1535593Y1151863D01*
G01X1535602Y1156837D02*
X1535610Y1156811D01*
G01X1535593Y1156863D02*
X1535602Y1156837D01*
G01X1535581Y1156890D02*
X1535593Y1156863D01*
G01X1535602Y1161837D02*
X1535610Y1161811D01*
G01X1535593Y1161863D02*
X1535602Y1161837D01*
G01X1535581Y1161890D02*
X1535593Y1161863D01*
G01X1535602Y1166837D02*
X1535610Y1166811D01*
G01X1535593Y1166863D02*
X1535602Y1166837D01*
G01X1535581Y1166890D02*
X1535593Y1166863D01*
G01X1535602Y1171837D02*
X1535610Y1171811D01*
G01X1535593Y1171863D02*
X1535602Y1171837D01*
G01X1535581Y1171890D02*
X1535593Y1171863D01*
G01X1535602Y1176837D02*
X1535610Y1176811D01*
G01X1535593Y1176863D02*
X1535602Y1176837D01*
G01X1535581Y1176890D02*
X1535593Y1176863D01*
G01Y1136688D02*
X1535574Y1136693D01*
G01X1535607Y1136674D02*
X1535593Y1136688D01*
G01X1535613Y1136654D02*
X1535607Y1136674D01*
G01X1535593Y1141688D02*
X1535574Y1141693D01*
G01X1535607Y1141674D02*
X1535593Y1141688D01*
G01X1535613Y1141654D02*
X1535607Y1141674D01*
G01X1535593Y1146688D02*
X1535574Y1146693D01*
G01X1535607Y1146674D02*
X1535593Y1146688D01*
G01X1535613Y1146654D02*
X1535607Y1146674D01*
G01X1535593Y1151688D02*
X1535574Y1151693D01*
G01X1535607Y1151674D02*
X1535593Y1151688D01*
G01X1535613Y1151654D02*
X1535607Y1151674D01*
G01X1535593Y1156688D02*
X1535574Y1156693D01*
G01X1535607Y1156674D02*
X1535593Y1156688D01*
G01X1535613Y1156654D02*
X1535607Y1156674D01*
G01X1535593Y1161688D02*
X1535574Y1161693D01*
G01X1535607Y1161674D02*
X1535593Y1161688D01*
G01X1535613Y1161654D02*
X1535607Y1161674D01*
G01X1535593Y1166688D02*
X1535574Y1166693D01*
G01X1535607Y1166674D02*
X1535593Y1166688D01*
G01X1535613Y1166654D02*
X1535607Y1166674D01*
G01X1535593Y1171688D02*
X1535574Y1171693D01*
G01X1535607Y1171674D02*
X1535593Y1171688D01*
G01X1535613Y1171654D02*
X1535607Y1171674D01*
G01X1535593Y1176688D02*
X1535574Y1176693D01*
G01X1535607Y1176674D02*
X1535593Y1176688D01*
G01X1535613Y1176654D02*
X1535607Y1176674D01*
G01X1535610Y1131667D02*
X1535611Y1131676D01*
G01X1535610Y1136667D02*
X1535611Y1136676D01*
G01X1535610Y1141667D02*
X1535611Y1141676D01*
G01X1535610Y1146667D02*
X1535611Y1146676D01*
G01X1535610Y1151667D02*
X1535611Y1151676D01*
G01X1535610Y1156667D02*
X1535611Y1156676D01*
G01X1535610Y1161667D02*
X1535611Y1161676D01*
G01X1535610Y1166667D02*
X1535611Y1166676D01*
G01X1535610Y1171667D02*
X1535611Y1171676D01*
G01X1535610Y1176667D02*
X1535611Y1176676D01*
G01X1539961Y1175315D02*
Y1176693D01*
G01Y1170315D02*
Y1171693D01*
G01Y1165315D02*
Y1166693D01*
G01Y1160315D02*
Y1161693D01*
G01Y1155315D02*
Y1156693D01*
G01Y1150315D02*
Y1151693D01*
G01Y1145315D02*
Y1146693D01*
G01Y1140315D02*
Y1141693D01*
G01Y1135315D02*
Y1136693D01*
G01X1536791D02*
Y1135315D01*
G01Y1141693D02*
Y1140315D01*
G01Y1146693D02*
Y1145315D01*
G01Y1151693D02*
Y1150315D01*
G01Y1156693D02*
Y1155315D01*
G01Y1161693D02*
Y1160315D01*
G01Y1166693D02*
Y1165315D01*
G01Y1171693D02*
Y1170315D01*
G01Y1176693D02*
Y1175315D01*
G01X1535610Y1174823D02*
Y1177185D01*
G01Y1169823D02*
Y1172185D01*
G01Y1164823D02*
Y1167185D01*
G01Y1159823D02*
Y1162185D01*
G01Y1154823D02*
Y1157185D01*
G01Y1149823D02*
Y1152185D01*
G01Y1144823D02*
Y1147185D01*
G01Y1139823D02*
Y1142185D01*
G01Y1134823D02*
Y1137185D01*
G01Y1131667D02*
Y1131811D01*
G01Y1136667D02*
Y1136811D01*
G01Y1141667D02*
Y1141811D01*
G01Y1146667D02*
Y1146811D01*
G01Y1151667D02*
Y1151811D01*
G01Y1156667D02*
Y1156811D01*
G01Y1161667D02*
Y1161811D01*
G01Y1166667D02*
Y1166811D01*
G01Y1171667D02*
Y1171811D01*
G01Y1176667D02*
Y1176811D01*
G01X1534626Y1137185D02*
Y1134823D01*
G01Y1142185D02*
Y1139823D01*
G01Y1147185D02*
Y1144823D01*
G01Y1152185D02*
Y1149823D01*
G01Y1157185D02*
Y1154823D01*
G01Y1162185D02*
Y1159823D01*
G01Y1167185D02*
Y1164823D01*
G01Y1172185D02*
Y1169823D01*
G01Y1177185D02*
Y1174823D01*
G01X1535610Y1177185D02*
X1534626D01*
G01X1534628Y1176693D02*
X1539961D01*
G01Y1176654D02*
X1535613D01*
G01X1539961Y1175315D02*
X1534628D01*
G01X1534626Y1174823D02*
X1535610D01*
G01Y1172185D02*
X1534626D01*
G01X1534628Y1171693D02*
X1539961D01*
G01Y1171654D02*
X1535613D01*
G01X1539961Y1170315D02*
X1534628D01*
G01X1534626Y1169823D02*
X1535610D01*
G01Y1167185D02*
X1534626D01*
G01X1534628Y1166693D02*
X1539961D01*
G01Y1166654D02*
X1535613D01*
G01X1539961Y1165315D02*
X1534628D01*
G01X1534626Y1164823D02*
X1535610D01*
G01Y1162185D02*
X1534626D01*
G01X1534628Y1161693D02*
X1539961D01*
G01Y1161654D02*
X1535613D01*
G01X1539961Y1160315D02*
X1534628D01*
G01X1534626Y1159823D02*
X1535610D01*
G01Y1157185D02*
X1534626D01*
G01X1534628Y1156693D02*
X1539961D01*
G01Y1156654D02*
X1535613D01*
G01X1539961Y1155315D02*
X1534628D01*
G01X1534626Y1154823D02*
X1535610D01*
G01X1534626Y1176889D02*
X1535581Y1176890D01*
G01X1535610Y1175119D02*
X1534626Y1175118D01*
G01Y1171889D02*
X1535581Y1171890D01*
G01X1535610Y1170119D02*
X1534626Y1170118D01*
G01Y1166889D02*
X1535581Y1166890D01*
G01X1535610Y1165119D02*
X1534626Y1165118D01*
G01Y1161889D02*
X1535581Y1161890D01*
G01X1535610Y1160119D02*
X1534626Y1160118D01*
G01Y1156889D02*
X1535581Y1156890D01*
G01X1535610Y1155119D02*
X1534626Y1155118D01*
G01X1535610Y1152185D02*
X1534626D01*
G01X1534628Y1151693D02*
X1539961D01*
G01Y1151654D02*
X1535613D01*
G01X1539961Y1150315D02*
X1534628D01*
G01X1534626Y1149823D02*
X1535610D01*
G01Y1147185D02*
X1534626D01*
G01X1534628Y1146693D02*
X1539961D01*
G01Y1146654D02*
X1535613D01*
G01X1539961Y1145315D02*
X1534628D01*
G01X1534626Y1144823D02*
X1535610D01*
G01Y1142185D02*
X1534626D01*
G01X1534628Y1141693D02*
X1539961D01*
G01Y1141654D02*
X1535613D01*
G01X1539961Y1140315D02*
X1534628D01*
G01X1534626Y1139823D02*
X1535610D01*
G01Y1137185D02*
X1534626D01*
G01X1534628Y1136693D02*
X1539961D01*
G01Y1136654D02*
X1535613D01*
G01X1539961Y1135315D02*
X1534628D01*
G01X1534626Y1134823D02*
X1535610D01*
G01Y1132185D02*
X1534626D01*
G01X1534628Y1131693D02*
X1539961D01*
G01Y1131654D02*
X1535613D01*
G01X1534626Y1151889D02*
X1535581Y1151890D01*
G01X1535610Y1150119D02*
X1534626Y1150118D01*
G01Y1146889D02*
X1535581Y1146890D01*
G01X1535610Y1145119D02*
X1534626Y1145118D01*
G01Y1141889D02*
X1535581Y1141890D01*
G01X1535610Y1140119D02*
X1534626Y1140118D01*
G01Y1136889D02*
X1535581Y1136890D01*
G01X1535610Y1135119D02*
X1534626Y1135118D01*
G01Y1131889D02*
X1535581Y1131890D01*
G01X1535611Y1195308D02*
X1535610Y1195299D01*
G01X1535611Y1195313D02*
Y1195308D01*
G01X1535613Y1195315D02*
X1535611Y1195313D01*
G01Y1190308D02*
X1535610Y1190299D01*
G01X1535611Y1190313D02*
Y1190308D01*
G01X1535613Y1190315D02*
X1535611Y1190313D01*
G01Y1185308D02*
X1535610Y1185299D01*
G01X1535611Y1185313D02*
Y1185308D01*
G01X1535613Y1185315D02*
X1535611Y1185313D01*
G01Y1180308D02*
X1535610Y1180299D01*
G01X1535611Y1180313D02*
Y1180308D01*
G01X1535613Y1180315D02*
X1535611Y1180313D01*
G01X1535577Y1181791D02*
X1535581Y1181890D01*
G01X1535572Y1181719D02*
X1535577Y1181791D01*
G01X1535574Y1181693D02*
X1535572Y1181719D01*
G01X1535577Y1186791D02*
X1535581Y1186890D01*
G01X1535572Y1186719D02*
X1535577Y1186791D01*
G01X1535574Y1186693D02*
X1535572Y1186719D01*
G01X1535577Y1191791D02*
X1535581Y1191890D01*
G01X1535572Y1191719D02*
X1535577Y1191791D01*
G01X1535574Y1191693D02*
X1535572Y1191719D01*
G01X1535577Y1196791D02*
X1535581Y1196890D01*
G01X1535572Y1196719D02*
X1535577Y1196791D01*
G01X1535574Y1196693D02*
X1535572Y1196719D01*
G01X1534627Y1195313D02*
X1534628Y1195315D01*
G01X1534626Y1195308D02*
X1534627Y1195313D01*
G01X1534626Y1195299D02*
Y1195308D01*
G01X1534627Y1190313D02*
X1534628Y1190315D01*
G01X1534626Y1190308D02*
X1534627Y1190313D01*
G01X1534626Y1190299D02*
Y1190308D01*
G01X1534627Y1185313D02*
X1534628Y1185315D01*
G01X1534626Y1185308D02*
X1534627Y1185313D01*
G01X1534626Y1185299D02*
Y1185308D01*
G01X1534627Y1180313D02*
X1534628Y1180315D01*
G01X1534626Y1180308D02*
X1534627Y1180313D01*
G01X1534626Y1180299D02*
Y1180308D01*
G01X1535598Y1181685D02*
X1535609Y1181669D01*
G01X1535573Y1181693D02*
X1535598Y1181685D01*
G01Y1186685D02*
X1535609Y1186669D01*
G01X1535573Y1186693D02*
X1535598Y1186685D01*
G01Y1191685D02*
X1535609Y1191669D01*
G01X1535573Y1191693D02*
X1535598Y1191685D01*
G01Y1196685D02*
X1535609Y1196669D01*
G01X1535573Y1196693D02*
X1535598Y1196685D01*
G01X1535611Y1181660D02*
X1535610Y1181667D01*
G01X1535611Y1181656D02*
Y1181660D01*
G01X1535613Y1181654D02*
X1535611Y1181656D01*
G01Y1186660D02*
X1535610Y1186667D01*
G01X1535611Y1186656D02*
Y1186660D01*
G01X1535613Y1186654D02*
X1535611Y1186656D01*
G01Y1191660D02*
X1535610Y1191667D01*
G01X1535611Y1191656D02*
Y1191660D01*
G01X1535613Y1191654D02*
X1535611Y1191656D01*
G01Y1196660D02*
X1535610Y1196667D01*
G01X1535611Y1196656D02*
Y1196660D01*
G01X1535613Y1196654D02*
X1535611Y1196656D01*
G01X1534626Y1181700D02*
Y1181709D01*
G01X1534627Y1181695D02*
X1534626Y1181700D01*
G01X1534628Y1181693D02*
X1534627Y1181695D01*
G01X1534626Y1186700D02*
Y1186709D01*
G01X1534627Y1186695D02*
X1534626Y1186700D01*
G01X1534628Y1186693D02*
X1534627Y1186695D01*
G01X1534626Y1191700D02*
Y1191709D01*
G01X1534627Y1191695D02*
X1534626Y1191700D01*
G01X1534628Y1191693D02*
X1534627Y1191695D01*
G01X1534626Y1196700D02*
Y1196709D01*
G01X1534627Y1196695D02*
X1534626Y1196700D01*
G01X1534628Y1196693D02*
X1534627Y1196695D01*
G01X1535602Y1181837D02*
X1535610Y1181811D01*
G01X1535593Y1181863D02*
X1535602Y1181837D01*
G01X1535581Y1181890D02*
X1535593Y1181863D01*
G01X1535602Y1186837D02*
X1535610Y1186811D01*
G01X1535593Y1186863D02*
X1535602Y1186837D01*
G01X1535581Y1186890D02*
X1535593Y1186863D01*
G01X1535602Y1191837D02*
X1535610Y1191811D01*
G01X1535593Y1191863D02*
X1535602Y1191837D01*
G01X1535581Y1191890D02*
X1535593Y1191863D01*
G01X1535602Y1196837D02*
X1535610Y1196811D01*
G01X1535593Y1196863D02*
X1535602Y1196837D01*
G01X1535581Y1196890D02*
X1535593Y1196863D01*
G01Y1181688D02*
X1535574Y1181693D01*
G01X1535607Y1181674D02*
X1535593Y1181688D01*
G01X1535613Y1181654D02*
X1535607Y1181674D01*
G01X1535593Y1186688D02*
X1535574Y1186693D01*
G01X1535607Y1186674D02*
X1535593Y1186688D01*
G01X1535613Y1186654D02*
X1535607Y1186674D01*
G01X1535593Y1191688D02*
X1535574Y1191693D01*
G01X1535607Y1191674D02*
X1535593Y1191688D01*
G01X1535613Y1191654D02*
X1535607Y1191674D01*
G01X1535593Y1196688D02*
X1535574Y1196693D01*
G01X1535607Y1196674D02*
X1535593Y1196688D01*
G01X1535613Y1196654D02*
X1535607Y1196674D01*
G01X1534055Y1222185D02*
G03X1533465Y1222776I-591J0D01*
G01X1526772D02*
G03X1526181Y1222185I0J-591D01*
G01X1528937Y1221004D02*
G03Y1219035I0J-985D01*
G01X1531299D02*
G03Y1221004I0J985D01*
G01X1540945Y1221594D02*
G03X1538976Y1223563I-1968J1D01*
G01X1527559Y1213091D02*
G03X1526378Y1211909I0J-1181D01*
G01X1533858D02*
G03X1532677Y1213091I-1181J1D01*
G01X1532008Y1207815D02*
G03I-1890J0D01*
G01X1532480D02*
G03I-2362J0D01*
G01X1528937Y1208406D02*
X1526627Y1212635D01*
G01X1531299Y1206713D02*
X1532603Y1204744D01*
G01X1524409Y1201004D02*
X1525591Y1199823D01*
G01X1535610Y1181667D02*
X1535611Y1181676D01*
G01X1535610Y1186667D02*
X1535611Y1186676D01*
G01X1535610Y1191667D02*
X1535611Y1191676D01*
G01X1535610Y1196667D02*
X1535611Y1196676D01*
G01X1540945Y1205846D02*
Y1221594D01*
G01X1539961Y1195315D02*
Y1196693D01*
G01Y1190315D02*
Y1191693D01*
G01Y1185315D02*
Y1186693D01*
G01Y1180315D02*
Y1181693D01*
G01X1536791D02*
Y1180315D01*
G01Y1186693D02*
Y1185315D01*
G01Y1191693D02*
Y1190315D01*
G01Y1196693D02*
Y1195315D01*
G01X1535610Y1194823D02*
Y1197185D01*
G01Y1189823D02*
Y1192185D01*
G01Y1184823D02*
Y1187185D01*
G01Y1179823D02*
Y1182185D01*
G01Y1181667D02*
Y1181811D01*
G01Y1186667D02*
Y1186811D01*
G01Y1191667D02*
Y1191811D01*
G01Y1196667D02*
Y1196811D01*
G01X1534626Y1182185D02*
Y1179823D01*
G01Y1187185D02*
Y1184823D01*
G01Y1192185D02*
Y1189823D01*
G01Y1197185D02*
Y1194823D01*
G01X1534055Y1216083D02*
Y1222185D01*
G01X1533858Y1211909D02*
Y1203366D01*
G01X1531299Y1208406D02*
Y1206713D01*
G01X1528937D02*
Y1208406D01*
G01X1526378Y1203366D02*
Y1211909D01*
G01X1526181Y1216083D02*
Y1222185D01*
G01X1533465Y1222776D02*
X1526772D01*
G01X1531299Y1221004D02*
X1528937D01*
G01Y1219035D02*
X1531299D01*
G01X1534055Y1217657D02*
X1526181D01*
G01Y1216083D02*
X1534055D01*
G01X1527559Y1213091D02*
X1532677D01*
G01X1528937Y1208406D02*
X1531299D01*
G01X1528937Y1206713D02*
X1531299D01*
G01X1537008Y1203366D02*
X1533858D01*
G01X1524409Y1201004D02*
X1532283D01*
G01X1525591Y1199823D02*
X1531102D01*
G01X1535610Y1197185D02*
X1534626D01*
G01X1534628Y1196693D02*
X1539961D01*
G01Y1196654D02*
X1535613D01*
G01X1539961Y1195315D02*
X1534628D01*
G01X1534626Y1194823D02*
X1535610D01*
G01Y1192185D02*
X1534626D01*
G01X1534628Y1191693D02*
X1539961D01*
G01Y1191654D02*
X1535613D01*
G01X1539961Y1190315D02*
X1534628D01*
G01X1534626Y1189823D02*
X1535610D01*
G01Y1187185D02*
X1534626D01*
G01X1534628Y1186693D02*
X1539961D01*
G01Y1186654D02*
X1535613D01*
G01X1539961Y1185315D02*
X1534628D01*
G01X1534626Y1184823D02*
X1535610D01*
G01Y1182185D02*
X1534626D01*
G01X1534628Y1181693D02*
X1539961D01*
G01Y1181654D02*
X1535613D01*
G01X1539961Y1180315D02*
X1534628D01*
G01X1534626Y1179823D02*
X1535610D01*
G01X1534626Y1196889D02*
X1535581Y1196890D01*
G01X1535610Y1195119D02*
X1534626Y1195118D01*
G01Y1191889D02*
X1535581Y1191890D01*
G01X1535610Y1190119D02*
X1534626Y1190118D01*
G01Y1186889D02*
X1535581Y1186890D01*
G01X1535610Y1185119D02*
X1534626Y1185118D01*
G01Y1181889D02*
X1535581Y1181890D01*
G01X1535610Y1180119D02*
X1534626Y1180118D01*
G01X1533609Y1212635D02*
X1531299Y1208406D01*
G01X1527633Y1204744D02*
X1528937Y1206713D01*
G01X1540945Y1205846D02*
X1537598Y1202500D01*
G01X1531102Y1199823D02*
X1532283Y1201004D01*
G01X1532996Y1284397D02*
G03X1566807I16906J-13531D01*
G01X1532996D02*
G03X1566807I16906J-13531D01*
G01X1559882Y1297528D02*
G03X1566807Y1284397I37662J11471D01*
G01X1559882Y1297528D02*
G03X1539921I-9980J-3040D01*
G01X1532996Y1284397D02*
G03X1539921Y1297528I-30737J24602D01*
G01X1559882D02*
G03X1566807Y1284397I37662J11471D01*
G01X1532996D02*
G03X1539921Y1297528I-30737J24602D01*
G01X1559882D02*
G03X1539921I-9980J-3040D01*
G01X1563976Y1382677D02*
G03Y1374803I0J-3937D01*
G01X1524606D02*
G03Y1382677I0J3937D01*
G01X1864567D02*
X1563976D01*
G01X1864567D02*
X1563976D01*
G01D02*
G03Y1374803I0J-3937D01*
G01X1524606D02*
G03Y1382677I0J3937D01*
G01X1540805Y1656868D02*
Y1659668D01*
G01X1593701Y-7874D02*
G03Y0I0J3937D01*
G01Y-7874D02*
G03Y0I0J3937D01*
G01X1614370Y374803D02*
G03X1615551I590J0D01*
G01Y368504D02*
G03X1614370I-590J0D01*
G01X1612402D02*
G03X1611220I-591J0D01*
G01Y374803D02*
G03X1612402I591J0D01*
G01X1614370D02*
G03X1615551I590J0D01*
G01Y368504D02*
G03X1614370I-590J0D01*
G01X1612402D02*
G03X1611220I-591J0D01*
G01Y374803D02*
G03X1612402I591J0D01*
G01X1616339Y368504D02*
Y374803D01*
G01Y368504D02*
Y374803D01*
G01X1610433Y368504D02*
Y374803D01*
G01D02*
Y368504D01*
G01X1611220Y374803D02*
X1610433D01*
G01X1611220D02*
X1610433D01*
G01X1614370D02*
X1612402D01*
G01X1616339D02*
X1615551D01*
G01X1614370D02*
X1612402D01*
G01X1616339D02*
X1615551D01*
G01X1616339Y373819D02*
X1610433D01*
G01Y373622D02*
X1616339D01*
G01X1610433Y369685D02*
X1616339D01*
G01Y369488D02*
X1610433D01*
G01X1615551Y368504D02*
X1616339D01*
G01X1612402D02*
X1614370D01*
G01X1615551D02*
X1616339D01*
G01X1612402D02*
X1614370D01*
G01X1610433D02*
X1611220D01*
G01X1610433D02*
X1611220D01*
G01X1611024Y646457D02*
G03X1594488I-8268J0D01*
G01D02*
G03X1611024I8268J0D01*
G01D02*
G03I-8268J0D01*
G01X1614370Y827559D02*
G03X1615551I590J0D01*
G01Y821260D02*
G03X1614370I-590J0D01*
G01X1612402D02*
G03X1611220I-591J0D01*
G01Y827559D02*
G03X1612402I591J0D01*
G01X1614370D02*
G03X1615551I590J0D01*
G01Y821260D02*
G03X1614370I-590J0D01*
G01X1612402D02*
G03X1611220I-591J0D01*
G01Y827559D02*
G03X1612402I591J0D01*
G01X1616339Y821260D02*
Y827559D01*
G01Y821260D02*
Y827559D01*
G01X1610433Y821260D02*
Y827559D01*
G01D02*
Y821260D01*
G01X1611220Y827559D02*
X1610433D01*
G01X1611220D02*
X1610433D01*
G01X1614370D02*
X1612402D01*
G01X1616339D02*
X1615551D01*
G01X1614370D02*
X1612402D01*
G01X1616339D02*
X1615551D01*
G01X1616339Y826575D02*
X1610433D01*
G01Y826378D02*
X1616339D01*
G01X1610433Y822441D02*
X1616339D01*
G01Y822244D02*
X1610433D01*
G01X1615551Y821260D02*
X1616339D01*
G01X1612402D02*
X1614370D01*
G01X1615551D02*
X1616339D01*
G01X1612402D02*
X1614370D01*
G01X1610433D02*
X1611220D01*
G01X1610433D02*
X1611220D01*
G01X1585138Y1141732D02*
G03X1599115I6989J0D01*
G01D02*
G03X1585138I-6988J0D01*
G01X1599114D02*
G03I-6988J0D01*
G01X1615551Y1274016D02*
G03X1614370I-590J0D01*
G01X1612402D02*
G03X1611220I-591J0D01*
G01X1615551D02*
G03X1614370I-590J0D01*
G01X1612402D02*
G03X1611220I-591J0D01*
G01X1616339D02*
Y1280315D01*
G01Y1274016D02*
Y1280315D01*
G01X1610433Y1274016D02*
Y1280315D01*
G01D02*
Y1274016D01*
G01Y1275197D02*
X1616339D01*
G01Y1275000D02*
X1610433D01*
G01X1615551Y1274016D02*
X1616339D01*
G01X1612402D02*
X1614370D01*
G01X1615551D02*
X1616339D01*
G01X1612402D02*
X1614370D01*
G01X1610433D02*
X1611220D01*
G01X1610433D02*
X1611220D01*
G01X1614370Y1280315D02*
G03X1615551I590J0D01*
G01X1611220D02*
G03X1612402I591J0D01*
G01X1614370D02*
G03X1615551I590J0D01*
G01X1611220D02*
G03X1612402I591J0D01*
G01X1611220D02*
X1610433D01*
G01X1611220D02*
X1610433D01*
G01X1614370D02*
X1612402D01*
G01X1616339D02*
X1615551D01*
G01X1614370D02*
X1612402D01*
G01X1616339D02*
X1615551D01*
G01X1616339Y1279331D02*
X1610433D01*
G01Y1279134D02*
X1616339D01*
G01X1603795Y1656868D02*
Y1659668D01*
G01X1572300Y1656868D02*
Y1659668D01*
G01X1638583Y-335933D02*
Y-354870D01*
G01X1633071Y0D02*
G03Y-7874I0J-3937D01*
G01D02*
X1880512D01*
G01X1633071D02*
X1880512D01*
G01X1633071Y0D02*
G03Y-7874I0J-3937D01*
G01X1655433Y153681D02*
G03I-1102J0D01*
G01X1655906D02*
G03I-1575J0D01*
G01X1650394Y139311D02*
G03X1650984Y138720I591J0D01*
G01X1657677D02*
G03X1658268Y139311I0J591D01*
G01X1655512Y140492D02*
G03Y142461I0J984D01*
G01X1653150D02*
G03Y140492I0J-984D01*
G01X1656890Y148406D02*
G03X1658071Y149587I0J1181D01*
G01X1650591D02*
G03X1651772Y148406I1181J0D01*
G01X1643504Y139902D02*
G03X1645472Y137933I1969J0D01*
G01X1663189D02*
G03X1665157Y139902I0J1968D01*
G01X1649803Y161673D02*
X1648622Y160492D01*
G01X1646850Y158996D02*
X1643504Y155650D01*
G01X1656815Y156752D02*
X1655512Y154783D01*
G01X1650839Y148861D02*
X1653150Y153091D01*
G01X1665157Y139902D02*
Y155650D01*
G01X1661811Y296988D02*
Y158996D01*
G01X1661220Y299232D02*
Y156752D01*
G01X1658268Y145413D02*
Y139311D01*
G01X1658071Y158130D02*
Y149587D01*
G01X1656496Y196949D02*
Y160492D01*
G01X1655512Y154783D02*
Y153091D01*
G01X1655315Y198130D02*
Y161673D01*
G01X1653150Y153091D02*
Y154783D01*
G01X1650591Y149587D02*
Y158130D01*
G01X1650394Y145413D02*
Y139311D01*
G01X1649803Y161673D02*
Y294311D01*
G01X1648622Y160492D02*
Y295492D01*
G01X1646850Y195787D02*
Y156752D01*
G01X1643504Y155650D02*
Y139902D01*
G01X1655512Y153091D02*
X1657822Y148861D01*
G01X1653150Y154783D02*
X1651846Y156752D01*
G01X1665157Y155650D02*
X1661811Y158996D01*
G01X1655315Y161673D02*
X1656496Y160492D01*
G01X1655315Y161673D02*
X1649803D01*
G01X1656496Y160492D02*
X1648622D01*
G01X1661811Y158996D02*
X1646850D01*
G01X1658071Y158130D02*
X1661220D01*
G01X1650591D02*
X1646850D01*
G01Y156752D02*
X1661220D01*
G01X1655512Y154783D02*
X1653150D01*
G01X1655512Y153091D02*
X1653150D01*
G01X1656890Y148406D02*
X1651772D01*
G01X1665157Y148366D02*
X1643504D01*
G01X1658268Y145413D02*
X1650394D01*
G01Y143839D02*
X1658268D01*
G01X1655512Y142461D02*
X1653150D01*
G01Y140492D02*
X1655512D01*
G01X1657677Y138720D02*
X1650984D01*
G01X1663189Y137933D02*
X1645472D01*
G01X1645416Y199114D02*
X1645411Y199094D01*
G01X1645431Y199129D02*
X1645416Y199114D01*
G01X1645450Y199134D02*
X1645431Y199129D01*
G01X1645416Y202264D02*
X1645411Y202244D01*
G01X1645431Y202278D02*
X1645416Y202264D01*
G01X1645450Y202283D02*
X1645431Y202278D01*
G01X1645416Y205413D02*
X1645411Y205394D01*
G01X1645431Y205428D02*
X1645416Y205413D01*
G01X1645450Y205433D02*
X1645431Y205428D01*
G01X1645416Y208563D02*
X1645411Y208543D01*
G01X1645431Y208578D02*
X1645416Y208563D01*
G01X1645450Y208583D02*
X1645431Y208578D01*
G01X1645416Y211713D02*
X1645411Y211693D01*
G01X1645431Y211727D02*
X1645416Y211713D01*
G01X1645450Y211732D02*
X1645431Y211727D01*
G01X1646391Y197972D02*
X1646396Y197992D01*
G01X1646376Y197958D02*
X1646391Y197972D01*
G01X1646357Y197953D02*
X1646376Y197958D01*
G01X1646391Y201122D02*
X1646396Y201142D01*
G01X1646376Y201108D02*
X1646391Y201122D01*
G01X1646357Y201102D02*
X1646376Y201108D01*
G01X1646391Y204272D02*
X1646396Y204291D01*
G01X1646376Y204257D02*
X1646391Y204272D01*
G01X1646357Y204252D02*
X1646376Y204257D01*
G01X1646391Y207421D02*
X1646396Y207441D01*
G01X1646376Y207407D02*
X1646391Y207421D01*
G01X1646357Y207402D02*
X1646376Y207407D01*
G01X1646391Y210571D02*
X1646396Y210591D01*
G01X1646376Y210557D02*
X1646391Y210571D01*
G01X1646357Y210551D02*
X1646376Y210557D01*
G01X1646375Y197945D02*
X1646378Y197947D01*
G01X1646372Y197944D02*
X1646375Y197945D01*
G01X1646369Y197943D02*
X1646372Y197944D01*
G01X1646365Y197942D02*
X1646369Y197943D01*
G01X1646362Y197942D02*
X1646365D01*
G01X1646358D02*
X1646362D01*
G01X1645436Y199142D02*
X1645433Y199140D01*
G01X1645439Y199143D02*
X1645436Y199142D01*
G01X1645442Y199144D02*
X1645439Y199143D01*
G01X1645446Y199144D02*
X1645442D01*
G01X1645449Y199145D02*
X1645446Y199144D01*
G01X1645453Y199145D02*
X1645449D01*
G01X1646375Y201095D02*
X1646378Y201096D01*
G01X1646372Y201094D02*
X1646375Y201095D01*
G01X1646369Y201093D02*
X1646372Y201094D01*
G01X1646365Y201092D02*
X1646369Y201093D01*
G01X1646362Y201091D02*
X1646365Y201092D01*
G01X1646358Y201091D02*
X1646362D01*
G01X1645436Y202291D02*
X1645433Y202290D01*
G01X1645439Y202293D02*
X1645436Y202291D01*
G01X1645442Y202294D02*
X1645439Y202293D01*
G01X1645446Y202294D02*
X1645442D01*
G01X1645449Y202295D02*
X1645446Y202294D01*
G01X1645453Y202295D02*
X1645449D01*
G01X1646375Y204244D02*
X1646378Y204246D01*
G01X1646372Y204243D02*
X1646375Y204244D01*
G01X1646369Y204242D02*
X1646372Y204243D01*
G01X1646365Y204241D02*
X1646369Y204242D01*
G01X1646362Y204241D02*
X1646365D01*
G01X1646358D02*
X1646362D01*
G01X1645436Y205441D02*
X1645433Y205439D01*
G01X1645439Y205442D02*
X1645436Y205441D01*
G01X1645442Y205443D02*
X1645439Y205442D01*
G01X1645446Y205444D02*
X1645442Y205443D01*
G01X1645449Y205444D02*
X1645446D01*
G01X1645453D02*
X1645449D01*
G01X1646375Y207394D02*
X1646378Y207396D01*
G01X1646372Y207393D02*
X1646375Y207394D01*
G01X1646369Y207392D02*
X1646372Y207393D01*
G01X1646365Y207391D02*
X1646369Y207392D01*
G01X1646362Y207391D02*
X1646365D01*
G01X1646358D02*
X1646362D01*
G01X1645436Y208591D02*
X1645433Y208589D01*
G01X1645439Y208592D02*
X1645436Y208591D01*
G01X1645442Y208593D02*
X1645439Y208592D01*
G01X1645446Y208593D02*
X1645442D01*
G01X1645449Y208594D02*
X1645446Y208593D01*
G01X1645453Y208594D02*
X1645449D01*
G01X1646375Y210544D02*
X1646378Y210545D01*
G01X1646372Y210543D02*
X1646375Y210544D01*
G01X1646369Y210541D02*
X1646372Y210543D01*
G01X1646365Y210541D02*
X1646369D01*
G01X1646362Y210540D02*
X1646365Y210541D01*
G01X1646358Y210540D02*
X1646362D01*
G01X1645436Y211740D02*
X1645433Y211739D01*
G01X1645439Y211741D02*
X1645436Y211740D01*
G01X1645442Y211743D02*
X1645439Y211741D01*
G01X1645446Y211743D02*
X1645442D01*
G01X1645449Y211744D02*
X1645446Y211743D01*
G01X1645453Y211744D02*
X1645449D01*
G01X1646388Y199132D02*
X1646392Y199127D01*
G01X1646383Y199137D02*
X1646388Y199132D01*
G01X1646378Y199141D02*
X1646383Y199137D01*
G01X1646372Y199143D02*
X1646378Y199141D01*
G01X1646365Y199145D02*
X1646372Y199143D01*
G01X1646358Y199145D02*
X1646365D01*
G01X1646388Y202282D02*
X1646392Y202277D01*
G01X1646383Y202286D02*
X1646388Y202282D01*
G01X1646378Y202290D02*
X1646383Y202286D01*
G01X1646372Y202293D02*
X1646378Y202290D01*
G01X1646365Y202294D02*
X1646372Y202293D01*
G01X1646358Y202295D02*
X1646365Y202294D01*
G01X1646388Y205431D02*
X1646392Y205426D01*
G01X1646383Y205436D02*
X1646388Y205431D01*
G01X1646378Y205440D02*
X1646383Y205436D01*
G01X1646372Y205442D02*
X1646378Y205440D01*
G01X1646365Y205444D02*
X1646372Y205442D01*
G01X1646358Y205444D02*
X1646365D01*
G01X1646388Y208581D02*
X1646392Y208576D01*
G01X1646383Y208585D02*
X1646388Y208581D01*
G01X1646378Y208589D02*
X1646383Y208585D01*
G01X1646372Y208592D02*
X1646378Y208589D01*
G01X1646365Y208594D02*
X1646372Y208592D01*
G01X1646358Y208594D02*
X1646365D01*
G01X1646388Y211731D02*
X1646392Y211726D01*
G01X1646383Y211735D02*
X1646388Y211731D01*
G01X1646378Y211739D02*
X1646383Y211735D01*
G01X1646372Y211741D02*
X1646378Y211739D01*
G01X1646365Y211743D02*
X1646372Y211741D01*
G01X1646358Y211744D02*
X1646365Y211743D01*
G01X1645414Y197971D02*
X1645413Y197979D01*
G01X1645417Y197965D02*
X1645414Y197971D01*
G01X1645420Y197958D02*
X1645417Y197965D01*
G01X1645425Y197952D02*
X1645420Y197958D01*
G01X1645431Y197948D02*
X1645425Y197952D01*
G01X1645438Y197944D02*
X1645431Y197948D01*
G01X1645445Y197943D02*
X1645438Y197944D01*
G01X1645453Y197942D02*
X1645445Y197943D01*
G01X1645414Y201121D02*
X1645413Y201128D01*
G01X1645417Y201114D02*
X1645414Y201121D01*
G01X1645420Y201108D02*
X1645417Y201114D01*
G01X1645425Y201102D02*
X1645420Y201108D01*
G01X1645431Y201097D02*
X1645425Y201102D01*
G01X1645438Y201094D02*
X1645431Y201097D01*
G01X1645445Y201092D02*
X1645438Y201094D01*
G01X1645453Y201091D02*
X1645445Y201092D01*
G01X1645414Y204270D02*
X1645413Y204278D01*
G01X1645417Y204264D02*
X1645414Y204270D01*
G01X1645420Y204257D02*
X1645417Y204264D01*
G01X1645425Y204252D02*
X1645420Y204257D01*
G01X1645431Y204247D02*
X1645425Y204252D01*
G01X1645438Y204244D02*
X1645431Y204247D01*
G01X1645445Y204242D02*
X1645438Y204244D01*
G01X1645453Y204241D02*
X1645445Y204242D01*
G01X1645414Y207420D02*
X1645413Y207428D01*
G01X1645417Y207413D02*
X1645414Y207420D01*
G01X1645420Y207407D02*
X1645417Y207413D01*
G01X1645425Y207401D02*
X1645420Y207407D01*
G01X1645431Y207396D02*
X1645425Y207401D01*
G01X1645438Y207393D02*
X1645431Y207396D01*
G01X1645445Y207391D02*
X1645438Y207393D01*
G01X1645453Y207391D02*
X1645445D01*
G01X1645414Y210570D02*
X1645413Y210577D01*
G01X1645417Y210563D02*
X1645414Y210570D01*
G01X1645420Y210557D02*
X1645417Y210563D01*
G01X1645425Y210551D02*
X1645420Y210557D01*
G01X1645431Y210546D02*
X1645425Y210551D01*
G01X1645438Y210543D02*
X1645431Y210546D01*
G01X1645445Y210541D02*
X1645438Y210543D01*
G01X1645453Y210540D02*
X1645445Y210541D01*
G01X1646367Y199133D02*
X1646377Y199128D01*
G01X1646357Y199134D02*
X1646367Y199133D01*
G01Y202282D02*
X1646377Y202278D01*
G01X1646357Y202283D02*
X1646367Y202282D01*
G01Y205432D02*
X1646377Y205428D01*
G01X1646357Y205433D02*
X1646367Y205432D01*
G01Y208581D02*
X1646377Y208577D01*
G01X1646357Y208583D02*
X1646367Y208581D01*
G01Y211731D02*
X1646377Y211727D01*
G01X1646357Y211732D02*
X1646367Y211731D01*
G01X1645413Y201132D02*
Y201128D01*
G01X1645415Y201126D02*
X1645413Y201132D01*
G01X1645427Y201111D02*
X1645415Y201126D01*
G01X1645452Y201102D02*
X1645427Y201111D01*
G01X1659810Y166173D02*
X1659821Y166157D01*
G01X1659786Y166181D02*
X1659810Y166173D01*
G01Y171173D02*
X1659821Y171157D01*
G01X1659786Y171181D02*
X1659810Y171173D01*
G01X1645413Y204282D02*
Y204278D01*
G01X1645415Y204276D02*
X1645413Y204282D01*
G01X1645426Y204260D02*
X1645415Y204276D01*
G01X1645451Y204252D02*
X1645426Y204260D01*
G01X1645413Y210581D02*
Y210577D01*
G01X1645415Y210575D02*
X1645413Y210581D01*
G01X1645426Y210559D02*
X1645415Y210575D01*
G01X1645451Y210551D02*
X1645426Y210559D01*
G01X1645413Y197983D02*
Y197979D01*
G01X1645415Y197976D02*
X1645413Y197983D01*
G01X1645426Y197961D02*
X1645415Y197976D01*
G01X1645451Y197953D02*
X1645426Y197961D01*
G01X1659810Y176173D02*
X1659821Y176157D01*
G01X1659786Y176181D02*
X1659810Y176173D01*
G01Y181173D02*
X1659821Y181157D01*
G01X1659786Y181181D02*
X1659810Y181173D01*
G01Y186173D02*
X1659821Y186157D01*
G01X1659786Y186181D02*
X1659810Y186173D01*
G01Y191173D02*
X1659821Y191157D01*
G01X1659786Y191181D02*
X1659810Y191173D01*
G01Y196173D02*
X1659821Y196157D01*
G01X1659786Y196181D02*
X1659810Y196173D01*
G01X1645413Y207431D02*
Y207428D01*
G01X1645415Y207426D02*
X1645413Y207431D01*
G01X1645425Y207411D02*
X1645415Y207426D01*
G01X1645448Y207402D02*
X1645425Y207411D01*
G01X1646366Y205432D02*
X1646357Y205433D01*
G01X1646375Y205429D02*
X1646366Y205432D01*
G01X1646383Y205424D02*
X1646375Y205429D01*
G01X1646366Y199133D02*
X1646357Y199134D01*
G01X1646375Y199130D02*
X1646366Y199133D01*
G01X1646383Y199124D02*
X1646375Y199130D01*
G01X1646366Y202282D02*
X1646357Y202283D01*
G01X1646375Y202279D02*
X1646366Y202282D01*
G01X1646383Y202274D02*
X1646375Y202279D01*
G01X1646366Y208581D02*
X1646357Y208583D01*
G01X1646375Y208578D02*
X1646366Y208581D01*
G01X1646383Y208573D02*
X1646375Y208578D01*
G01X1646366Y211731D02*
X1646357Y211732D01*
G01X1646375Y211728D02*
X1646366Y211731D01*
G01X1646383Y211723D02*
X1646375Y211728D01*
G01X1645452Y197948D02*
X1645453Y197942D01*
G01X1645452Y197952D02*
Y197948D01*
G01X1645450Y197953D02*
X1645452Y197952D01*
G01Y201098D02*
X1645453Y201091D01*
G01X1645452Y201101D02*
Y201098D01*
G01X1645450Y201102D02*
X1645452Y201101D01*
G01Y204247D02*
X1645453Y204241D01*
G01X1645452Y204251D02*
Y204247D01*
G01X1645450Y204252D02*
X1645452Y204251D01*
G01Y207397D02*
X1645453Y207391D01*
G01X1645452Y207400D02*
Y207397D01*
G01X1645450Y207402D02*
X1645452Y207400D01*
G01Y210546D02*
X1645453Y210540D01*
G01X1645452Y210550D02*
Y210546D01*
G01X1645450Y210551D02*
X1645452Y210550D01*
G01X1659823Y166148D02*
Y166156D01*
G01X1659824Y166144D02*
X1659823Y166148D01*
G01X1659825Y166142D02*
X1659824Y166144D01*
G01X1659823Y171148D02*
Y171156D01*
G01X1659824Y171144D02*
X1659823Y171148D01*
G01X1659825Y171142D02*
X1659824Y171144D01*
G01X1659823Y176148D02*
Y176156D01*
G01X1659824Y176144D02*
X1659823Y176148D01*
G01X1659825Y176142D02*
X1659824Y176144D01*
G01X1659823Y181148D02*
Y181156D01*
G01X1659824Y181144D02*
X1659823Y181148D01*
G01X1659825Y181142D02*
X1659824Y181144D01*
G01X1659823Y186148D02*
Y186156D01*
G01X1659824Y186144D02*
X1659823Y186148D01*
G01X1659825Y186142D02*
X1659824Y186144D01*
G01X1659823Y191148D02*
Y191156D01*
G01X1659824Y191144D02*
X1659823Y191148D01*
G01X1659825Y191142D02*
X1659824Y191144D01*
G01X1659823Y196148D02*
Y196156D01*
G01X1659824Y196144D02*
X1659823Y196148D01*
G01X1659825Y196142D02*
X1659824Y196144D01*
G01X1645436Y201105D02*
X1645450Y201102D01*
G01X1645425Y201112D02*
X1645436Y201105D01*
G01X1645413Y201131D02*
X1645425Y201112D01*
G01X1645436Y210554D02*
X1645450Y210551D01*
G01X1645424Y210561D02*
X1645436Y210554D01*
G01X1645413Y210580D02*
X1645424Y210561D01*
G01X1645436Y204255D02*
X1645450Y204252D01*
G01X1645424Y204263D02*
X1645436Y204255D01*
G01X1645412Y204283D02*
X1645424Y204263D01*
G01X1646398Y197986D02*
Y197979D01*
G01X1646397Y197991D02*
X1646398Y197986D01*
G01X1646396Y197992D02*
X1646397Y197991D01*
G01X1646398Y201136D02*
Y201128D01*
G01X1646397Y201141D02*
X1646398Y201136D01*
G01X1646396Y201142D02*
X1646397Y201141D01*
G01X1646398Y204285D02*
Y204278D01*
G01X1646397Y204290D02*
X1646398Y204285D01*
G01X1646396Y204291D02*
X1646397Y204290D01*
G01X1646398Y207435D02*
Y207428D01*
G01X1646397Y207440D02*
X1646398Y207435D01*
G01X1646396Y207441D02*
X1646397Y207440D01*
G01X1646398Y210585D02*
Y210577D01*
G01X1646397Y210589D02*
X1646398Y210585D01*
G01X1646396Y210591D02*
X1646397Y210589D01*
G01X1645435Y197956D02*
X1645450Y197953D01*
G01X1645422Y197964D02*
X1645435Y197956D01*
G01X1645412Y197985D02*
X1645422Y197964D01*
G01X1646397Y199115D02*
X1646398Y199108D01*
G01X1646395Y199121D02*
X1646397Y199115D01*
G01X1646392Y199127D02*
X1646395Y199121D01*
G01X1646397Y202265D02*
X1646398Y202258D01*
G01X1646395Y202271D02*
X1646397Y202265D01*
G01X1646392Y202277D02*
X1646395Y202271D01*
G01X1646397Y205414D02*
X1646398Y205407D01*
G01X1646395Y205420D02*
X1646397Y205414D01*
G01X1646392Y205426D02*
X1646395Y205420D01*
G01X1646397Y208564D02*
X1646398Y208557D01*
G01X1646395Y208570D02*
X1646397Y208564D01*
G01X1646392Y208576D02*
X1646395Y208570D01*
G01X1646397Y211713D02*
X1646398Y211707D01*
G01X1646395Y211720D02*
X1646397Y211713D01*
G01X1646392Y211726D02*
X1646395Y211720D01*
G01X1646359Y197948D02*
Y197942D01*
G01X1646357Y197952D02*
X1646359Y197948D01*
G01X1646357Y197953D02*
Y197952D01*
G01X1646359Y201097D02*
Y201091D01*
G01X1646357Y201101D02*
X1646359Y201097D01*
G01X1646357Y201102D02*
Y201101D01*
G01X1646359Y204247D02*
Y204241D01*
G01X1646357Y204251D02*
X1646359Y204247D01*
G01X1646357Y204252D02*
Y204251D01*
G01X1646359Y207396D02*
Y207391D01*
G01X1646357Y207400D02*
X1646359Y207396D01*
G01X1646357Y207402D02*
Y207400D01*
G01X1646359Y210546D02*
Y210540D01*
G01X1646357Y210550D02*
X1646359Y210546D01*
G01X1646357Y210551D02*
Y210550D01*
G01X1658839Y166189D02*
Y166198D01*
G01Y166183D02*
Y166189D01*
G01X1658840Y166181D02*
X1658839Y166183D01*
G01Y171189D02*
Y171198D01*
G01Y171183D02*
Y171189D01*
G01X1658840Y171181D02*
X1658839Y171183D01*
G01Y176189D02*
Y176198D01*
G01Y176183D02*
Y176189D01*
G01X1658840Y176181D02*
X1658839Y176183D01*
G01Y181189D02*
Y181198D01*
G01Y181183D02*
Y181189D01*
G01X1658840Y181181D02*
X1658839Y181183D01*
G01Y186189D02*
Y186198D01*
G01Y186183D02*
Y186189D01*
G01X1658840Y186181D02*
X1658839Y186183D01*
G01Y191189D02*
Y191198D01*
G01Y191183D02*
Y191189D01*
G01X1658840Y191181D02*
X1658839Y191183D01*
G01Y196189D02*
Y196198D01*
G01Y196183D02*
Y196189D01*
G01X1658840Y196181D02*
X1658839Y196183D01*
G01X1659815Y166325D02*
X1659823Y166299D01*
G01X1659805Y166352D02*
X1659815Y166325D01*
G01X1659794Y166378D02*
X1659805Y166352D01*
G01X1659815Y171325D02*
X1659823Y171299D01*
G01X1659805Y171352D02*
X1659815Y171325D01*
G01X1659794Y171378D02*
X1659805Y171352D01*
G01X1659815Y176325D02*
X1659823Y176299D01*
G01X1659805Y176352D02*
X1659815Y176325D01*
G01X1659794Y176378D02*
X1659805Y176352D01*
G01X1659815Y181325D02*
X1659823Y181299D01*
G01X1659805Y181352D02*
X1659815Y181325D01*
G01X1659794Y181378D02*
X1659805Y181352D01*
G01X1659815Y186325D02*
X1659823Y186299D01*
G01X1659805Y186352D02*
X1659815Y186325D01*
G01X1659794Y186378D02*
X1659805Y186352D01*
G01X1659815Y191325D02*
X1659823Y191299D01*
G01X1659805Y191352D02*
X1659815Y191325D01*
G01X1659794Y191378D02*
X1659805Y191352D01*
G01X1659815Y196325D02*
X1659823Y196299D01*
G01X1659805Y196352D02*
X1659815Y196325D01*
G01X1659794Y196378D02*
X1659805Y196352D01*
G01X1645431Y207407D02*
X1645450Y207402D01*
G01X1645418Y207419D02*
X1645431Y207407D01*
G01X1645411Y207437D02*
X1645418Y207419D01*
G01X1659806Y166176D02*
X1659786Y166181D01*
G01X1659820Y166162D02*
X1659806Y166176D01*
G01X1659825Y166142D02*
X1659820Y166162D01*
G01X1659806Y171176D02*
X1659786Y171181D01*
G01X1659820Y171162D02*
X1659806Y171176D01*
G01X1659825Y171142D02*
X1659820Y171162D01*
G01X1659806Y176176D02*
X1659786Y176181D01*
G01X1659820Y176162D02*
X1659806Y176176D01*
G01X1659825Y176142D02*
X1659820Y176162D01*
G01X1659806Y181176D02*
X1659786Y181181D01*
G01X1659820Y181162D02*
X1659806Y181176D01*
G01X1659825Y181142D02*
X1659820Y181162D01*
G01X1659806Y186176D02*
X1659786Y186181D01*
G01X1659820Y186162D02*
X1659806Y186176D01*
G01X1659825Y186142D02*
X1659820Y186162D01*
G01X1659806Y191176D02*
X1659786Y191181D01*
G01X1659820Y191162D02*
X1659806Y191176D01*
G01X1659825Y191142D02*
X1659820Y191162D01*
G01X1659806Y196176D02*
X1659786Y196181D01*
G01X1659820Y196162D02*
X1659806Y196176D01*
G01X1659825Y196142D02*
X1659820Y196162D01*
G01X1646390Y205415D02*
X1646383Y205424D01*
G01X1646394Y205405D02*
X1646390Y205415D01*
G01X1646396Y205394D02*
X1646394Y205405D01*
G01X1646390Y199116D02*
X1646383Y199124D01*
G01X1646395Y199106D02*
X1646390Y199116D01*
G01X1646396Y199094D02*
X1646395Y199106D01*
G01X1646390Y202265D02*
X1646383Y202274D01*
G01X1646395Y202255D02*
X1646390Y202265D01*
G01X1646396Y202244D02*
X1646395Y202255D01*
G01X1646390Y208565D02*
X1646383Y208573D01*
G01X1646395Y208554D02*
X1646390Y208565D01*
G01X1646396Y208543D02*
X1646395Y208554D01*
G01X1646390Y211714D02*
X1646383Y211723D01*
G01X1646395Y211704D02*
X1646390Y211714D01*
G01X1646396Y211693D02*
X1646395Y211704D01*
G01X1659790Y166279D02*
X1659794Y166378D01*
G01X1659784Y166207D02*
X1659790Y166279D01*
G01X1659786Y166181D02*
X1659784Y166207D01*
G01X1659790Y171279D02*
X1659794Y171378D01*
G01X1659784Y171207D02*
X1659790Y171279D01*
G01X1659786Y171181D02*
X1659784Y171207D01*
G01X1659790Y176279D02*
X1659794Y176378D01*
G01X1659784Y176207D02*
X1659790Y176279D01*
G01X1659786Y176181D02*
X1659784Y176207D01*
G01X1659790Y181279D02*
X1659794Y181378D01*
G01X1659784Y181207D02*
X1659790Y181279D01*
G01X1659786Y181181D02*
X1659784Y181207D01*
G01X1659790Y186279D02*
X1659794Y186378D01*
G01X1659784Y186207D02*
X1659790Y186279D01*
G01X1659786Y186181D02*
X1659784Y186207D01*
G01X1659790Y191279D02*
X1659794Y191378D01*
G01X1659784Y191207D02*
X1659790Y191279D01*
G01X1659786Y191181D02*
X1659784Y191207D01*
G01X1659790Y196279D02*
X1659794Y196378D01*
G01X1659784Y196207D02*
X1659790Y196279D01*
G01X1659786Y196181D02*
X1659784Y196207D01*
G01X1645413Y210585D02*
Y210577D01*
G01X1645412Y210589D02*
X1645413Y210585D01*
G01Y210580D02*
X1645412Y210589D01*
G01X1645454Y211917D02*
X1645453Y211929D01*
G01X1645450Y211904D02*
X1645454Y211917D01*
G01X1645450Y211890D02*
Y211904D01*
G01X1645454Y208767D02*
X1645453Y208780D01*
G01X1645450Y208754D02*
X1645454Y208767D01*
G01X1645450Y208741D02*
Y208754D01*
G01X1645454Y205618D02*
X1645453Y205630D01*
G01X1645450Y205605D02*
X1645454Y205618D01*
G01X1645450Y205591D02*
Y205605D01*
G01X1645454Y202468D02*
X1645453Y202480D01*
G01X1645450Y202455D02*
X1645454Y202468D01*
G01X1645450Y202441D02*
Y202455D01*
G01X1645454Y199319D02*
X1645453Y199331D01*
G01X1645450Y199306D02*
X1645454Y199319D01*
G01X1645450Y199292D02*
Y199306D01*
G01X1658839Y194802D02*
X1658840Y194803D01*
G01X1658839Y194796D02*
Y194802D01*
G01Y194787D02*
Y194796D01*
G01Y189802D02*
X1658840Y189803D01*
G01X1658839Y189796D02*
Y189802D01*
G01Y189787D02*
Y189796D01*
G01Y184802D02*
X1658840Y184803D01*
G01X1658839Y184796D02*
Y184802D01*
G01Y184787D02*
Y184796D01*
G01Y179802D02*
X1658840Y179803D01*
G01X1658839Y179796D02*
Y179802D01*
G01Y179787D02*
Y179796D01*
G01Y174802D02*
X1658840Y174803D01*
G01X1658839Y174796D02*
Y174802D01*
G01Y174787D02*
Y174796D01*
G01Y169802D02*
X1658840Y169803D01*
G01X1658839Y169796D02*
Y169802D01*
G01Y169787D02*
Y169796D01*
G01Y164802D02*
X1658840Y164803D01*
G01X1658839Y164796D02*
Y164802D01*
G01Y164787D02*
Y164796D01*
G01X1645450Y210380D02*
X1645449Y210393D01*
G01X1645454Y210367D02*
X1645450Y210380D01*
G01X1645453Y210354D02*
X1645454Y210367D01*
G01X1645450Y207230D02*
X1645449Y207244D01*
G01X1645454Y207217D02*
X1645450Y207230D01*
G01X1645453Y207205D02*
X1645454Y207217D01*
G01X1645450Y204081D02*
X1645449Y204094D01*
G01X1645454Y204068D02*
X1645450Y204081D01*
G01X1645453Y204055D02*
X1645454Y204068D01*
G01X1645450Y200931D02*
X1645449Y200944D01*
G01X1645454Y200918D02*
X1645450Y200931D01*
G01X1645453Y200906D02*
X1645454Y200918D01*
G01X1645450Y197781D02*
X1645449Y197795D01*
G01X1645454Y197769D02*
X1645450Y197781D01*
G01X1645453Y197756D02*
X1645454Y197769D01*
G01X1646361Y211904D02*
X1646362Y211890D01*
G01X1646357Y211917D02*
X1646361Y211904D01*
G01X1646358Y211929D02*
X1646357Y211917D01*
G01X1646361Y208754D02*
X1646362Y208741D01*
G01X1646357Y208767D02*
X1646361Y208754D01*
G01X1646358Y208780D02*
X1646357Y208767D01*
G01X1646361Y205604D02*
X1646362Y205591D01*
G01X1646357Y205617D02*
X1646361Y205604D01*
G01X1646358Y205630D02*
X1646357Y205617D01*
G01X1646361Y202455D02*
X1646362Y202441D01*
G01X1646357Y202468D02*
X1646361Y202455D01*
G01X1646358Y202480D02*
X1646357Y202468D01*
G01X1646361Y199305D02*
X1646362Y199292D01*
G01X1646357Y199318D02*
X1646361Y199305D01*
G01X1646358Y199331D02*
X1646357Y199318D01*
G01X1645413Y204285D02*
Y204278D01*
G01X1645412Y204290D02*
X1645413Y204285D01*
G01X1645412Y204283D02*
Y204290D01*
G01X1646357Y210367D02*
X1646358Y210354D01*
G01X1646360Y210380D02*
X1646357Y210367D01*
G01X1646361Y210393D02*
X1646360Y210380D01*
G01X1646357Y207217D02*
X1646358Y207205D01*
G01X1646360Y207230D02*
X1646357Y207217D01*
G01X1646361Y207244D02*
X1646360Y207230D01*
G01X1646357Y204068D02*
X1646358Y204055D01*
G01X1646360Y204081D02*
X1646357Y204068D01*
G01X1646361Y204094D02*
X1646360Y204081D01*
G01X1646357Y200918D02*
X1646358Y200906D01*
G01X1646360Y200931D02*
X1646357Y200918D01*
G01X1646361Y200944D02*
X1646360Y200931D01*
G01X1646357Y197769D02*
X1646358Y197756D01*
G01X1646360Y197781D02*
X1646357Y197769D01*
G01X1646361Y197795D02*
X1646360Y197781D01*
G01X1645413Y197987D02*
Y197979D01*
G01X1645412Y197991D02*
X1645413Y197987D01*
G01X1645412Y197985D02*
Y197991D01*
G01X1645426Y211724D02*
X1645450Y211732D01*
G01X1645415Y211709D02*
X1645426Y211724D01*
G01X1645413Y211703D02*
X1645415Y211709D01*
G01X1645426Y208574D02*
X1645450Y208583D01*
G01X1645415Y208560D02*
X1645426Y208574D01*
G01X1645413Y208553D02*
X1645415Y208560D01*
G01X1645426Y205425D02*
X1645450Y205433D01*
G01X1645415Y205410D02*
X1645426Y205425D01*
G01X1645413Y205404D02*
X1645415Y205410D01*
G01X1645426Y202275D02*
X1645450Y202283D01*
G01X1645415Y202261D02*
X1645426Y202275D01*
G01X1645413Y202254D02*
X1645415Y202261D01*
G01X1645426Y199126D02*
X1645450Y199134D01*
G01X1645415Y199111D02*
X1645426Y199126D01*
G01X1645413Y199104D02*
X1645415Y199111D01*
G01X1646369Y210553D02*
X1646357Y210551D01*
G01X1646379Y210558D02*
X1646369Y210553D01*
G01Y207404D02*
X1646357Y207402D01*
G01X1646379Y207409D02*
X1646369Y207404D01*
G01Y204254D02*
X1646357Y204252D01*
G01X1646379Y204259D02*
X1646369Y204254D01*
G01X1646398Y211699D02*
Y211706D01*
G01X1646397Y211695D02*
X1646398Y211699D01*
G01X1646396Y211693D02*
X1646397Y211695D01*
G01X1646398Y208550D02*
Y208557D01*
G01X1646397Y208545D02*
X1646398Y208550D01*
G01X1646396Y208543D02*
X1646397Y208545D01*
G01X1646398Y205400D02*
Y205407D01*
G01X1646397Y205396D02*
X1646398Y205400D01*
G01X1646396Y205394D02*
X1646397Y205396D01*
G01X1646398Y202250D02*
Y202257D01*
G01X1646397Y202246D02*
X1646398Y202250D01*
G01X1646396Y202244D02*
X1646397Y202246D01*
G01X1646398Y199101D02*
Y199108D01*
G01X1646397Y199096D02*
X1646398Y199101D01*
G01X1646396Y199094D02*
X1646397Y199096D01*
G01X1645413Y207435D02*
Y207428D01*
G01X1645412Y207440D02*
X1645413Y207435D01*
G01X1645411Y207437D02*
X1645412Y207440D01*
G01X1645413Y201136D02*
Y201128D01*
G01X1645412Y201141D02*
X1645413Y201136D01*
G01X1645411Y201138D02*
X1645412Y201141D01*
G01X1646358Y211737D02*
Y211744D01*
G01X1646357Y211734D02*
X1646358Y211737D01*
G01X1646357Y211732D02*
Y211734D01*
G01X1646358Y208588D02*
Y208594D01*
G01X1646357Y208584D02*
X1646358Y208588D01*
G01X1646357Y208583D02*
Y208584D01*
G01X1646358Y205438D02*
Y205444D01*
G01X1646357Y205435D02*
X1646358Y205438D01*
G01X1646357Y205433D02*
Y205435D01*
G01X1646358Y202289D02*
Y202295D01*
G01X1646357Y202285D02*
X1646358Y202289D01*
G01X1646357Y202283D02*
Y202285D01*
G01X1646358Y199139D02*
Y199145D01*
G01X1646357Y199135D02*
X1646358Y199139D01*
G01X1646357Y199134D02*
Y199135D01*
G01X1659823Y194796D02*
Y194787D01*
G01X1659824Y194802D02*
X1659823Y194796D01*
G01X1659826Y194803D02*
X1659824Y194802D01*
G01X1645413Y211699D02*
Y211707D01*
G01X1645412Y211694D02*
X1645413Y211699D01*
G01X1645411Y211693D02*
X1645412Y211694D01*
G01X1645413Y208550D02*
Y208557D01*
G01X1645412Y208545D02*
X1645413Y208550D01*
G01X1645411Y208543D02*
X1645412Y208545D01*
G01X1645413Y205400D02*
Y205407D01*
G01X1645412Y205395D02*
X1645413Y205400D01*
G01X1645411Y205394D02*
X1645412Y205395D01*
G01X1645413Y202250D02*
Y202258D01*
G01X1645412Y202246D02*
X1645413Y202250D01*
G01X1645411Y202244D02*
X1645412Y202246D01*
G01X1645413Y199101D02*
Y199108D01*
G01X1645412Y199096D02*
X1645413Y199101D01*
G01X1645411Y199094D02*
X1645412Y199096D01*
G01X1646395Y210565D02*
X1646398Y210577D01*
G01X1646389Y210554D02*
X1646395Y210565D01*
G01X1646378Y210545D02*
X1646389Y210554D01*
G01X1646395Y207415D02*
X1646398Y207428D01*
G01X1646389Y207404D02*
X1646395Y207415D01*
G01X1646378Y207396D02*
X1646389Y207404D01*
G01X1646395Y204265D02*
X1646398Y204278D01*
G01X1646389Y204254D02*
X1646395Y204265D01*
G01X1646378Y204246D02*
X1646389Y204254D01*
G01X1646395Y201116D02*
X1646398Y201128D01*
G01X1646389Y201105D02*
X1646395Y201116D01*
G01X1646378Y201096D02*
X1646389Y201105D01*
G01X1646395Y197966D02*
X1646398Y197979D01*
G01X1646389Y197955D02*
X1646395Y197966D01*
G01X1646378Y197947D02*
X1646389Y197955D01*
G01X1645452Y211737D02*
Y211744D01*
G01Y211733D02*
Y211737D01*
G01X1645450Y211732D02*
X1645452Y211733D01*
G01Y208588D02*
Y208594D01*
G01Y208584D02*
Y208588D01*
G01X1645450Y208583D02*
X1645452Y208584D01*
G01Y205438D02*
Y205444D01*
G01Y205434D02*
Y205438D01*
G01X1645450Y205433D02*
X1645452Y205434D01*
G01Y202289D02*
Y202295D01*
G01Y202285D02*
Y202289D01*
G01X1645450Y202283D02*
X1645452Y202285D01*
G01Y199139D02*
Y199145D01*
G01Y199135D02*
Y199139D01*
G01X1645450Y199134D02*
X1645452Y199135D01*
G01X1645414Y211713D02*
X1645413Y211707D01*
G01X1645416Y211719D02*
X1645414Y211713D01*
G01X1645419Y211725D02*
X1645416Y211719D01*
G01X1645422Y211730D02*
X1645419Y211725D01*
G01X1645427Y211735D02*
X1645422Y211730D01*
G01X1645433Y211739D02*
X1645427Y211735D01*
G01X1645414Y208563D02*
X1645413Y208557D01*
G01X1645416Y208570D02*
X1645414Y208563D01*
G01X1645419Y208575D02*
X1645416Y208570D01*
G01X1645422Y208581D02*
X1645419Y208575D01*
G01X1645427Y208585D02*
X1645422Y208581D01*
G01X1645433Y208589D02*
X1645427Y208585D01*
G01X1645414Y205414D02*
X1645413Y205407D01*
G01X1645416Y205420D02*
X1645414Y205414D01*
G01X1645419Y205426D02*
X1645416Y205420D01*
G01X1645422Y205431D02*
X1645419Y205426D01*
G01X1645427Y205435D02*
X1645422Y205431D01*
G01X1645433Y205439D02*
X1645427Y205435D01*
G01X1645414Y202264D02*
X1645413Y202258D01*
G01X1645416Y202270D02*
X1645414Y202264D01*
G01X1645419Y202276D02*
X1645416Y202270D01*
G01X1645422Y202281D02*
X1645419Y202276D01*
G01X1645427Y202286D02*
X1645422Y202281D01*
G01X1645433Y202290D02*
X1645427Y202286D01*
G01X1645414Y199115D02*
X1645413Y199108D01*
G01X1645416Y199121D02*
X1645414Y199115D01*
G01X1645419Y199126D02*
X1645416Y199121D01*
G01X1645422Y199132D02*
X1645419Y199126D01*
G01X1645427Y199136D02*
X1645422Y199132D01*
G01X1645433Y199140D02*
X1645427Y199136D01*
G01X1646369Y201104D02*
X1646357Y201102D01*
G01X1646379Y201109D02*
X1646369Y201104D01*
G01Y197955D02*
X1646357Y197953D01*
G01X1646379Y197960D02*
X1646369Y197955D01*
G01X1659823Y189796D02*
Y189787D01*
G01X1659824Y189802D02*
X1659823Y189796D01*
G01X1659826Y189803D02*
X1659824Y189802D01*
G01X1659823Y184796D02*
Y184787D01*
G01X1659824Y184802D02*
X1659823Y184796D01*
G01X1659826Y184803D02*
X1659824Y184802D01*
G01X1659823Y179796D02*
Y179787D01*
G01X1659824Y179802D02*
X1659823Y179796D01*
G01X1659826Y179803D02*
X1659824Y179802D01*
G01X1659823Y174796D02*
Y174787D01*
G01X1659824Y174802D02*
X1659823Y174796D01*
G01X1659826Y174803D02*
X1659824Y174802D01*
G01X1659823Y169796D02*
Y169787D01*
G01X1659824Y169802D02*
X1659823Y169796D01*
G01X1659826Y169803D02*
X1659824Y169802D01*
G01X1659823Y164796D02*
Y164787D01*
G01X1659824Y164802D02*
X1659823Y164796D01*
G01X1659826Y164803D02*
X1659824Y164802D01*
G01X1646397Y199097D02*
X1646398Y199108D01*
G01X1646397Y202246D02*
X1646398Y202257D01*
G01X1646397Y205396D02*
X1646398Y205407D01*
G01X1646397Y208546D02*
X1646398Y208557D01*
G01X1646397Y211695D02*
X1646398Y211706D01*
G01X1659823Y166155D02*
Y166164D01*
G01Y171155D02*
Y171164D01*
G01Y176155D02*
Y176164D01*
G01Y181155D02*
Y181164D01*
G01Y186155D02*
Y186164D01*
G01Y191155D02*
Y191164D01*
G01Y196155D02*
Y196164D01*
G01X1664173Y194803D02*
Y196181D01*
G01Y189803D02*
Y191181D01*
G01Y184803D02*
Y186181D01*
G01Y179803D02*
Y181181D01*
G01Y174803D02*
Y176181D01*
G01Y169803D02*
Y171181D01*
G01Y164803D02*
Y166181D01*
G01X1661004D02*
Y164803D01*
G01Y171181D02*
Y169803D01*
G01Y176181D02*
Y174803D01*
G01Y181181D02*
Y179803D01*
G01Y186181D02*
Y184803D01*
G01Y191181D02*
Y189803D01*
G01Y196181D02*
Y194803D01*
G01X1660433Y219035D02*
Y196949D01*
G01X1659823Y166156D02*
Y166299D01*
G01Y176156D02*
Y176299D01*
G01Y171156D02*
Y171299D01*
G01Y186156D02*
Y186299D01*
G01Y181156D02*
Y181299D01*
G01Y196156D02*
Y196299D01*
G01Y191156D02*
Y191299D01*
G01Y194311D02*
Y196673D01*
G01Y189311D02*
Y191673D01*
G01Y184311D02*
Y186673D01*
G01Y179311D02*
Y181673D01*
G01Y174311D02*
Y176673D01*
G01Y169311D02*
Y171673D01*
G01Y164311D02*
Y166673D01*
G01X1659252Y217854D02*
Y198130D01*
G01X1658839Y166673D02*
Y164311D01*
G01Y171673D02*
Y169311D01*
G01Y176673D02*
Y174311D01*
G01Y181673D02*
Y179311D01*
G01Y186673D02*
Y184311D01*
G01Y191673D02*
Y189311D01*
G01Y196673D02*
Y194311D01*
G01X1646398Y210394D02*
Y211890D01*
G01Y207244D02*
Y208740D01*
G01Y204094D02*
Y205591D01*
G01Y200945D02*
Y202441D01*
G01Y197795D02*
Y199291D01*
G01X1646358Y197942D02*
Y197795D01*
G01Y201091D02*
Y200944D01*
G01Y202441D02*
Y202295D01*
G01Y199292D02*
Y199145D01*
G01Y207391D02*
Y207244D01*
G01Y204241D02*
Y204094D01*
G01Y205591D02*
Y205444D01*
G01Y210540D02*
Y210393D01*
G01Y211890D02*
Y211744D01*
G01Y208741D02*
Y208594D01*
G01X1645453Y210393D02*
Y210540D01*
G01Y211744D02*
Y211891D01*
G01Y208594D02*
Y208741D01*
G01Y207243D02*
Y207391D01*
G01Y204094D02*
Y204241D01*
G01Y205444D02*
Y205591D01*
G01Y200944D02*
Y201091D01*
G01Y202295D02*
Y202442D01*
G01Y199145D02*
Y199292D01*
G01Y197794D02*
Y197942D01*
G01X1645413Y202441D02*
Y200945D01*
G01Y199291D02*
Y197795D01*
G01Y205591D02*
Y204094D01*
G01Y211890D02*
Y210394D01*
G01Y208740D02*
Y207244D01*
G01X1644232Y199134D02*
Y197953D01*
G01Y202283D02*
Y201102D01*
G01Y208583D02*
Y207402D01*
G01Y205433D02*
Y204252D01*
G01Y211732D02*
Y210551D01*
G01X1643898Y220197D02*
Y195787D01*
G01X1643504D02*
Y220197D01*
G01X1640472Y210551D02*
Y211732D01*
G01Y207402D02*
Y208583D01*
G01Y204252D02*
Y205433D01*
G01Y201102D02*
Y202283D01*
G01Y197953D02*
Y199134D01*
G01X1646398Y210577D02*
X1646397Y210588D01*
G01X1646398Y207428D02*
X1646397Y207439D01*
G01X1646398Y204278D02*
X1646397Y204289D01*
G01X1646398Y201128D02*
X1646397Y201139D01*
G01X1646398Y197979D02*
X1646397Y197990D01*
G01X1659252Y198130D02*
X1660433Y196949D01*
G01X1655315Y198130D02*
X1656496Y196949D01*
G01X1645411Y207437D02*
X1645300Y207441D01*
G01X1645411Y201138D02*
X1645300Y201142D01*
G01X1645411Y210587D02*
X1645300Y210591D01*
G01X1646358Y211929D02*
X1645453D01*
G01X1646398Y211890D02*
X1645413D01*
G01X1646357Y211732D02*
X1640472D01*
G01Y211693D02*
X1646396D01*
G01X1644666Y210591D02*
X1644232D01*
G01X1646396D02*
X1640472D01*
G01X1646357Y210551D02*
X1640472D01*
G01X1645413Y210394D02*
X1646398D01*
G01X1645453Y210354D02*
X1646358D01*
G01Y208780D02*
X1645453D01*
G01X1646398Y208740D02*
X1645413D01*
G01X1646357Y208583D02*
X1640472D01*
G01Y208543D02*
X1646396D01*
G01X1644666Y207441D02*
X1644232D01*
G01X1646396D02*
X1640472D01*
G01X1646357Y207402D02*
X1640472D01*
G01X1645413Y207244D02*
X1646398D01*
G01X1645453Y207205D02*
X1646358D01*
G01Y205630D02*
X1645453D01*
G01X1646398Y205591D02*
X1645413D01*
G01X1646357Y205433D02*
X1640472D01*
G01Y205394D02*
X1646396D01*
G01Y204291D02*
X1640472D01*
G01X1646357Y204252D02*
X1640472D01*
G01X1645413Y204094D02*
X1646398D01*
G01X1645453Y204055D02*
X1646358D01*
G01Y202480D02*
X1645453D01*
G01X1646398Y202441D02*
X1645413D01*
G01X1646357Y202283D02*
X1640472D01*
G01Y202244D02*
X1646396D01*
G01X1644666Y201142D02*
X1644232D01*
G01X1646396D02*
X1640472D01*
G01X1646357Y201102D02*
X1640472D01*
G01X1645413Y200945D02*
X1646398D01*
G01X1645453Y200906D02*
X1646358D01*
G01Y199331D02*
X1645453D01*
G01X1646398Y199291D02*
X1645413D01*
G01X1646357Y199134D02*
X1640472D01*
G01Y199094D02*
X1646396D01*
G01X1659252Y198130D02*
X1655315D01*
G01X1646396Y197992D02*
X1640472D01*
G01X1646357Y197953D02*
X1640472D01*
G01X1645413Y197795D02*
X1646398D01*
G01X1645453Y197756D02*
X1646358D01*
G01X1660433Y196949D02*
X1656496D01*
G01X1659823Y196673D02*
X1658839D01*
G01X1658840Y196181D02*
X1664173D01*
G01Y196142D02*
X1659825D01*
G01X1646850Y195787D02*
X1643504D01*
G01X1664173Y194803D02*
X1658840D01*
G01X1658839Y194311D02*
X1659823D01*
G01Y191673D02*
X1658839D01*
G01X1658840Y191181D02*
X1664173D01*
G01Y191142D02*
X1659825D01*
G01X1664173Y189803D02*
X1658840D01*
G01X1658839Y189311D02*
X1659823D01*
G01Y186673D02*
X1658839D01*
G01X1658840Y186181D02*
X1664173D01*
G01Y186142D02*
X1659825D01*
G01X1664173Y184803D02*
X1658840D01*
G01X1658839Y184311D02*
X1659823D01*
G01Y181673D02*
X1658839D01*
G01X1658840Y181181D02*
X1664173D01*
G01Y181142D02*
X1659825D01*
G01X1664173Y179803D02*
X1658840D01*
G01X1658839Y179311D02*
X1659823D01*
G01Y176673D02*
X1658839D01*
G01X1658840Y176181D02*
X1664173D01*
G01Y176142D02*
X1659825D01*
G01X1664173Y174803D02*
X1658840D01*
G01X1658839Y174311D02*
X1659823D01*
G01Y171673D02*
X1658839D01*
G01X1658840Y171181D02*
X1664173D01*
G01Y171142D02*
X1659825D01*
G01X1664173Y169803D02*
X1658840D01*
G01X1658839Y169311D02*
X1659823D01*
G01X1658839Y196377D02*
X1659794Y196378D01*
G01X1659823Y194607D02*
X1658839Y194606D01*
G01Y191377D02*
X1659794Y191378D01*
G01X1659823Y189607D02*
X1658839Y189606D01*
G01Y186377D02*
X1659794Y186378D01*
G01X1659823Y184607D02*
X1658839Y184606D01*
G01Y181377D02*
X1659794Y181378D01*
G01X1659823Y179607D02*
X1658839Y179606D01*
G01Y176377D02*
X1659794Y176378D01*
G01X1659823Y174607D02*
X1658839Y174606D01*
G01Y171377D02*
X1659794Y171378D01*
G01X1659823Y169607D02*
X1658839Y169606D01*
G01X1659823Y166673D02*
X1658839D01*
G01X1658840Y166181D02*
X1664173D01*
G01Y166142D02*
X1659825D01*
G01X1664173Y164803D02*
X1658840D01*
G01X1658839Y164311D02*
X1659823D01*
G01X1658839Y166377D02*
X1659794Y166378D01*
G01X1659823Y164607D02*
X1658839Y164606D01*
G01X1645416Y214862D02*
X1645411Y214843D01*
G01X1645431Y214877D02*
X1645416Y214862D01*
G01X1645450Y214882D02*
X1645431Y214877D01*
G01X1645416Y218012D02*
X1645411Y217992D01*
G01X1645431Y218026D02*
X1645416Y218012D01*
G01X1645450Y218031D02*
X1645431Y218026D01*
G01X1646391Y213720D02*
X1646396Y213740D01*
G01X1646376Y213706D02*
X1646391Y213720D01*
G01X1646357Y213701D02*
X1646376Y213706D01*
G01X1646391Y216870D02*
X1646396Y216890D01*
G01X1646376Y216856D02*
X1646391Y216870D01*
G01X1646357Y216850D02*
X1646376Y216856D01*
G01X1646397Y213719D02*
X1646398Y213727D01*
G01X1646394Y213713D02*
X1646397Y213719D01*
G01X1646391Y213706D02*
X1646394Y213713D01*
G01X1646386Y213700D02*
X1646391Y213706D01*
G01X1646380Y213696D02*
X1646386Y213700D01*
G01X1646373Y213693D02*
X1646380Y213696D01*
G01X1646366Y213691D02*
X1646373Y213693D01*
G01X1646358Y213690D02*
X1646366Y213691D01*
G01X1645436Y214890D02*
X1645433Y214888D01*
G01X1645439Y214891D02*
X1645436Y214890D01*
G01X1645442Y214892D02*
X1645439Y214891D01*
G01X1645446Y214893D02*
X1645442Y214892D01*
G01X1645449Y214893D02*
X1645446D01*
G01X1645453D02*
X1645449D01*
G01X1646375Y216843D02*
X1646378Y216844D01*
G01X1646372Y216842D02*
X1646375Y216843D01*
G01X1646369Y216841D02*
X1646372Y216842D01*
G01X1646365Y216840D02*
X1646369Y216841D01*
G01X1646362Y216839D02*
X1646365Y216840D01*
G01X1646358Y216839D02*
X1646362D01*
G01X1645436Y218039D02*
X1645433Y218038D01*
G01X1645439Y218041D02*
X1645436Y218039D01*
G01X1645442Y218042D02*
X1645439Y218041D01*
G01X1645446Y218042D02*
X1645442D01*
G01X1645449Y218043D02*
X1645446Y218042D01*
G01X1645453Y218043D02*
X1645449D01*
G01X1646388Y214880D02*
X1646392Y214875D01*
G01X1646383Y214885D02*
X1646388Y214880D01*
G01X1646378Y214889D02*
X1646383Y214885D01*
G01X1646372Y214891D02*
X1646378Y214889D01*
G01X1646365Y214893D02*
X1646372Y214891D01*
G01X1646358Y214893D02*
X1646365D01*
G01X1646388Y218030D02*
X1646392Y218025D01*
G01X1646383Y218034D02*
X1646388Y218030D01*
G01X1646378Y218038D02*
X1646383Y218034D01*
G01X1646372Y218041D02*
X1646378Y218038D01*
G01X1646365Y218043D02*
X1646372Y218041D01*
G01X1646358Y218043D02*
X1646365D01*
G01X1645414Y213719D02*
X1645413Y213727D01*
G01X1645417Y213713D02*
X1645414Y213719D01*
G01X1645420Y213706D02*
X1645417Y213713D01*
G01X1645425Y213700D02*
X1645420Y213706D01*
G01X1645431Y213696D02*
X1645425Y213700D01*
G01X1645438Y213693D02*
X1645431Y213696D01*
G01X1645445Y213691D02*
X1645438Y213693D01*
G01X1645453Y213690D02*
X1645445Y213691D01*
G01X1645414Y216869D02*
X1645413Y216876D01*
G01X1645417Y216862D02*
X1645414Y216869D01*
G01X1645420Y216856D02*
X1645417Y216862D01*
G01X1645425Y216850D02*
X1645420Y216856D01*
G01X1645431Y216845D02*
X1645425Y216850D01*
G01X1645438Y216842D02*
X1645431Y216845D01*
G01X1645445Y216840D02*
X1645438Y216842D01*
G01X1645453Y216839D02*
X1645445Y216840D01*
G01X1646367Y214881D02*
X1646377Y214876D01*
G01X1646357Y214882D02*
X1646367Y214881D01*
G01Y218030D02*
X1646377Y218026D01*
G01X1646357Y218031D02*
X1646367Y218030D01*
G01X1645413Y213731D02*
Y213727D01*
G01X1645415Y213724D02*
X1645413Y213731D01*
G01X1645426Y213709D02*
X1645415Y213724D01*
G01X1645451Y213701D02*
X1645426Y213709D01*
G01X1645413Y216880D02*
Y216876D01*
G01X1645415Y216874D02*
X1645413Y216880D01*
G01X1645426Y216859D02*
X1645415Y216874D01*
G01X1645451Y216850D02*
X1645426Y216859D01*
G01X1659810Y221173D02*
X1659821Y221157D01*
G01X1659786Y221181D02*
X1659810Y221173D01*
G01Y226173D02*
X1659821Y226157D01*
G01X1659786Y226181D02*
X1659810Y226173D01*
G01Y231173D02*
X1659821Y231157D01*
G01X1659786Y231181D02*
X1659810Y231173D01*
G01Y236173D02*
X1659821Y236157D01*
G01X1659786Y236181D02*
X1659810Y236173D01*
G01Y241173D02*
X1659821Y241157D01*
G01X1659786Y241181D02*
X1659810Y241173D01*
G01Y246173D02*
X1659821Y246157D01*
G01X1659786Y246181D02*
X1659810Y246173D01*
G01Y251173D02*
X1659821Y251157D01*
G01X1659786Y251181D02*
X1659810Y251173D01*
G01Y256173D02*
X1659821Y256157D01*
G01X1659786Y256181D02*
X1659810Y256173D01*
G01X1646366Y214881D02*
X1646357Y214882D01*
G01X1646375Y214878D02*
X1646366Y214881D01*
G01X1646383Y214872D02*
X1646375Y214878D01*
G01X1646366Y218030D02*
X1646357Y218031D01*
G01X1646375Y218027D02*
X1646366Y218030D01*
G01X1646383Y218022D02*
X1646375Y218027D01*
G01X1645452Y213696D02*
X1645453Y213690D01*
G01X1645452Y213700D02*
Y213696D01*
G01X1645450Y213701D02*
X1645452Y213700D01*
G01Y216846D02*
X1645453Y216839D01*
G01X1645452Y216849D02*
Y216846D01*
G01X1645450Y216850D02*
X1645452Y216849D01*
G01X1659823Y221148D02*
Y221156D01*
G01X1659824Y221144D02*
X1659823Y221148D01*
G01X1659825Y221142D02*
X1659824Y221144D01*
G01X1659823Y226148D02*
Y226156D01*
G01X1659824Y226144D02*
X1659823Y226148D01*
G01X1659825Y226142D02*
X1659824Y226144D01*
G01X1659823Y231148D02*
Y231156D01*
G01X1659824Y231144D02*
X1659823Y231148D01*
G01X1659825Y231142D02*
X1659824Y231144D01*
G01X1659823Y236148D02*
Y236156D01*
G01X1659824Y236144D02*
X1659823Y236148D01*
G01X1659825Y236142D02*
X1659824Y236144D01*
G01X1659823Y241148D02*
Y241156D01*
G01X1659824Y241144D02*
X1659823Y241148D01*
G01X1659825Y241142D02*
X1659824Y241144D01*
G01X1659823Y246148D02*
Y246156D01*
G01X1659824Y246144D02*
X1659823Y246148D01*
G01X1659825Y246142D02*
X1659824Y246144D01*
G01X1659823Y251148D02*
Y251156D01*
G01X1659824Y251144D02*
X1659823Y251148D01*
G01X1659825Y251142D02*
X1659824Y251144D01*
G01X1659823Y256148D02*
Y256156D01*
G01X1659824Y256144D02*
X1659823Y256148D01*
G01X1659825Y256142D02*
X1659824Y256144D01*
G01X1645436Y213704D02*
X1645450Y213701D01*
G01X1645424Y213711D02*
X1645436Y213704D01*
G01X1645412Y213731D02*
X1645424Y213711D01*
G01X1646398Y213734D02*
Y213727D01*
G01X1646397Y213739D02*
X1646398Y213734D01*
G01X1646396Y213740D02*
X1646397Y213739D01*
G01X1646398Y216884D02*
Y216876D01*
G01X1646397Y216889D02*
X1646398Y216884D01*
G01X1646396Y216890D02*
X1646397Y216889D01*
G01X1645436Y216853D02*
X1645450Y216850D01*
G01X1645423Y216861D02*
X1645436Y216853D01*
G01X1645412Y216881D02*
X1645423Y216861D01*
G01X1646397Y214863D02*
X1646398Y214856D01*
G01X1646395Y214869D02*
X1646397Y214863D01*
G01X1646392Y214875D02*
X1646395Y214869D01*
G01X1646397Y218013D02*
X1646398Y218006D01*
G01X1646395Y218019D02*
X1646397Y218013D01*
G01X1646392Y218025D02*
X1646395Y218019D01*
G01X1646359Y216845D02*
Y216839D01*
G01X1646357Y216849D02*
X1646359Y216845D01*
G01X1646357Y216850D02*
Y216849D01*
G01X1658839Y221189D02*
Y221198D01*
G01Y221183D02*
Y221189D01*
G01X1658840Y221181D02*
X1658839Y221183D01*
G01Y226189D02*
Y226198D01*
G01Y226183D02*
Y226189D01*
G01X1658840Y226181D02*
X1658839Y226183D01*
G01Y231189D02*
Y231198D01*
G01Y231183D02*
Y231189D01*
G01X1658840Y231181D02*
X1658839Y231183D01*
G01Y236189D02*
Y236198D01*
G01Y236183D02*
Y236189D01*
G01X1658840Y236181D02*
X1658839Y236183D01*
G01Y241189D02*
Y241198D01*
G01Y241183D02*
Y241189D01*
G01X1658840Y241181D02*
X1658839Y241183D01*
G01Y246189D02*
Y246198D01*
G01Y246183D02*
Y246189D01*
G01X1658840Y246181D02*
X1658839Y246183D01*
G01Y251189D02*
Y251198D01*
G01Y251183D02*
Y251189D01*
G01X1658840Y251181D02*
X1658839Y251183D01*
G01Y256189D02*
Y256198D01*
G01Y256183D02*
Y256189D01*
G01X1658840Y256181D02*
X1658839Y256183D01*
G01X1659815Y221325D02*
X1659823Y221299D01*
G01X1659805Y221352D02*
X1659815Y221325D01*
G01X1659794Y221378D02*
X1659805Y221352D01*
G01X1659815Y226325D02*
X1659823Y226299D01*
G01X1659805Y226352D02*
X1659815Y226325D01*
G01X1659794Y226378D02*
X1659805Y226352D01*
G01X1659815Y231325D02*
X1659823Y231299D01*
G01X1659805Y231352D02*
X1659815Y231325D01*
G01X1659794Y231378D02*
X1659805Y231352D01*
G01X1659815Y236325D02*
X1659823Y236299D01*
G01X1659805Y236352D02*
X1659815Y236325D01*
G01X1659794Y236378D02*
X1659805Y236352D01*
G01X1659815Y241325D02*
X1659823Y241299D01*
G01X1659805Y241352D02*
X1659815Y241325D01*
G01X1659794Y241378D02*
X1659805Y241352D01*
G01X1659815Y246325D02*
X1659823Y246299D01*
G01X1659805Y246352D02*
X1659815Y246325D01*
G01X1659794Y246378D02*
X1659805Y246352D01*
G01X1659815Y251325D02*
X1659823Y251299D01*
G01X1659805Y251352D02*
X1659815Y251325D01*
G01X1659794Y251378D02*
X1659805Y251352D01*
G01X1659815Y256325D02*
X1659823Y256299D01*
G01X1659805Y256352D02*
X1659815Y256325D01*
G01X1659794Y256378D02*
X1659805Y256352D01*
G01X1659806Y221176D02*
X1659786Y221181D01*
G01X1659820Y221162D02*
X1659806Y221176D01*
G01X1659825Y221142D02*
X1659820Y221162D01*
G01X1659806Y226176D02*
X1659786Y226181D01*
G01X1659820Y226162D02*
X1659806Y226176D01*
G01X1659825Y226142D02*
X1659820Y226162D01*
G01X1659806Y231176D02*
X1659786Y231181D01*
G01X1659820Y231162D02*
X1659806Y231176D01*
G01X1659825Y231142D02*
X1659820Y231162D01*
G01X1659806Y236176D02*
X1659786Y236181D01*
G01X1659820Y236162D02*
X1659806Y236176D01*
G01X1659825Y236142D02*
X1659820Y236162D01*
G01X1659806Y241176D02*
X1659786Y241181D01*
G01X1659820Y241162D02*
X1659806Y241176D01*
G01X1659825Y241142D02*
X1659820Y241162D01*
G01X1659806Y246176D02*
X1659786Y246181D01*
G01X1659820Y246162D02*
X1659806Y246176D01*
G01X1659825Y246142D02*
X1659820Y246162D01*
G01X1659806Y251176D02*
X1659786Y251181D01*
G01X1659820Y251162D02*
X1659806Y251176D01*
G01X1659825Y251142D02*
X1659820Y251162D01*
G01X1659806Y256176D02*
X1659786Y256181D01*
G01X1659820Y256162D02*
X1659806Y256176D01*
G01X1659825Y256142D02*
X1659820Y256162D01*
G01X1646390Y214864D02*
X1646383Y214872D01*
G01X1646395Y214854D02*
X1646390Y214864D01*
G01X1646396Y214843D02*
X1646395Y214854D01*
G01X1646390Y218013D02*
X1646383Y218022D01*
G01X1646395Y218003D02*
X1646390Y218013D01*
G01X1646396Y217992D02*
X1646395Y218003D01*
G01X1659790Y221279D02*
X1659794Y221378D01*
G01X1659784Y221207D02*
X1659790Y221279D01*
G01X1659786Y221181D02*
X1659784Y221207D01*
G01X1659790Y226279D02*
X1659794Y226378D01*
G01X1659784Y226207D02*
X1659790Y226279D01*
G01X1659786Y226181D02*
X1659784Y226207D01*
G01X1659790Y231279D02*
X1659794Y231378D01*
G01X1659784Y231207D02*
X1659790Y231279D01*
G01X1659786Y231181D02*
X1659784Y231207D01*
G01X1659790Y236279D02*
X1659794Y236378D01*
G01X1659784Y236207D02*
X1659790Y236279D01*
G01X1659786Y236181D02*
X1659784Y236207D01*
G01X1659790Y241279D02*
X1659794Y241378D01*
G01X1659784Y241207D02*
X1659790Y241279D01*
G01X1659786Y241181D02*
X1659784Y241207D01*
G01X1659790Y246279D02*
X1659794Y246378D01*
G01X1659784Y246207D02*
X1659790Y246279D01*
G01X1659786Y246181D02*
X1659784Y246207D01*
G01X1659790Y251279D02*
X1659794Y251378D01*
G01X1659784Y251207D02*
X1659790Y251279D01*
G01X1659786Y251181D02*
X1659784Y251207D01*
G01X1659790Y256279D02*
X1659794Y256378D01*
G01X1659784Y256207D02*
X1659790Y256279D01*
G01X1659786Y256181D02*
X1659784Y256207D01*
G01X1645454Y218216D02*
X1645453Y218228D01*
G01X1645450Y218203D02*
X1645454Y218216D01*
G01X1645450Y218189D02*
Y218203D01*
G01X1645454Y215067D02*
X1645453Y215079D01*
G01X1645450Y215054D02*
X1645454Y215067D01*
G01X1645450Y215040D02*
Y215054D01*
G01X1658839Y259802D02*
X1658840Y259803D01*
G01X1658839Y259796D02*
Y259802D01*
G01Y259787D02*
Y259796D01*
G01Y254802D02*
X1658840Y254803D01*
G01X1658839Y254796D02*
Y254802D01*
G01Y254787D02*
Y254796D01*
G01Y249802D02*
X1658840Y249803D01*
G01X1658839Y249796D02*
Y249802D01*
G01Y249787D02*
Y249796D01*
G01Y244802D02*
X1658840Y244803D01*
G01X1658839Y244796D02*
Y244802D01*
G01Y244787D02*
Y244796D01*
G01Y239802D02*
X1658840Y239803D01*
G01X1658839Y239796D02*
Y239802D01*
G01Y239787D02*
Y239796D01*
G01Y234802D02*
X1658840Y234803D01*
G01X1658839Y234796D02*
Y234802D01*
G01Y234787D02*
Y234796D01*
G01Y229802D02*
X1658840Y229803D01*
G01X1658839Y229796D02*
Y229802D01*
G01Y229787D02*
Y229796D01*
G01Y224802D02*
X1658840Y224803D01*
G01X1658839Y224796D02*
Y224802D01*
G01Y224787D02*
Y224796D01*
G01Y219802D02*
X1658840Y219803D01*
G01X1658839Y219796D02*
Y219802D01*
G01Y219787D02*
Y219796D01*
G01X1645413Y216884D02*
Y216876D01*
G01X1645412Y216889D02*
X1645413Y216884D01*
G01X1645412Y216881D02*
Y216889D01*
G01X1645450Y216679D02*
X1645449Y216693D01*
G01X1645454Y216666D02*
X1645450Y216679D01*
G01X1645453Y216654D02*
X1645454Y216666D01*
G01X1645450Y213530D02*
X1645449Y213543D01*
G01X1645454Y213517D02*
X1645450Y213530D01*
G01X1645453Y213504D02*
X1645454Y213517D01*
G01X1646361Y218203D02*
X1646362Y218189D01*
G01X1646357Y218216D02*
X1646361Y218203D01*
G01X1646358Y218228D02*
X1646357Y218216D01*
G01X1646361Y215053D02*
X1646362Y215040D01*
G01X1646357Y215066D02*
X1646361Y215053D01*
G01X1646358Y215079D02*
X1646357Y215066D01*
G01X1645413Y213734D02*
Y213727D01*
G01X1645412Y213739D02*
X1645413Y213734D01*
G01X1645412Y213732D02*
Y213739D01*
G01X1646357Y216666D02*
X1646358Y216654D01*
G01X1646360Y216679D02*
X1646357Y216666D01*
G01X1646361Y216693D02*
X1646360Y216679D01*
G01X1646357Y213517D02*
X1646358Y213504D01*
G01X1646360Y213530D02*
X1646357Y213517D01*
G01X1646361Y213543D02*
X1646360Y213530D01*
G01X1645426Y218023D02*
X1645450Y218031D01*
G01X1645415Y218009D02*
X1645426Y218023D01*
G01X1645413Y218002D02*
X1645415Y218009D01*
G01X1645426Y214874D02*
X1645450Y214882D01*
G01X1645415Y214859D02*
X1645426Y214874D01*
G01X1645413Y214852D02*
X1645415Y214859D01*
G01X1646369Y216852D02*
X1646357Y216850D01*
G01X1646379Y216857D02*
X1646369Y216852D01*
G01Y213703D02*
X1646357Y213701D01*
G01X1646379Y213708D02*
X1646369Y213703D01*
G01X1646398Y217998D02*
Y218006D01*
G01X1646397Y217994D02*
X1646398Y217998D01*
G01X1646396Y217992D02*
X1646397Y217994D01*
G01X1646398Y214849D02*
Y214856D01*
G01X1646397Y214844D02*
X1646398Y214849D01*
G01X1646396Y214843D02*
X1646397Y214844D01*
G01X1646358Y218037D02*
Y218043D01*
G01X1646357Y218033D02*
X1646358Y218037D01*
G01X1646357Y218031D02*
Y218033D01*
G01X1646358Y214887D02*
Y214893D01*
G01X1646357Y214883D02*
X1646358Y214887D01*
G01X1646357Y214882D02*
Y214883D01*
G01X1659823Y259796D02*
Y259787D01*
G01X1659824Y259802D02*
X1659823Y259796D01*
G01X1659826Y259803D02*
X1659824Y259802D01*
G01X1659823Y254796D02*
Y254787D01*
G01X1659824Y254802D02*
X1659823Y254796D01*
G01X1659826Y254803D02*
X1659824Y254802D01*
G01X1659823Y249796D02*
Y249787D01*
G01X1659824Y249802D02*
X1659823Y249796D01*
G01X1659826Y249803D02*
X1659824Y249802D01*
G01X1659823Y244796D02*
Y244787D01*
G01X1659824Y244802D02*
X1659823Y244796D01*
G01X1659826Y244803D02*
X1659824Y244802D01*
G01X1659823Y239796D02*
Y239787D01*
G01X1659824Y239802D02*
X1659823Y239796D01*
G01X1659826Y239803D02*
X1659824Y239802D01*
G01X1659823Y234796D02*
Y234787D01*
G01X1659824Y234802D02*
X1659823Y234796D01*
G01X1659826Y234803D02*
X1659824Y234802D01*
G01X1659823Y229796D02*
Y229787D01*
G01X1659824Y229802D02*
X1659823Y229796D01*
G01X1659826Y229803D02*
X1659824Y229802D01*
G01X1659823Y224796D02*
Y224787D01*
G01X1659824Y224802D02*
X1659823Y224796D01*
G01X1659826Y224803D02*
X1659824Y224802D01*
G01X1659823Y219796D02*
Y219787D01*
G01X1659824Y219802D02*
X1659823Y219796D01*
G01X1659826Y219803D02*
X1659824Y219802D01*
G01X1645413Y217998D02*
Y218006D01*
G01X1645412Y217994D02*
X1645413Y217998D01*
G01X1645411Y217992D02*
X1645412Y217994D01*
G01X1645413Y214849D02*
Y214856D01*
G01X1645412Y214844D02*
X1645413Y214849D01*
G01X1645411Y214843D02*
X1645412Y214844D01*
G01X1646395Y216864D02*
X1646398Y216876D01*
G01X1646389Y216853D02*
X1646395Y216864D01*
G01X1646378Y216844D02*
X1646389Y216853D01*
G01X1645452Y218037D02*
Y218043D01*
G01Y218033D02*
Y218037D01*
G01X1645450Y218031D02*
X1645452Y218033D01*
G01Y214887D02*
Y214893D01*
G01Y214883D02*
Y214887D01*
G01X1645450Y214882D02*
X1645452Y214883D01*
G01X1645414Y218012D02*
X1645413Y218006D01*
G01X1645416Y218019D02*
X1645414Y218012D01*
G01X1645419Y218024D02*
X1645416Y218019D01*
G01X1645422Y218030D02*
X1645419Y218024D01*
G01X1645427Y218034D02*
X1645422Y218030D01*
G01X1645433Y218038D02*
X1645427Y218034D01*
G01X1645414Y214863D02*
X1645413Y214856D01*
G01X1645416Y214869D02*
X1645414Y214863D01*
G01X1645419Y214874D02*
X1645416Y214869D01*
G01X1645422Y214880D02*
X1645419Y214874D01*
G01X1645427Y214884D02*
X1645422Y214880D01*
G01X1645433Y214888D02*
X1645427Y214884D01*
G01X1659252Y217854D02*
X1660433Y219035D01*
G01X1655315Y217854D02*
X1656496Y219035D01*
G01X1646397Y214845D02*
X1646398Y214856D01*
G01X1646397Y217994D02*
X1646398Y218006D01*
G01X1659823Y221155D02*
Y221164D01*
G01Y226155D02*
Y226164D01*
G01Y231155D02*
Y231164D01*
G01Y236155D02*
Y236164D01*
G01Y241155D02*
Y241164D01*
G01Y246155D02*
Y246164D01*
G01Y251155D02*
Y251164D01*
G01Y256155D02*
Y256164D01*
G01X1664173Y259803D02*
Y261181D01*
G01Y254803D02*
Y256181D01*
G01Y249803D02*
Y251181D01*
G01Y244803D02*
Y246181D01*
G01Y239803D02*
Y241181D01*
G01Y234803D02*
Y236181D01*
G01Y229803D02*
Y231181D01*
G01Y224803D02*
Y226181D01*
G01Y219803D02*
Y221181D01*
G01X1661004D02*
Y219803D01*
G01Y226181D02*
Y224803D01*
G01Y231181D02*
Y229803D01*
G01Y236181D02*
Y234803D01*
G01Y241181D02*
Y239803D01*
G01Y246181D02*
Y244803D01*
G01Y251181D02*
Y249803D01*
G01Y256181D02*
Y254803D01*
G01Y261181D02*
Y259803D01*
G01X1659823Y226156D02*
Y226299D01*
G01Y221156D02*
Y221299D01*
G01Y236156D02*
Y236299D01*
G01Y231156D02*
Y231299D01*
G01Y246156D02*
Y246299D01*
G01Y241156D02*
Y241299D01*
G01Y256156D02*
Y256299D01*
G01Y251156D02*
Y251299D01*
G01Y259311D02*
Y261673D01*
G01Y254311D02*
Y256673D01*
G01Y249311D02*
Y251673D01*
G01Y244311D02*
Y246673D01*
G01Y239311D02*
Y241673D01*
G01Y234311D02*
Y236673D01*
G01Y229311D02*
Y231673D01*
G01Y224311D02*
Y226673D01*
G01Y219311D02*
Y221673D01*
G01X1658839D02*
Y219311D01*
G01Y226673D02*
Y224311D01*
G01Y231673D02*
Y229311D01*
G01Y236673D02*
Y234311D01*
G01Y241673D02*
Y239311D01*
G01Y246673D02*
Y244311D01*
G01Y251673D02*
Y249311D01*
G01Y256673D02*
Y254311D01*
G01Y261673D02*
Y259311D01*
G01X1656496Y295492D02*
Y219035D01*
G01X1655315Y294311D02*
Y217854D01*
G01X1646850Y299232D02*
Y220197D01*
G01X1646398Y216693D02*
Y218189D01*
G01Y213543D02*
Y215039D01*
G01X1646358Y216839D02*
Y216693D01*
G01Y213690D02*
Y213543D01*
G01Y215040D02*
Y214893D01*
G01Y218189D02*
Y218043D01*
G01X1645453D02*
Y218190D01*
G01Y216692D02*
Y216839D01*
G01Y213543D02*
Y213690D01*
G01Y214893D02*
Y215040D01*
G01X1645413Y215039D02*
Y213543D01*
G01Y218189D02*
Y216693D01*
G01X1644232Y218031D02*
Y216850D01*
G01Y214882D02*
Y213701D01*
G01X1640472Y216850D02*
Y218031D01*
G01Y213701D02*
Y214882D01*
G01X1646398Y216876D02*
X1646397Y216887D01*
G01X1646398Y213727D02*
X1646397Y213738D01*
G01X1646357Y213701D02*
X1646360Y213690D01*
G01X1645300Y216890D02*
X1645412Y216881D01*
G01X1664173Y259803D02*
X1658840D01*
G01X1658839Y259311D02*
X1659823D01*
G01Y256673D02*
X1658839D01*
G01X1659823Y259607D02*
X1658839Y259606D01*
G01X1658840Y256181D02*
X1664173D01*
G01Y256142D02*
X1659825D01*
G01X1664173Y254803D02*
X1658840D01*
G01X1658839Y254311D02*
X1659823D01*
G01Y251673D02*
X1658839D01*
G01X1658840Y251181D02*
X1664173D01*
G01Y251142D02*
X1659825D01*
G01X1664173Y249803D02*
X1658840D01*
G01X1658839Y249311D02*
X1659823D01*
G01Y246673D02*
X1658839D01*
G01X1658840Y246181D02*
X1664173D01*
G01Y246142D02*
X1659825D01*
G01X1664173Y244803D02*
X1658840D01*
G01X1658839Y244311D02*
X1659823D01*
G01Y241673D02*
X1658839D01*
G01X1658840Y241181D02*
X1664173D01*
G01Y241142D02*
X1659825D01*
G01X1664173Y239803D02*
X1658840D01*
G01X1658839Y239311D02*
X1659823D01*
G01Y236673D02*
X1658839D01*
G01X1658840Y236181D02*
X1664173D01*
G01Y236142D02*
X1659825D01*
G01X1664173Y234803D02*
X1658840D01*
G01X1658839Y234311D02*
X1659823D01*
G01Y231673D02*
X1658839D01*
G01X1658840Y231181D02*
X1664173D01*
G01Y231142D02*
X1659825D01*
G01X1664173Y229803D02*
X1658840D01*
G01X1658839Y229311D02*
X1659823D01*
G01Y226673D02*
X1658839D01*
G01X1658840Y226181D02*
X1664173D01*
G01Y226142D02*
X1659825D01*
G01X1664173Y224803D02*
X1658840D01*
G01X1658839Y224311D02*
X1659823D01*
G01Y221673D02*
X1658839D01*
G01X1658840Y221181D02*
X1664173D01*
G01Y221142D02*
X1659825D01*
G01X1646850Y220197D02*
X1643504D01*
G01X1664173Y219803D02*
X1658840D01*
G01X1658839Y219311D02*
X1659823D01*
G01X1656496Y219035D02*
X1660433D01*
G01X1646358Y218228D02*
X1645453D01*
G01X1646398Y218189D02*
X1645413D01*
G01X1646357Y218031D02*
X1640472D01*
G01Y217992D02*
X1646396D01*
G01X1655315Y217854D02*
X1659252D01*
G01X1646396Y216890D02*
X1640472D01*
G01X1646357Y216850D02*
X1640472D01*
G01X1645413Y216693D02*
X1646398D01*
G01X1645453Y216654D02*
X1646358D01*
G01Y215079D02*
X1645453D01*
G01X1646398Y215039D02*
X1645413D01*
G01X1646357Y214882D02*
X1640472D01*
G01Y214843D02*
X1646396D01*
G01Y213740D02*
X1640472D01*
G01X1646357Y213701D02*
X1640472D01*
G01X1645413Y213543D02*
X1646398D01*
G01X1645453Y213504D02*
X1646358D01*
G01X1658839Y256377D02*
X1659794Y256378D01*
G01X1659823Y254607D02*
X1658839Y254606D01*
G01Y251377D02*
X1659794Y251378D01*
G01X1659823Y249607D02*
X1658839Y249606D01*
G01Y246377D02*
X1659794Y246378D01*
G01X1659823Y244607D02*
X1658839Y244606D01*
G01Y241377D02*
X1659794Y241378D01*
G01X1659823Y239607D02*
X1658839Y239606D01*
G01Y236377D02*
X1659794Y236378D01*
G01X1659823Y234607D02*
X1658839Y234606D01*
G01Y231377D02*
X1659794Y231378D01*
G01X1659823Y229607D02*
X1658839Y229606D01*
G01Y226377D02*
X1659794Y226378D01*
G01X1659823Y224607D02*
X1658839Y224606D01*
G01Y221377D02*
X1659794Y221378D01*
G01X1659823Y219607D02*
X1658839Y219606D01*
G01X1659810Y261173D02*
X1659821Y261157D01*
G01X1659786Y261181D02*
X1659810Y261173D01*
G01Y266173D02*
X1659821Y266157D01*
G01X1659786Y266181D02*
X1659810Y266173D01*
G01Y271173D02*
X1659821Y271157D01*
G01X1659786Y271181D02*
X1659810Y271173D01*
G01Y276173D02*
X1659821Y276157D01*
G01X1659786Y276181D02*
X1659810Y276173D01*
G01Y281173D02*
X1659821Y281157D01*
G01X1659786Y281181D02*
X1659810Y281173D01*
G01Y286173D02*
X1659821Y286157D01*
G01X1659786Y286181D02*
X1659810Y286173D01*
G01Y291173D02*
X1659821Y291157D01*
G01X1659786Y291181D02*
X1659810Y291173D01*
G01X1659823Y261148D02*
Y261156D01*
G01X1659824Y261144D02*
X1659823Y261148D01*
G01X1659825Y261142D02*
X1659824Y261144D01*
G01X1659823Y266148D02*
Y266156D01*
G01X1659824Y266144D02*
X1659823Y266148D01*
G01X1659825Y266142D02*
X1659824Y266144D01*
G01X1659823Y271148D02*
Y271156D01*
G01X1659824Y271144D02*
X1659823Y271148D01*
G01X1659825Y271142D02*
X1659824Y271144D01*
G01X1659823Y276148D02*
Y276156D01*
G01X1659824Y276144D02*
X1659823Y276148D01*
G01X1659825Y276142D02*
X1659824Y276144D01*
G01X1659823Y281148D02*
Y281156D01*
G01X1659824Y281144D02*
X1659823Y281148D01*
G01X1659825Y281142D02*
X1659824Y281144D01*
G01X1659823Y286148D02*
Y286156D01*
G01X1659824Y286144D02*
X1659823Y286148D01*
G01X1659825Y286142D02*
X1659824Y286144D01*
G01X1659823Y291148D02*
Y291156D01*
G01X1659824Y291144D02*
X1659823Y291148D01*
G01X1659825Y291142D02*
X1659824Y291144D01*
G01X1658839Y261189D02*
Y261198D01*
G01Y261183D02*
Y261189D01*
G01X1658840Y261181D02*
X1658839Y261183D01*
G01Y266189D02*
Y266198D01*
G01Y266183D02*
Y266189D01*
G01X1658840Y266181D02*
X1658839Y266183D01*
G01Y271189D02*
Y271198D01*
G01Y271183D02*
Y271189D01*
G01X1658840Y271181D02*
X1658839Y271183D01*
G01Y276189D02*
Y276198D01*
G01Y276183D02*
Y276189D01*
G01X1658840Y276181D02*
X1658839Y276183D01*
G01Y281189D02*
Y281198D01*
G01Y281183D02*
Y281189D01*
G01X1658840Y281181D02*
X1658839Y281183D01*
G01Y286189D02*
Y286198D01*
G01Y286183D02*
Y286189D01*
G01X1658840Y286181D02*
X1658839Y286183D01*
G01Y291189D02*
Y291198D01*
G01Y291183D02*
Y291189D01*
G01X1658840Y291181D02*
X1658839Y291183D01*
G01X1659815Y261325D02*
X1659823Y261299D01*
G01X1659805Y261352D02*
X1659815Y261325D01*
G01X1659794Y261378D02*
X1659805Y261352D01*
G01X1659815Y266325D02*
X1659823Y266299D01*
G01X1659805Y266352D02*
X1659815Y266325D01*
G01X1659794Y266378D02*
X1659805Y266352D01*
G01X1659815Y271325D02*
X1659823Y271299D01*
G01X1659805Y271352D02*
X1659815Y271325D01*
G01X1659794Y271378D02*
X1659805Y271352D01*
G01X1659815Y276325D02*
X1659823Y276299D01*
G01X1659805Y276352D02*
X1659815Y276325D01*
G01X1659794Y276378D02*
X1659805Y276352D01*
G01X1659815Y281325D02*
X1659823Y281299D01*
G01X1659805Y281352D02*
X1659815Y281325D01*
G01X1659794Y281378D02*
X1659805Y281352D01*
G01X1659815Y286325D02*
X1659823Y286299D01*
G01X1659805Y286352D02*
X1659815Y286325D01*
G01X1659794Y286378D02*
X1659805Y286352D01*
G01X1659815Y291325D02*
X1659823Y291299D01*
G01X1659805Y291352D02*
X1659815Y291325D01*
G01X1659794Y291378D02*
X1659805Y291352D01*
G01X1659806Y261176D02*
X1659786Y261181D01*
G01X1659820Y261162D02*
X1659806Y261176D01*
G01X1659825Y261142D02*
X1659820Y261162D01*
G01X1659806Y266176D02*
X1659786Y266181D01*
G01X1659820Y266162D02*
X1659806Y266176D01*
G01X1659825Y266142D02*
X1659820Y266162D01*
G01X1659806Y271176D02*
X1659786Y271181D01*
G01X1659820Y271162D02*
X1659806Y271176D01*
G01X1659825Y271142D02*
X1659820Y271162D01*
G01X1659806Y276176D02*
X1659786Y276181D01*
G01X1659820Y276162D02*
X1659806Y276176D01*
G01X1659825Y276142D02*
X1659820Y276162D01*
G01X1659806Y281176D02*
X1659786Y281181D01*
G01X1659820Y281162D02*
X1659806Y281176D01*
G01X1659825Y281142D02*
X1659820Y281162D01*
G01X1659806Y286176D02*
X1659786Y286181D01*
G01X1659820Y286162D02*
X1659806Y286176D01*
G01X1659825Y286142D02*
X1659820Y286162D01*
G01X1659806Y291176D02*
X1659786Y291181D01*
G01X1659820Y291162D02*
X1659806Y291176D01*
G01X1659825Y291142D02*
X1659820Y291162D01*
G01X1659790Y261279D02*
X1659794Y261378D01*
G01X1659784Y261207D02*
X1659790Y261279D01*
G01X1659786Y261181D02*
X1659784Y261207D01*
G01X1659790Y266279D02*
X1659794Y266378D01*
G01X1659784Y266207D02*
X1659790Y266279D01*
G01X1659786Y266181D02*
X1659784Y266207D01*
G01X1659790Y271279D02*
X1659794Y271378D01*
G01X1659784Y271207D02*
X1659790Y271279D01*
G01X1659786Y271181D02*
X1659784Y271207D01*
G01X1659790Y276279D02*
X1659794Y276378D01*
G01X1659784Y276207D02*
X1659790Y276279D01*
G01X1659786Y276181D02*
X1659784Y276207D01*
G01X1659790Y281279D02*
X1659794Y281378D01*
G01X1659784Y281207D02*
X1659790Y281279D01*
G01X1659786Y281181D02*
X1659784Y281207D01*
G01X1659790Y286279D02*
X1659794Y286378D01*
G01X1659784Y286207D02*
X1659790Y286279D01*
G01X1659786Y286181D02*
X1659784Y286207D01*
G01X1659790Y291279D02*
X1659794Y291378D01*
G01X1659784Y291207D02*
X1659790Y291279D01*
G01X1659786Y291181D02*
X1659784Y291207D01*
G01X1658839Y289802D02*
X1658840Y289803D01*
G01X1658839Y289796D02*
Y289802D01*
G01Y289787D02*
Y289796D01*
G01Y284802D02*
X1658840Y284803D01*
G01X1658839Y284796D02*
Y284802D01*
G01Y284787D02*
Y284796D01*
G01Y279802D02*
X1658840Y279803D01*
G01X1658839Y279796D02*
Y279802D01*
G01Y279787D02*
Y279796D01*
G01Y274802D02*
X1658840Y274803D01*
G01X1658839Y274796D02*
Y274802D01*
G01Y274787D02*
Y274796D01*
G01Y269802D02*
X1658840Y269803D01*
G01X1658839Y269796D02*
Y269802D01*
G01Y269787D02*
Y269796D01*
G01Y264802D02*
X1658840Y264803D01*
G01X1658839Y264796D02*
Y264802D01*
G01Y264787D02*
Y264796D01*
G01X1659823Y289796D02*
Y289787D01*
G01X1659824Y289802D02*
X1659823Y289796D01*
G01X1659826Y289803D02*
X1659824Y289802D01*
G01X1659823Y284796D02*
Y284787D01*
G01X1659824Y284802D02*
X1659823Y284796D01*
G01X1659826Y284803D02*
X1659824Y284802D01*
G01X1659823Y279796D02*
Y279787D01*
G01X1659824Y279802D02*
X1659823Y279796D01*
G01X1659826Y279803D02*
X1659824Y279802D01*
G01X1659823Y274796D02*
Y274787D01*
G01X1659824Y274802D02*
X1659823Y274796D01*
G01X1659826Y274803D02*
X1659824Y274802D01*
G01X1659823Y269796D02*
Y269787D01*
G01X1659824Y269802D02*
X1659823Y269796D01*
G01X1659826Y269803D02*
X1659824Y269802D01*
G01X1659823Y264796D02*
Y264787D01*
G01X1659824Y264802D02*
X1659823Y264796D01*
G01X1659826Y264803D02*
X1659824Y264802D01*
G01X1651772Y307579D02*
G03X1650591Y306398I0J-1181D01*
G01X1658071D02*
G03X1656890Y307579I-1181J0D01*
G01X1656220Y302303D02*
G03I-1889J0D01*
G01X1656693D02*
G03I-2362J0D01*
G01X1665157Y300335D02*
X1661811Y296988D01*
G01X1655315Y294311D02*
X1656496Y295492D01*
G01X1651846Y299232D02*
X1653150Y301201D01*
G01X1657822Y307123D02*
X1655512Y302894D01*
G01X1659823Y261155D02*
Y261164D01*
G01Y266155D02*
Y266164D01*
G01Y271155D02*
Y271164D01*
G01Y276155D02*
Y276164D01*
G01Y281155D02*
Y281164D01*
G01Y286155D02*
Y286164D01*
G01Y291155D02*
Y291164D01*
G01X1665157Y300335D02*
Y316083D01*
G01X1664173Y289803D02*
Y291181D01*
G01Y284803D02*
Y286181D01*
G01Y279803D02*
Y281181D01*
G01Y274803D02*
Y276181D01*
G01Y269803D02*
Y271181D01*
G01Y264803D02*
Y266181D01*
G01X1661004D02*
Y264803D01*
G01Y271181D02*
Y269803D01*
G01Y276181D02*
Y274803D01*
G01Y281181D02*
Y279803D01*
G01Y286181D02*
Y284803D01*
G01Y291181D02*
Y289803D01*
G01X1659823Y266156D02*
Y266299D01*
G01Y261156D02*
Y261299D01*
G01Y276156D02*
Y276299D01*
G01Y271156D02*
Y271299D01*
G01Y286156D02*
Y286299D01*
G01Y281156D02*
Y281299D01*
G01Y291156D02*
Y291299D01*
G01Y289311D02*
Y291673D01*
G01Y284311D02*
Y286673D01*
G01Y279311D02*
Y281673D01*
G01Y274311D02*
Y276673D01*
G01Y269311D02*
Y271673D01*
G01Y264311D02*
Y266673D01*
G01X1658839D02*
Y264311D01*
G01Y271673D02*
Y269311D01*
G01Y276673D02*
Y274311D01*
G01Y281673D02*
Y279311D01*
G01Y286673D02*
Y284311D01*
G01Y291673D02*
Y289311D01*
G01X1658071Y306398D02*
Y297854D01*
G01X1655512Y302894D02*
Y301201D01*
G01X1653150D02*
Y302894D01*
G01X1650591Y297854D02*
Y306398D01*
G01X1643504Y316083D02*
Y300335D01*
G01X1653150Y302894D02*
X1650839Y307123D01*
G01X1655512Y301201D02*
X1656815Y299232D01*
G01X1648622Y295492D02*
X1649803Y294311D01*
G01X1643504Y300335D02*
X1646850Y296988D01*
G01X1665157Y307618D02*
X1643504D01*
G01X1651772Y307579D02*
X1656890D01*
G01X1653150Y302894D02*
X1655512D01*
G01X1653150Y301201D02*
X1655512D01*
G01X1646850Y299232D02*
X1661220D01*
G01X1646850Y297854D02*
X1650591D01*
G01X1661220D02*
X1658071D01*
G01X1646850Y296988D02*
X1661811D01*
G01X1648622Y295492D02*
X1656496D01*
G01X1649803Y294311D02*
X1655315D01*
G01X1659823Y291673D02*
X1658839D01*
G01X1658840Y291181D02*
X1664173D01*
G01Y291142D02*
X1659825D01*
G01X1664173Y289803D02*
X1658840D01*
G01X1658839Y289311D02*
X1659823D01*
G01Y286673D02*
X1658839D01*
G01X1658840Y286181D02*
X1664173D01*
G01Y286142D02*
X1659825D01*
G01X1664173Y284803D02*
X1658840D01*
G01X1658839Y284311D02*
X1659823D01*
G01Y281673D02*
X1658839D01*
G01X1658840Y281181D02*
X1664173D01*
G01Y281142D02*
X1659825D01*
G01X1664173Y279803D02*
X1658840D01*
G01X1658839Y279311D02*
X1659823D01*
G01Y276673D02*
X1658839D01*
G01X1658840Y276181D02*
X1664173D01*
G01Y276142D02*
X1659825D01*
G01X1664173Y274803D02*
X1658840D01*
G01X1658839Y274311D02*
X1659823D01*
G01Y271673D02*
X1658839D01*
G01X1658840Y271181D02*
X1664173D01*
G01Y271142D02*
X1659825D01*
G01X1664173Y269803D02*
X1658840D01*
G01X1658839Y269311D02*
X1659823D01*
G01Y266673D02*
X1658839D01*
G01X1658840Y266181D02*
X1664173D01*
G01Y266142D02*
X1659825D01*
G01X1664173Y264803D02*
X1658840D01*
G01X1658839Y264311D02*
X1659823D01*
G01Y261673D02*
X1658839D01*
G01X1658840Y261181D02*
X1664173D01*
G01Y261142D02*
X1659825D01*
G01X1658839Y291377D02*
X1659794Y291378D01*
G01X1659823Y289607D02*
X1658839Y289606D01*
G01Y286377D02*
X1659794Y286378D01*
G01X1659823Y284607D02*
X1658839Y284606D01*
G01Y281377D02*
X1659794Y281378D01*
G01X1659823Y279607D02*
X1658839Y279606D01*
G01Y276377D02*
X1659794Y276378D01*
G01X1659823Y274607D02*
X1658839Y274606D01*
G01Y271377D02*
X1659794Y271378D01*
G01X1659823Y269607D02*
X1658839Y269606D01*
G01Y266377D02*
X1659794Y266378D01*
G01X1659823Y264607D02*
X1658839Y264606D01*
G01Y261377D02*
X1659794Y261378D01*
G01X1658268Y316673D02*
G03X1657677Y317264I-591J0D01*
G01X1650984D02*
G03X1650394Y316673I0J-590D01*
G01X1653150Y315492D02*
G03Y313524I0J-984D01*
G01X1655512D02*
G03Y315492I0J984D01*
G01X1665157Y316083D02*
G03X1663189Y318051I-1968J0D01*
G01X1645472D02*
G03X1643504Y316083I0J-1968D01*
G01X1658268Y310571D02*
Y316673D01*
G01X1650394Y310571D02*
Y316673D01*
G01X1663189Y318051D02*
X1645472D01*
G01X1657677Y317264D02*
X1650984D01*
G01X1655512Y315492D02*
X1653150D01*
G01Y313524D02*
X1655512D01*
G01X1658268Y312146D02*
X1650394D01*
G01Y310571D02*
X1658268D01*
G01X1650394Y592067D02*
G03X1650984Y591476I591J0D01*
G01X1657677D02*
G03X1658268Y592067I0J591D01*
G01X1655512Y593248D02*
G03Y595217I0J985D01*
G01X1653150D02*
G03Y593248I0J-985D01*
G01X1643504Y592657D02*
G03X1645472Y590689I1969J1D01*
G01X1663189D02*
G03X1665157Y592657I0J1968D01*
G01D02*
Y608406D01*
G01X1658268Y598169D02*
Y592067D01*
G01X1650394Y598169D02*
Y592067D01*
G01X1643504Y608406D02*
Y592657D01*
G01X1658268Y598169D02*
X1650394D01*
G01Y596594D02*
X1658268D01*
G01X1655512Y595217D02*
X1653150D01*
G01Y593248D02*
X1655512D01*
G01X1657677Y591476D02*
X1650984D01*
G01X1663189Y590689D02*
X1645472D01*
G01X1659810Y618929D02*
X1659821Y618913D01*
G01X1659786Y618937D02*
X1659810Y618929D01*
G01Y623929D02*
X1659821Y623913D01*
G01X1659786Y623937D02*
X1659810Y623929D01*
G01Y628929D02*
X1659821Y628913D01*
G01X1659786Y628937D02*
X1659810Y628929D01*
G01Y633929D02*
X1659821Y633913D01*
G01X1659786Y633937D02*
X1659810Y633929D01*
G01Y638929D02*
X1659821Y638913D01*
G01X1659786Y638937D02*
X1659810Y638929D01*
G01Y643929D02*
X1659821Y643913D01*
G01X1659786Y643937D02*
X1659810Y643929D01*
G01X1659823Y618904D02*
Y618911D01*
G01X1659824Y618900D02*
X1659823Y618904D01*
G01X1659825Y618898D02*
X1659824Y618900D01*
G01X1659823Y623904D02*
Y623911D01*
G01X1659824Y623900D02*
X1659823Y623904D01*
G01X1659825Y623898D02*
X1659824Y623900D01*
G01X1659823Y628904D02*
Y628911D01*
G01X1659824Y628900D02*
X1659823Y628904D01*
G01X1659825Y628898D02*
X1659824Y628900D01*
G01X1659823Y633904D02*
Y633911D01*
G01X1659824Y633900D02*
X1659823Y633904D01*
G01X1659825Y633898D02*
X1659824Y633900D01*
G01X1659823Y638904D02*
Y638911D01*
G01X1659824Y638900D02*
X1659823Y638904D01*
G01X1659825Y638898D02*
X1659824Y638900D01*
G01X1659823Y643904D02*
Y643911D01*
G01X1659824Y643900D02*
X1659823Y643904D01*
G01X1659825Y643898D02*
X1659824Y643900D01*
G01X1659823Y647552D02*
Y647543D01*
G01X1659824Y647557D02*
X1659823Y647552D01*
G01X1659826Y647559D02*
X1659824Y647557D01*
G01X1659823Y642552D02*
Y642543D01*
G01X1659824Y642557D02*
X1659823Y642552D01*
G01X1659826Y642559D02*
X1659824Y642557D01*
G01X1659823Y637552D02*
Y637543D01*
G01X1659824Y637557D02*
X1659823Y637552D01*
G01X1659826Y637559D02*
X1659824Y637557D01*
G01X1659823Y632552D02*
Y632543D01*
G01X1659824Y632557D02*
X1659823Y632552D01*
G01X1659826Y632559D02*
X1659824Y632557D01*
G01X1659823Y627552D02*
Y627543D01*
G01X1659824Y627557D02*
X1659823Y627552D01*
G01X1659826Y627559D02*
X1659824Y627557D01*
G01X1659823Y622552D02*
Y622543D01*
G01X1659824Y622557D02*
X1659823Y622552D01*
G01X1659826Y622559D02*
X1659824Y622557D01*
G01X1658839Y618944D02*
Y618954D01*
G01Y618939D02*
Y618944D01*
G01X1658840Y618937D02*
X1658839Y618939D01*
G01Y623944D02*
Y623954D01*
G01Y623939D02*
Y623944D01*
G01X1658840Y623937D02*
X1658839Y623939D01*
G01Y628944D02*
Y628954D01*
G01Y628939D02*
Y628944D01*
G01X1658840Y628937D02*
X1658839Y628939D01*
G01Y633944D02*
Y633954D01*
G01Y633939D02*
Y633944D01*
G01X1658840Y633937D02*
X1658839Y633939D01*
G01Y638944D02*
Y638954D01*
G01Y638939D02*
Y638944D01*
G01X1658840Y638937D02*
X1658839Y638939D01*
G01Y643944D02*
Y643954D01*
G01Y643939D02*
Y643944D01*
G01X1658840Y643937D02*
X1658839Y643939D01*
G01X1659815Y619081D02*
X1659823Y619055D01*
G01X1659805Y619107D02*
X1659815Y619081D01*
G01X1659794Y619134D02*
X1659805Y619107D01*
G01X1659815Y624081D02*
X1659823Y624055D01*
G01X1659805Y624107D02*
X1659815Y624081D01*
G01X1659794Y624134D02*
X1659805Y624107D01*
G01X1659815Y629081D02*
X1659823Y629055D01*
G01X1659805Y629107D02*
X1659815Y629081D01*
G01X1659794Y629134D02*
X1659805Y629107D01*
G01X1659815Y634081D02*
X1659823Y634055D01*
G01X1659805Y634107D02*
X1659815Y634081D01*
G01X1659794Y634134D02*
X1659805Y634107D01*
G01X1659815Y639081D02*
X1659823Y639055D01*
G01X1659805Y639107D02*
X1659815Y639081D01*
G01X1659794Y639134D02*
X1659805Y639107D01*
G01X1659815Y644081D02*
X1659823Y644055D01*
G01X1659805Y644107D02*
X1659815Y644081D01*
G01X1659794Y644134D02*
X1659805Y644107D01*
G01X1659806Y618932D02*
X1659786Y618937D01*
G01X1659820Y618918D02*
X1659806Y618932D01*
G01X1659825Y618898D02*
X1659820Y618918D01*
G01X1659806Y623932D02*
X1659786Y623937D01*
G01X1659820Y623918D02*
X1659806Y623932D01*
G01X1659825Y623898D02*
X1659820Y623918D01*
G01X1659806Y628932D02*
X1659786Y628937D01*
G01X1659820Y628918D02*
X1659806Y628932D01*
G01X1659825Y628898D02*
X1659820Y628918D01*
G01X1659806Y633932D02*
X1659786Y633937D01*
G01X1659820Y633918D02*
X1659806Y633932D01*
G01X1659825Y633898D02*
X1659820Y633918D01*
G01X1659806Y638932D02*
X1659786Y638937D01*
G01X1659820Y638918D02*
X1659806Y638932D01*
G01X1659825Y638898D02*
X1659820Y638918D01*
G01X1659806Y643932D02*
X1659786Y643937D01*
G01X1659820Y643918D02*
X1659806Y643932D01*
G01X1659825Y643898D02*
X1659820Y643918D01*
G01X1659790Y619035D02*
X1659794Y619134D01*
G01X1659784Y618963D02*
X1659790Y619035D01*
G01X1659786Y618937D02*
X1659784Y618963D01*
G01X1659790Y624035D02*
X1659794Y624134D01*
G01X1659784Y623963D02*
X1659790Y624035D01*
G01X1659786Y623937D02*
X1659784Y623963D01*
G01X1659790Y629035D02*
X1659794Y629134D01*
G01X1659784Y628963D02*
X1659790Y629035D01*
G01X1659786Y628937D02*
X1659784Y628963D01*
G01X1659790Y634035D02*
X1659794Y634134D01*
G01X1659784Y633963D02*
X1659790Y634035D01*
G01X1659786Y633937D02*
X1659784Y633963D01*
G01X1659790Y639035D02*
X1659794Y639134D01*
G01X1659784Y638963D02*
X1659790Y639035D01*
G01X1659786Y638937D02*
X1659784Y638963D01*
G01X1659790Y644035D02*
X1659794Y644134D01*
G01X1659784Y643963D02*
X1659790Y644035D01*
G01X1659786Y643937D02*
X1659784Y643963D01*
G01X1658839Y647557D02*
X1658840Y647559D01*
G01X1658839Y647552D02*
Y647557D01*
G01Y647543D02*
Y647552D01*
G01Y642557D02*
X1658840Y642559D01*
G01X1658839Y642552D02*
Y642557D01*
G01Y642543D02*
Y642552D01*
G01Y637557D02*
X1658840Y637559D01*
G01X1658839Y637552D02*
Y637557D01*
G01Y637543D02*
Y637552D01*
G01Y632557D02*
X1658840Y632559D01*
G01X1658839Y632552D02*
Y632557D01*
G01Y632543D02*
Y632552D01*
G01Y627557D02*
X1658840Y627559D01*
G01X1658839Y627552D02*
Y627557D01*
G01Y627543D02*
Y627552D01*
G01Y622557D02*
X1658840Y622559D01*
G01X1658839Y622552D02*
Y622557D01*
G01Y622543D02*
Y622552D01*
G01Y617557D02*
X1658840Y617559D01*
G01X1658839Y617552D02*
Y617557D01*
G01Y617543D02*
Y617552D01*
G01X1659823D02*
Y617543D01*
G01X1659824Y617557D02*
X1659823Y617552D01*
G01X1659826Y617559D02*
X1659824Y617557D01*
G01X1655433Y606437D02*
G03I-1102J0D01*
G01X1656890Y601161D02*
G03X1658071Y602343I0J1181D01*
G01X1650591D02*
G03X1651772Y601161I1181J-1D01*
G01X1655906Y606437D02*
G03I-1575J0D01*
G01X1656815Y609508D02*
X1655512Y607539D01*
G01X1650839Y601617D02*
X1653150Y605846D01*
G01X1659823Y618911D02*
Y618920D01*
G01Y623911D02*
Y623920D01*
G01Y628911D02*
Y628920D01*
G01Y633911D02*
Y633920D01*
G01Y638911D02*
Y638920D01*
G01Y643911D02*
Y643920D01*
G01X1664173Y647559D02*
Y648937D01*
G01Y642559D02*
Y643937D01*
G01Y637559D02*
Y638937D01*
G01Y632559D02*
Y633937D01*
G01Y627559D02*
Y628937D01*
G01Y622559D02*
Y623937D01*
G01Y617559D02*
Y618937D01*
G01X1661811Y749744D02*
Y611752D01*
G01X1661220Y751988D02*
Y609508D01*
G01X1661004Y618937D02*
Y617559D01*
G01Y623937D02*
Y622559D01*
G01Y628937D02*
Y627559D01*
G01Y633937D02*
Y632559D01*
G01Y638937D02*
Y637559D01*
G01Y643937D02*
Y642559D01*
G01Y648937D02*
Y647559D01*
G01X1659823Y647067D02*
Y649429D01*
G01Y642067D02*
Y644429D01*
G01Y637067D02*
Y639429D01*
G01Y632067D02*
Y634429D01*
G01Y627067D02*
Y629429D01*
G01Y622067D02*
Y624429D01*
G01Y617067D02*
Y619429D01*
G01X1658839D02*
Y617067D01*
G01Y624429D02*
Y622067D01*
G01Y629429D02*
Y627067D01*
G01Y634429D02*
Y632067D01*
G01Y639429D02*
Y637067D01*
G01Y644429D02*
Y642067D01*
G01Y649429D02*
Y647067D01*
G01X1658071Y610886D02*
Y602343D01*
G01X1656496Y649705D02*
Y613248D01*
G01X1655512Y607539D02*
Y605846D01*
G01X1655315Y650886D02*
Y614429D01*
G01X1653150Y605846D02*
Y607539D01*
G01X1650591Y602343D02*
Y610886D01*
G01X1649803Y614429D02*
Y747067D01*
G01X1648622Y613248D02*
Y748248D01*
G01X1646850Y648543D02*
Y609508D01*
G01X1649803Y614429D02*
X1648622Y613248D01*
G01X1646850Y611752D02*
X1643504Y608406D01*
G01X1655512Y605846D02*
X1657822Y601617D01*
G01X1653150Y607539D02*
X1651846Y609508D01*
G01X1661811Y611752D02*
X1665157Y608406D01*
G01X1655315Y614429D02*
X1656496Y613248D01*
G01X1664173Y647559D02*
X1658840D01*
G01X1658839Y647067D02*
X1659823D01*
G01Y644429D02*
X1658839D01*
G01X1658840Y643937D02*
X1664173D01*
G01Y643898D02*
X1659825D01*
G01X1664173Y642559D02*
X1658840D01*
G01X1658839Y642067D02*
X1659823D01*
G01Y639429D02*
X1658839D01*
G01X1658840Y638937D02*
X1664173D01*
G01Y638898D02*
X1659825D01*
G01X1664173Y637559D02*
X1658840D01*
G01X1658839Y637067D02*
X1659823D01*
G01Y634429D02*
X1658839D01*
G01X1658840Y633937D02*
X1664173D01*
G01Y633898D02*
X1659825D01*
G01X1664173Y632559D02*
X1658840D01*
G01X1658839Y632067D02*
X1659823D01*
G01Y629429D02*
X1658839D01*
G01X1658840Y628937D02*
X1664173D01*
G01Y628898D02*
X1659825D01*
G01X1664173Y627559D02*
X1658840D01*
G01X1658839Y627067D02*
X1659823D01*
G01Y624429D02*
X1658839D01*
G01X1658840Y623937D02*
X1664173D01*
G01Y623898D02*
X1659825D01*
G01X1664173Y622559D02*
X1658840D01*
G01X1658839Y622067D02*
X1659823D01*
G01Y619429D02*
X1658839D01*
G01X1658840Y618937D02*
X1664173D01*
G01Y618898D02*
X1659825D01*
G01X1664173Y617559D02*
X1658840D01*
G01X1658839Y617067D02*
X1659823D01*
G01Y647363D02*
X1658839Y647362D01*
G01Y644133D02*
X1659794Y644134D01*
G01X1659823Y642363D02*
X1658839Y642362D01*
G01Y639133D02*
X1659794Y639134D01*
G01X1659823Y637363D02*
X1658839Y637362D01*
G01Y634133D02*
X1659794Y634134D01*
G01X1659823Y632363D02*
X1658839Y632362D01*
G01Y629133D02*
X1659794Y629134D01*
G01X1659823Y627363D02*
X1658839Y627362D01*
G01Y624133D02*
X1659794Y624134D01*
G01X1659823Y622363D02*
X1658839Y622362D01*
G01Y619133D02*
X1659794Y619134D01*
G01X1659823Y617363D02*
X1658839Y617362D01*
G01X1655315Y614429D02*
X1649803D01*
G01X1656496Y613248D02*
X1648622D01*
G01X1661811Y611752D02*
X1646850D01*
G01X1658071Y610886D02*
X1661220D01*
G01X1650591D02*
X1646850D01*
G01Y609508D02*
X1661220D01*
G01X1655512Y607539D02*
X1653150D01*
G01X1655512Y605846D02*
X1653150D01*
G01X1656890Y601161D02*
X1651772D01*
G01X1665157Y601122D02*
X1643504D01*
G01X1645416Y651870D02*
X1645411Y651850D01*
G01X1645431Y651885D02*
X1645416Y651870D01*
G01X1645450Y651890D02*
X1645431Y651885D01*
G01X1645416Y655020D02*
X1645411Y655000D01*
G01X1645431Y655034D02*
X1645416Y655020D01*
G01X1645450Y655039D02*
X1645431Y655034D01*
G01X1645416Y658169D02*
X1645411Y658150D01*
G01X1645431Y658184D02*
X1645416Y658169D01*
G01X1645450Y658189D02*
X1645431Y658184D01*
G01X1645416Y661319D02*
X1645411Y661299D01*
G01X1645431Y661333D02*
X1645416Y661319D01*
G01X1645450Y661339D02*
X1645431Y661333D01*
G01X1645416Y664469D02*
X1645411Y664449D01*
G01X1645431Y664483D02*
X1645416Y664469D01*
G01X1645450Y664488D02*
X1645431Y664483D01*
G01X1645416Y667618D02*
X1645411Y667598D01*
G01X1645431Y667633D02*
X1645416Y667618D01*
G01X1645450Y667638D02*
X1645431Y667633D01*
G01X1645416Y670768D02*
X1645411Y670748D01*
G01X1645431Y670782D02*
X1645416Y670768D01*
G01X1645450Y670787D02*
X1645431Y670782D01*
G01X1646391Y650728D02*
X1646396Y650748D01*
G01X1646376Y650714D02*
X1646391Y650728D01*
G01X1646357Y650709D02*
X1646376Y650714D01*
G01X1646391Y653878D02*
X1646396Y653898D01*
G01X1646376Y653864D02*
X1646391Y653878D01*
G01X1646357Y653858D02*
X1646376Y653864D01*
G01X1646391Y657028D02*
X1646396Y657047D01*
G01X1646376Y657013D02*
X1646391Y657028D01*
G01X1646357Y657008D02*
X1646376Y657013D01*
G01X1646391Y660177D02*
X1646396Y660197D01*
G01X1646376Y660163D02*
X1646391Y660177D01*
G01X1646357Y660157D02*
X1646376Y660163D01*
G01X1646391Y663327D02*
X1646396Y663346D01*
G01X1646376Y663313D02*
X1646391Y663327D01*
G01X1646357Y663307D02*
X1646376Y663313D01*
G01X1646391Y666476D02*
X1646396Y666496D01*
G01X1646376Y666462D02*
X1646391Y666476D01*
G01X1646357Y666457D02*
X1646376Y666462D01*
G01X1646391Y669626D02*
X1646396Y669646D01*
G01X1646376Y669612D02*
X1646391Y669626D01*
G01X1646357Y669606D02*
X1646376Y669612D01*
G01X1646397Y666475D02*
X1646398Y666483D01*
G01X1646394Y666469D02*
X1646397Y666475D01*
G01X1646391Y666462D02*
X1646394Y666469D01*
G01X1646386Y666456D02*
X1646391Y666462D01*
G01X1646380Y666452D02*
X1646386Y666456D01*
G01X1646373Y666448D02*
X1646380Y666452D01*
G01X1646366Y666446D02*
X1646373Y666448D01*
G01X1646358Y666446D02*
X1646366D01*
G01X1646375Y650701D02*
X1646378Y650703D01*
G01X1646372Y650700D02*
X1646375Y650701D01*
G01X1646369Y650699D02*
X1646372Y650700D01*
G01X1646365Y650698D02*
X1646369Y650699D01*
G01X1646362Y650698D02*
X1646365D01*
G01X1646358D02*
X1646362D01*
G01X1645436Y651898D02*
X1645433Y651896D01*
G01X1645439Y651899D02*
X1645436Y651898D01*
G01X1645442Y651900D02*
X1645439Y651899D01*
G01X1645446Y651900D02*
X1645442D01*
G01X1645449Y651901D02*
X1645446Y651900D01*
G01X1645453Y651901D02*
X1645449D01*
G01X1646375Y653851D02*
X1646378Y653852D01*
G01X1646372Y653850D02*
X1646375Y653851D01*
G01X1646369Y653848D02*
X1646372Y653850D01*
G01X1646365Y653848D02*
X1646369D01*
G01X1646362Y653847D02*
X1646365Y653848D01*
G01X1646358Y653847D02*
X1646362D01*
G01X1645436Y655047D02*
X1645433Y655046D01*
G01X1645439Y655048D02*
X1645436Y655047D01*
G01X1645442Y655050D02*
X1645439Y655048D01*
G01X1645446Y655050D02*
X1645442D01*
G01X1645449Y655051D02*
X1645446Y655050D01*
G01X1645453Y655051D02*
X1645449D01*
G01X1646375Y657000D02*
X1646378Y657002D01*
G01X1646372Y656999D02*
X1646375Y657000D01*
G01X1646369Y656998D02*
X1646372Y656999D01*
G01X1646365Y656997D02*
X1646369Y656998D01*
G01X1646362Y656997D02*
X1646365D01*
G01X1646358D02*
X1646362D01*
G01X1645436Y658197D02*
X1645433Y658195D01*
G01X1645439Y658198D02*
X1645436Y658197D01*
G01X1645442Y658199D02*
X1645439Y658198D01*
G01X1645446Y658200D02*
X1645442Y658199D01*
G01X1645449Y658200D02*
X1645446D01*
G01X1645453D02*
X1645449D01*
G01X1646375Y660150D02*
X1646378Y660152D01*
G01X1646372Y660149D02*
X1646375Y660150D01*
G01X1646369Y660148D02*
X1646372Y660149D01*
G01X1646365Y660147D02*
X1646369Y660148D01*
G01X1646362Y660146D02*
X1646365Y660147D01*
G01X1646358Y660146D02*
X1646362D01*
G01X1645436Y661346D02*
X1645433Y661345D01*
G01X1645439Y661348D02*
X1645436Y661346D01*
G01X1645442Y661349D02*
X1645439Y661348D01*
G01X1645446Y661349D02*
X1645442D01*
G01X1645449Y661350D02*
X1645446Y661349D01*
G01X1645453Y661350D02*
X1645449D01*
G01X1646375Y663300D02*
X1646378Y663301D01*
G01X1646372Y663298D02*
X1646375Y663300D01*
G01X1646369Y663297D02*
X1646372Y663298D01*
G01X1646365Y663296D02*
X1646369Y663297D01*
G01X1646362Y663296D02*
X1646365D01*
G01X1646358D02*
X1646362D01*
G01X1645436Y664496D02*
X1645433Y664494D01*
G01X1645439Y664497D02*
X1645436Y664496D01*
G01X1645442Y664498D02*
X1645439Y664497D01*
G01X1645446Y664499D02*
X1645442Y664498D01*
G01X1645449Y664500D02*
X1645446Y664499D01*
G01X1645453Y664500D02*
X1645449D01*
G01X1645436Y667646D02*
X1645433Y667644D01*
G01X1645439Y667647D02*
X1645436Y667646D01*
G01X1645442Y667648D02*
X1645439Y667647D01*
G01X1645446Y667648D02*
X1645442D01*
G01X1645449Y667649D02*
X1645446Y667648D01*
G01X1645453Y667649D02*
X1645449D01*
G01X1646375Y669599D02*
X1646378Y669600D01*
G01X1646372Y669598D02*
X1646375Y669599D01*
G01X1646369Y669596D02*
X1646372Y669598D01*
G01X1646365Y669596D02*
X1646369D01*
G01X1646362Y669595D02*
X1646365Y669596D01*
G01X1646358Y669595D02*
X1646362D01*
G01X1645436Y670795D02*
X1645433Y670794D01*
G01X1645439Y670796D02*
X1645436Y670795D01*
G01X1645442Y670798D02*
X1645439Y670796D01*
G01X1645446Y670798D02*
X1645442D01*
G01X1645449Y670799D02*
X1645446Y670798D01*
G01X1645453Y670799D02*
X1645449D01*
G01X1646388Y651888D02*
X1646392Y651883D01*
G01X1646383Y651893D02*
X1646388Y651888D01*
G01X1646378Y651896D02*
X1646383Y651893D01*
G01X1646372Y651899D02*
X1646378Y651896D01*
G01X1646365Y651901D02*
X1646372Y651899D01*
G01X1646358Y651901D02*
X1646365D01*
G01X1646388Y655038D02*
X1646392Y655033D01*
G01X1646383Y655042D02*
X1646388Y655038D01*
G01X1646378Y655046D02*
X1646383Y655042D01*
G01X1646372Y655048D02*
X1646378Y655046D01*
G01X1646365Y655050D02*
X1646372Y655048D01*
G01X1646358Y655051D02*
X1646365Y655050D01*
G01X1646388Y658187D02*
X1646392Y658182D01*
G01X1646383Y658192D02*
X1646388Y658187D01*
G01X1646378Y658196D02*
X1646383Y658192D01*
G01X1646372Y658198D02*
X1646378Y658196D01*
G01X1646365Y658200D02*
X1646372Y658198D01*
G01X1646358Y658200D02*
X1646365D01*
G01X1646388Y661337D02*
X1646392Y661332D01*
G01X1646383Y661341D02*
X1646388Y661337D01*
G01X1646378Y661345D02*
X1646383Y661341D01*
G01X1646372Y661348D02*
X1646378Y661345D01*
G01X1646365Y661350D02*
X1646372Y661348D01*
G01X1646358Y661350D02*
X1646365D01*
G01X1646388Y664487D02*
X1646392Y664481D01*
G01X1646383Y664491D02*
X1646388Y664487D01*
G01X1646378Y664495D02*
X1646383Y664491D01*
G01X1646372Y664497D02*
X1646378Y664495D01*
G01X1646365Y664499D02*
X1646372Y664497D01*
G01X1646358Y664500D02*
X1646365Y664499D01*
G01X1646388Y667636D02*
X1646392Y667631D01*
G01X1646383Y667641D02*
X1646388Y667636D01*
G01X1646378Y667644D02*
X1646383Y667641D01*
G01X1646372Y667647D02*
X1646378Y667644D01*
G01X1646365Y667649D02*
X1646372Y667647D01*
G01X1646358Y667649D02*
X1646365D01*
G01X1646388Y670786D02*
X1646392Y670781D01*
G01X1646383Y670790D02*
X1646388Y670786D01*
G01X1646378Y670794D02*
X1646383Y670790D01*
G01X1646372Y670796D02*
X1646378Y670794D01*
G01X1646365Y670798D02*
X1646372Y670796D01*
G01X1646358Y670799D02*
X1646365Y670798D01*
G01X1645414Y650727D02*
X1645413Y650735D01*
G01X1645417Y650720D02*
X1645414Y650727D01*
G01X1645420Y650714D02*
X1645417Y650720D01*
G01X1645425Y650708D02*
X1645420Y650714D01*
G01X1645431Y650704D02*
X1645425Y650708D01*
G01X1645438Y650700D02*
X1645431Y650704D01*
G01X1645445Y650698D02*
X1645438Y650700D01*
G01X1645453Y650698D02*
X1645445D01*
G01X1645414Y653877D02*
X1645413Y653884D01*
G01X1645417Y653870D02*
X1645414Y653877D01*
G01X1645420Y653864D02*
X1645417Y653870D01*
G01X1645425Y653858D02*
X1645420Y653864D01*
G01X1645431Y653853D02*
X1645425Y653858D01*
G01X1645438Y653850D02*
X1645431Y653853D01*
G01X1645445Y653848D02*
X1645438Y653850D01*
G01X1645453Y653847D02*
X1645445Y653848D01*
G01X1645414Y657026D02*
X1645413Y657034D01*
G01X1645417Y657020D02*
X1645414Y657026D01*
G01X1645420Y657013D02*
X1645417Y657020D01*
G01X1645425Y657007D02*
X1645420Y657013D01*
G01X1645431Y657003D02*
X1645425Y657007D01*
G01X1645438Y657000D02*
X1645431Y657003D01*
G01X1645445Y656998D02*
X1645438Y657000D01*
G01X1645453Y656997D02*
X1645445Y656998D01*
G01X1645414Y660176D02*
X1645413Y660183D01*
G01X1645417Y660169D02*
X1645414Y660176D01*
G01X1645420Y660163D02*
X1645417Y660169D01*
G01X1645425Y660157D02*
X1645420Y660163D01*
G01X1645431Y660152D02*
X1645425Y660157D01*
G01X1645438Y660149D02*
X1645431Y660152D01*
G01X1645445Y660147D02*
X1645438Y660149D01*
G01X1645453Y660146D02*
X1645445Y660147D01*
G01X1645414Y663326D02*
X1645413Y663333D01*
G01X1645417Y663319D02*
X1645414Y663326D01*
G01X1645420Y663313D02*
X1645417Y663319D01*
G01X1645425Y663307D02*
X1645420Y663313D01*
G01X1645431Y663302D02*
X1645425Y663307D01*
G01X1645438Y663299D02*
X1645431Y663302D01*
G01X1645445Y663297D02*
X1645438Y663299D01*
G01X1645453Y663296D02*
X1645445Y663297D01*
G01X1645414Y666475D02*
X1645413Y666483D01*
G01X1645417Y666469D02*
X1645414Y666475D01*
G01X1645420Y666462D02*
X1645417Y666469D01*
G01X1645425Y666456D02*
X1645420Y666462D01*
G01X1645431Y666452D02*
X1645425Y666456D01*
G01X1645438Y666448D02*
X1645431Y666452D01*
G01X1645445Y666446D02*
X1645438Y666448D01*
G01X1645453Y666446D02*
X1645445D01*
G01X1645414Y669625D02*
X1645413Y669632D01*
G01X1645417Y669618D02*
X1645414Y669625D01*
G01X1645420Y669612D02*
X1645417Y669618D01*
G01X1645425Y669606D02*
X1645420Y669612D01*
G01X1645431Y669601D02*
X1645425Y669606D01*
G01X1645438Y669598D02*
X1645431Y669601D01*
G01X1645445Y669596D02*
X1645438Y669598D01*
G01X1645453Y669595D02*
X1645445Y669596D01*
G01X1646367Y651889D02*
X1646377Y651884D01*
G01X1646357Y651890D02*
X1646367Y651889D01*
G01Y655038D02*
X1646377Y655034D01*
G01X1646357Y655039D02*
X1646367Y655038D01*
G01Y658188D02*
X1646377Y658183D01*
G01X1646357Y658189D02*
X1646367Y658188D01*
G01Y661337D02*
X1646377Y661333D01*
G01X1646357Y661339D02*
X1646367Y661337D01*
G01Y664487D02*
X1646377Y664483D01*
G01X1646357Y664488D02*
X1646367Y664487D01*
G01Y667637D02*
X1646377Y667632D01*
G01X1646357Y667638D02*
X1646367Y667637D01*
G01Y670786D02*
X1646377Y670782D01*
G01X1646357Y670787D02*
X1646367Y670786D01*
G01X1645413Y653888D02*
Y653884D01*
G01X1645415Y653882D02*
X1645413Y653888D01*
G01X1645427Y653867D02*
X1645415Y653882D01*
G01X1645452Y653858D02*
X1645427Y653867D01*
G01X1645413Y657038D02*
Y657034D01*
G01X1645415Y657031D02*
X1645413Y657038D01*
G01X1645426Y657016D02*
X1645415Y657031D01*
G01X1645451Y657008D02*
X1645426Y657016D01*
G01X1645413Y650739D02*
Y650735D01*
G01X1645415Y650732D02*
X1645413Y650739D01*
G01X1645426Y650717D02*
X1645415Y650732D01*
G01X1645451Y650709D02*
X1645426Y650717D01*
G01X1645413Y663337D02*
Y663333D01*
G01X1645415Y663331D02*
X1645413Y663337D01*
G01X1645426Y663315D02*
X1645415Y663331D01*
G01X1645451Y663307D02*
X1645426Y663315D01*
G01X1645413Y666487D02*
Y666483D01*
G01X1645415Y666480D02*
X1645413Y666487D01*
G01X1645426Y666465D02*
X1645415Y666480D01*
G01X1645451Y666457D02*
X1645426Y666465D01*
G01X1645413Y669636D02*
Y669632D01*
G01X1645415Y669630D02*
X1645413Y669636D01*
G01X1645426Y669615D02*
X1645415Y669630D01*
G01X1645451Y669606D02*
X1645426Y669615D01*
G01X1659810Y648929D02*
X1659821Y648913D01*
G01X1659786Y648937D02*
X1659810Y648929D01*
G01Y673929D02*
X1659821Y673913D01*
G01X1659786Y673937D02*
X1659810Y673929D01*
G01Y678929D02*
X1659821Y678913D01*
G01X1659786Y678937D02*
X1659810Y678929D01*
G01Y683929D02*
X1659821Y683913D01*
G01X1659786Y683937D02*
X1659810Y683929D01*
G01Y688929D02*
X1659821Y688913D01*
G01X1659786Y688937D02*
X1659810Y688929D01*
G01Y693929D02*
X1659821Y693913D01*
G01X1659786Y693937D02*
X1659810Y693929D01*
G01X1645413Y660187D02*
Y660183D01*
G01X1645415Y660182D02*
X1645413Y660187D01*
G01X1645425Y660167D02*
X1645415Y660182D01*
G01X1645448Y660158D02*
X1645425Y660167D01*
G01X1646366Y658188D02*
X1646357Y658189D01*
G01X1646375Y658185D02*
X1646366Y658188D01*
G01X1646383Y658180D02*
X1646375Y658185D01*
G01X1646366Y651889D02*
X1646357Y651890D01*
G01X1646375Y651885D02*
X1646366Y651889D01*
G01X1646383Y651880D02*
X1646375Y651885D01*
G01X1646366Y655038D02*
X1646357Y655039D01*
G01X1646375Y655035D02*
X1646366Y655038D01*
G01X1646383Y655030D02*
X1646375Y655035D01*
G01X1646366Y661337D02*
X1646357Y661339D01*
G01X1646375Y661334D02*
X1646366Y661337D01*
G01X1646383Y661329D02*
X1646375Y661334D01*
G01X1646366Y664487D02*
X1646357Y664488D01*
G01X1646375Y664484D02*
X1646366Y664487D01*
G01X1646383Y664479D02*
X1646375Y664484D01*
G01X1646366Y667637D02*
X1646357Y667638D01*
G01X1646375Y667633D02*
X1646366Y667637D01*
G01X1646383Y667628D02*
X1646375Y667633D01*
G01X1646366Y670786D02*
X1646357Y670787D01*
G01X1646375Y670783D02*
X1646366Y670786D01*
G01X1646383Y670778D02*
X1646375Y670783D01*
G01X1645452Y650704D02*
X1645453Y650698D01*
G01X1645452Y650707D02*
Y650704D01*
G01X1645450Y650709D02*
X1645452Y650707D01*
G01Y653854D02*
X1645453Y653847D01*
G01X1645452Y653857D02*
Y653854D01*
G01X1645450Y653858D02*
X1645452Y653857D01*
G01Y657003D02*
X1645453Y656997D01*
G01X1645452Y657007D02*
Y657003D01*
G01X1645450Y657008D02*
X1645452Y657007D01*
G01Y660153D02*
X1645453Y660146D01*
G01X1645452Y660156D02*
Y660153D01*
G01X1645450Y660157D02*
X1645452Y660156D01*
G01Y663302D02*
X1645453Y663296D01*
G01X1645452Y663306D02*
Y663302D01*
G01X1645450Y663307D02*
X1645452Y663306D01*
G01Y666452D02*
X1645453Y666446D01*
G01X1645452Y666456D02*
Y666452D01*
G01X1645450Y666457D02*
X1645452Y666456D01*
G01Y669602D02*
X1645453Y669595D01*
G01X1645452Y669605D02*
Y669602D01*
G01X1645450Y669606D02*
X1645452Y669605D01*
G01X1646369Y669608D02*
X1646357Y669606D01*
G01X1646379Y669613D02*
X1646369Y669608D01*
G01Y666459D02*
X1646357Y666457D01*
G01X1646379Y666464D02*
X1646369Y666459D01*
G01Y663309D02*
X1646357Y663307D01*
G01X1646379Y663314D02*
X1646369Y663309D01*
G01Y660159D02*
X1646357Y660157D01*
G01X1646379Y660165D02*
X1646369Y660159D01*
G01Y657010D02*
X1646357Y657008D01*
G01X1646379Y657015D02*
X1646369Y657010D01*
G01Y653860D02*
X1646357Y653858D01*
G01X1646379Y653865D02*
X1646369Y653860D01*
G01Y650711D02*
X1646357Y650709D01*
G01X1646379Y650716D02*
X1646369Y650711D01*
G01X1646395Y669620D02*
X1646398Y669632D01*
G01X1646389Y669609D02*
X1646395Y669620D01*
G01X1646378Y669600D02*
X1646389Y669609D01*
G01X1646395Y663320D02*
X1646398Y663333D01*
G01X1646389Y663309D02*
X1646395Y663320D01*
G01X1646378Y663301D02*
X1646389Y663309D01*
G01X1646395Y660171D02*
X1646398Y660183D01*
G01X1646389Y660160D02*
X1646395Y660171D01*
G01X1646378Y660152D02*
X1646389Y660160D01*
G01X1646395Y657021D02*
X1646398Y657034D01*
G01X1646389Y657010D02*
X1646395Y657021D01*
G01X1646378Y657002D02*
X1646389Y657010D01*
G01X1646395Y653872D02*
X1646398Y653884D01*
G01X1646389Y653861D02*
X1646395Y653872D01*
G01X1646378Y653852D02*
X1646389Y653861D01*
G01X1646395Y650722D02*
X1646398Y650735D01*
G01X1646389Y650711D02*
X1646395Y650722D01*
G01X1646378Y650703D02*
X1646389Y650711D01*
G01X1645452Y670793D02*
Y670799D01*
G01Y670789D02*
Y670793D01*
G01X1645450Y670787D02*
X1645452Y670789D01*
G01Y667643D02*
Y667649D01*
G01Y667639D02*
Y667643D01*
G01X1645450Y667638D02*
X1645452Y667639D01*
G01Y664493D02*
Y664500D01*
G01Y664489D02*
Y664493D01*
G01X1645450Y664488D02*
X1645452Y664489D01*
G01Y661344D02*
Y661350D01*
G01Y661340D02*
Y661344D01*
G01X1645450Y661339D02*
X1645452Y661340D01*
G01Y658194D02*
Y658200D01*
G01Y658190D02*
Y658194D01*
G01X1645450Y658189D02*
X1645452Y658190D01*
G01Y655044D02*
Y655051D01*
G01Y655041D02*
Y655044D01*
G01X1645450Y655039D02*
X1645452Y655041D01*
G01Y651895D02*
Y651901D01*
G01Y651891D02*
Y651895D01*
G01X1645450Y651890D02*
X1645452Y651891D01*
G01X1645414Y670768D02*
X1645413Y670762D01*
G01X1645416Y670774D02*
X1645414Y670768D01*
G01X1645419Y670780D02*
X1645416Y670774D01*
G01X1645422Y670785D02*
X1645419Y670780D01*
G01X1645427Y670790D02*
X1645422Y670785D01*
G01X1645433Y670794D02*
X1645427Y670790D01*
G01X1645414Y667619D02*
X1645413Y667612D01*
G01X1645416Y667625D02*
X1645414Y667619D01*
G01X1645419Y667630D02*
X1645416Y667625D01*
G01X1645422Y667636D02*
X1645419Y667630D01*
G01X1645427Y667640D02*
X1645422Y667636D01*
G01X1645433Y667644D02*
X1645427Y667640D01*
G01X1645414Y664469D02*
X1645413Y664463D01*
G01X1645416Y664475D02*
X1645414Y664469D01*
G01X1645419Y664481D02*
X1645416Y664475D01*
G01X1645422Y664486D02*
X1645419Y664481D01*
G01X1645427Y664491D02*
X1645422Y664486D01*
G01X1645433Y664494D02*
X1645427Y664491D01*
G01X1645414Y661319D02*
X1645413Y661313D01*
G01X1645416Y661326D02*
X1645414Y661319D01*
G01X1645419Y661331D02*
X1645416Y661326D01*
G01X1645422Y661337D02*
X1645419Y661331D01*
G01X1645427Y661341D02*
X1645422Y661337D01*
G01X1645433Y661345D02*
X1645427Y661341D01*
G01X1645414Y658170D02*
X1645413Y658163D01*
G01X1645416Y658176D02*
X1645414Y658170D01*
G01X1645419Y658181D02*
X1645416Y658176D01*
G01X1645422Y658187D02*
X1645419Y658181D01*
G01X1645427Y658191D02*
X1645422Y658187D01*
G01X1645433Y658195D02*
X1645427Y658191D01*
G01X1645414Y655020D02*
X1645413Y655014D01*
G01X1645416Y655026D02*
X1645414Y655020D01*
G01X1645419Y655032D02*
X1645416Y655026D01*
G01X1645422Y655037D02*
X1645419Y655032D01*
G01X1645427Y655042D02*
X1645422Y655037D01*
G01X1645433Y655046D02*
X1645427Y655042D01*
G01X1645414Y651870D02*
X1645413Y651864D01*
G01X1645416Y651877D02*
X1645414Y651870D01*
G01X1645419Y651882D02*
X1645416Y651877D01*
G01X1645422Y651888D02*
X1645419Y651882D01*
G01X1645427Y651892D02*
X1645422Y651888D01*
G01X1645433Y651896D02*
X1645427Y651892D01*
G01X1659823Y648904D02*
Y648911D01*
G01X1659824Y648900D02*
X1659823Y648904D01*
G01X1659825Y648898D02*
X1659824Y648900D01*
G01X1659823Y673904D02*
Y673911D01*
G01X1659824Y673900D02*
X1659823Y673904D01*
G01X1659825Y673898D02*
X1659824Y673900D01*
G01X1659823Y678904D02*
Y678911D01*
G01X1659824Y678900D02*
X1659823Y678904D01*
G01X1659825Y678898D02*
X1659824Y678900D01*
G01X1659823Y683904D02*
Y683911D01*
G01X1659824Y683900D02*
X1659823Y683904D01*
G01X1659825Y683898D02*
X1659824Y683900D01*
G01X1659823Y688904D02*
Y688911D01*
G01X1659824Y688900D02*
X1659823Y688904D01*
G01X1659825Y688898D02*
X1659824Y688900D01*
G01X1659823Y693904D02*
Y693911D01*
G01X1659824Y693900D02*
X1659823Y693904D01*
G01X1659825Y693898D02*
X1659824Y693900D01*
G01X1645436Y653861D02*
X1645450Y653858D01*
G01X1645425Y653868D02*
X1645436Y653861D01*
G01X1645413Y653887D02*
X1645425Y653868D01*
G01X1645436Y663310D02*
X1645450Y663307D01*
G01X1645424Y663317D02*
X1645436Y663310D01*
G01X1645413Y663335D02*
X1645424Y663317D01*
G01X1645436Y657011D02*
X1645450Y657008D01*
G01X1645424Y657019D02*
X1645436Y657011D01*
G01X1645412Y657039D02*
X1645424Y657019D01*
G01X1645436Y666459D02*
X1645450Y666457D01*
G01X1645424Y666467D02*
X1645436Y666459D01*
G01X1645412Y666487D02*
X1645424Y666467D01*
G01X1646398Y650742D02*
Y650735D01*
G01X1646397Y650747D02*
X1646398Y650742D01*
G01X1646396Y650748D02*
X1646397Y650747D01*
G01X1646398Y653892D02*
Y653884D01*
G01X1646397Y653896D02*
X1646398Y653892D01*
G01X1646396Y653898D02*
X1646397Y653896D01*
G01X1646398Y657041D02*
Y657034D01*
G01X1646397Y657046D02*
X1646398Y657041D01*
G01X1646396Y657047D02*
X1646397Y657046D01*
G01X1646398Y660191D02*
Y660183D01*
G01X1646397Y660196D02*
X1646398Y660191D01*
G01X1646396Y660197D02*
X1646397Y660196D01*
G01X1646398Y663341D02*
Y663333D01*
G01X1646397Y663345D02*
X1646398Y663341D01*
G01X1646396Y663346D02*
X1646397Y663345D01*
G01X1646398Y666490D02*
Y666483D01*
G01X1646397Y666495D02*
X1646398Y666490D01*
G01X1646396Y666496D02*
X1646397Y666495D01*
G01X1646398Y669640D02*
Y669632D01*
G01X1646397Y669644D02*
X1646398Y669640D01*
G01X1646396Y669646D02*
X1646397Y669644D01*
G01X1645436Y669609D02*
X1645450Y669606D01*
G01X1645423Y669617D02*
X1645436Y669609D01*
G01X1645412Y669637D02*
X1645423Y669617D01*
G01X1645435Y650712D02*
X1645450Y650709D01*
G01X1645422Y650720D02*
X1645435Y650712D01*
G01X1645412Y650741D02*
X1645422Y650720D01*
G01X1646397Y651871D02*
X1646398Y651864D01*
G01X1646395Y651877D02*
X1646397Y651871D01*
G01X1646392Y651883D02*
X1646395Y651877D01*
G01X1646397Y655020D02*
X1646398Y655014D01*
G01X1646395Y655027D02*
X1646397Y655020D01*
G01X1646392Y655033D02*
X1646395Y655027D01*
G01X1646397Y658170D02*
X1646398Y658163D01*
G01X1646395Y658176D02*
X1646397Y658170D01*
G01X1646392Y658182D02*
X1646395Y658176D01*
G01X1646397Y661320D02*
X1646398Y661313D01*
G01X1646395Y661326D02*
X1646397Y661320D01*
G01X1646392Y661332D02*
X1646395Y661326D01*
G01X1646397Y664469D02*
X1646398Y664463D01*
G01X1646395Y664476D02*
X1646397Y664469D01*
G01X1646392Y664481D02*
X1646395Y664476D01*
G01X1646358Y670793D02*
Y670799D01*
G01X1646357Y670789D02*
X1646358Y670793D01*
G01X1646357Y670787D02*
Y670789D01*
G01X1646358Y667643D02*
Y667649D01*
G01X1646357Y667639D02*
X1646358Y667643D01*
G01X1646357Y667638D02*
Y667639D01*
G01X1646358Y664493D02*
Y664500D01*
G01X1646357Y664490D02*
X1646358Y664493D01*
G01X1646357Y664488D02*
Y664490D01*
G01X1646358Y661344D02*
Y661350D01*
G01X1646357Y661340D02*
X1646358Y661344D01*
G01X1646357Y661339D02*
Y661340D01*
G01X1646358Y658194D02*
Y658200D01*
G01X1646357Y658191D02*
X1646358Y658194D01*
G01X1646357Y658189D02*
Y658191D01*
G01X1646358Y655044D02*
Y655051D01*
G01X1646357Y655041D02*
X1646358Y655044D01*
G01X1646357Y655039D02*
Y655041D01*
G01X1659823Y692552D02*
Y692543D01*
G01X1659824Y692557D02*
X1659823Y692552D01*
G01X1659826Y692559D02*
X1659824Y692557D01*
G01X1659823Y687552D02*
Y687543D01*
G01X1659824Y687557D02*
X1659823Y687552D01*
G01X1659826Y687559D02*
X1659824Y687557D01*
G01X1659823Y682552D02*
Y682543D01*
G01X1659824Y682557D02*
X1659823Y682552D01*
G01X1659826Y682559D02*
X1659824Y682557D01*
G01X1659823Y677552D02*
Y677543D01*
G01X1659824Y677557D02*
X1659823Y677552D01*
G01X1659826Y677559D02*
X1659824Y677557D01*
G01X1659823Y672552D02*
Y672543D01*
G01X1659824Y672557D02*
X1659823Y672552D01*
G01X1659826Y672559D02*
X1659824Y672557D01*
G01X1645413Y670754D02*
Y670762D01*
G01X1645412Y670750D02*
X1645413Y670754D01*
G01X1645411Y670748D02*
X1645412Y670750D01*
G01X1645413Y667605D02*
Y667612D01*
G01X1645412Y667600D02*
X1645413Y667605D01*
G01X1645411Y667598D02*
X1645412Y667600D01*
G01X1645413Y664455D02*
Y664463D01*
G01X1645412Y664450D02*
X1645413Y664455D01*
G01X1645411Y664449D02*
X1645412Y664450D01*
G01X1645413Y661306D02*
Y661313D01*
G01X1645412Y661301D02*
X1645413Y661306D01*
G01X1645411Y661299D02*
X1645412Y661301D01*
G01X1645413Y658156D02*
Y658163D01*
G01X1645412Y658151D02*
X1645413Y658156D01*
G01X1645411Y658150D02*
X1645412Y658151D01*
G01X1645413Y655006D02*
Y655014D01*
G01X1645412Y655002D02*
X1645413Y655006D01*
G01X1645411Y655000D02*
X1645412Y655002D01*
G01X1645413Y651857D02*
Y651864D01*
G01X1645412Y651852D02*
X1645413Y651857D01*
G01X1645411Y651850D02*
X1645412Y651852D01*
G01X1646397Y667619D02*
X1646398Y667612D01*
G01X1646395Y667625D02*
X1646397Y667619D01*
G01X1646392Y667631D02*
X1646395Y667625D01*
G01X1646397Y670769D02*
X1646398Y670762D01*
G01X1646395Y670775D02*
X1646397Y670769D01*
G01X1646392Y670781D02*
X1646395Y670775D01*
G01X1646359Y650704D02*
Y650698D01*
G01X1646357Y650707D02*
X1646359Y650704D01*
G01X1646357Y650709D02*
Y650707D01*
G01X1646359Y653853D02*
Y653847D01*
G01X1646357Y653857D02*
X1646359Y653853D01*
G01X1646357Y653858D02*
Y653857D01*
G01X1646359Y657003D02*
Y656997D01*
G01X1646357Y657007D02*
X1646359Y657003D01*
G01X1646357Y657008D02*
Y657007D01*
G01X1646359Y660152D02*
Y660146D01*
G01X1646357Y660156D02*
X1646359Y660152D01*
G01X1646357Y660157D02*
Y660156D01*
G01X1646359Y663302D02*
Y663296D01*
G01X1646357Y663306D02*
X1646359Y663302D01*
G01X1646357Y663307D02*
Y663306D01*
G01X1646359Y669601D02*
Y669595D01*
G01X1646357Y669605D02*
X1646359Y669601D01*
G01X1646357Y669606D02*
Y669605D01*
G01X1658839Y648944D02*
Y648954D01*
G01Y648939D02*
Y648944D01*
G01X1658840Y648937D02*
X1658839Y648939D01*
G01Y673944D02*
Y673954D01*
G01Y673939D02*
Y673944D01*
G01X1658840Y673937D02*
X1658839Y673939D01*
G01Y678944D02*
Y678954D01*
G01Y678939D02*
Y678944D01*
G01X1658840Y678937D02*
X1658839Y678939D01*
G01Y683944D02*
Y683954D01*
G01Y683939D02*
Y683944D01*
G01X1658840Y683937D02*
X1658839Y683939D01*
G01Y688944D02*
Y688954D01*
G01Y688939D02*
Y688944D01*
G01X1658840Y688937D02*
X1658839Y688939D01*
G01Y693944D02*
Y693954D01*
G01Y693939D02*
Y693944D01*
G01X1658840Y693937D02*
X1658839Y693939D01*
G01X1659815Y649081D02*
X1659823Y649055D01*
G01X1659805Y649107D02*
X1659815Y649081D01*
G01X1659794Y649134D02*
X1659805Y649107D01*
G01X1659815Y674081D02*
X1659823Y674055D01*
G01X1659805Y674107D02*
X1659815Y674081D01*
G01X1659794Y674134D02*
X1659805Y674107D01*
G01X1659815Y679081D02*
X1659823Y679055D01*
G01X1659805Y679107D02*
X1659815Y679081D01*
G01X1659794Y679134D02*
X1659805Y679107D01*
G01X1659815Y684081D02*
X1659823Y684055D01*
G01X1659805Y684107D02*
X1659815Y684081D01*
G01X1659794Y684134D02*
X1659805Y684107D01*
G01X1659815Y689081D02*
X1659823Y689055D01*
G01X1659805Y689107D02*
X1659815Y689081D01*
G01X1659794Y689134D02*
X1659805Y689107D01*
G01X1659815Y694081D02*
X1659823Y694055D01*
G01X1659805Y694107D02*
X1659815Y694081D01*
G01X1659794Y694134D02*
X1659805Y694107D01*
G01X1645431Y660163D02*
X1645450Y660157D01*
G01X1645418Y660175D02*
X1645431Y660163D01*
G01X1645411Y660193D02*
X1645418Y660175D01*
G01X1659806Y648932D02*
X1659786Y648937D01*
G01X1659820Y648918D02*
X1659806Y648932D01*
G01X1659825Y648898D02*
X1659820Y648918D01*
G01X1659790Y649035D02*
X1659794Y649134D01*
G01X1659784Y648963D02*
X1659790Y649035D01*
G01X1659786Y648937D02*
X1659784Y648963D01*
G01X1659790Y674035D02*
X1659794Y674134D01*
G01X1659784Y673963D02*
X1659790Y674035D01*
G01X1659786Y673937D02*
X1659784Y673963D01*
G01X1659790Y679035D02*
X1659794Y679134D01*
G01X1659784Y678963D02*
X1659790Y679035D01*
G01X1659786Y678937D02*
X1659784Y678963D01*
G01X1659790Y684035D02*
X1659794Y684134D01*
G01X1659784Y683963D02*
X1659790Y684035D01*
G01X1659786Y683937D02*
X1659784Y683963D01*
G01X1659790Y689035D02*
X1659794Y689134D01*
G01X1659784Y688963D02*
X1659790Y689035D01*
G01X1659786Y688937D02*
X1659784Y688963D01*
G01X1659790Y694035D02*
X1659794Y694134D01*
G01X1659784Y693963D02*
X1659790Y694035D01*
G01X1659786Y693937D02*
X1659784Y693963D01*
G01X1645413Y663341D02*
Y663333D01*
G01X1645412Y663345D02*
X1645413Y663341D01*
G01Y663336D02*
X1645412Y663345D01*
G01X1645454Y670972D02*
X1645453Y670984D01*
G01X1645450Y670959D02*
X1645454Y670972D01*
G01X1645450Y670945D02*
Y670959D01*
G01X1645454Y667822D02*
X1645453Y667835D01*
G01X1645450Y667809D02*
X1645454Y667822D01*
G01X1645450Y667796D02*
Y667809D01*
G01X1645454Y664673D02*
X1645453Y664685D01*
G01X1645450Y664660D02*
X1645454Y664673D01*
G01X1645450Y664646D02*
Y664660D01*
G01X1645454Y661523D02*
X1645453Y661535D01*
G01X1645450Y661510D02*
X1645454Y661523D01*
G01X1645450Y661496D02*
Y661510D01*
G01X1645454Y658374D02*
X1645453Y658386D01*
G01X1645450Y658361D02*
X1645454Y658374D01*
G01X1645450Y658347D02*
Y658361D01*
G01X1645454Y655224D02*
X1645453Y655236D01*
G01X1645450Y655211D02*
X1645454Y655224D01*
G01X1645450Y655197D02*
Y655211D01*
G01X1645454Y652074D02*
X1645453Y652087D01*
G01X1645450Y652061D02*
X1645454Y652074D01*
G01X1645450Y652048D02*
Y652061D01*
G01X1658839Y692557D02*
X1658840Y692559D01*
G01X1658839Y692552D02*
Y692557D01*
G01Y692543D02*
Y692552D01*
G01Y687557D02*
X1658840Y687559D01*
G01X1658839Y687552D02*
Y687557D01*
G01Y687543D02*
Y687552D01*
G01Y682557D02*
X1658840Y682559D01*
G01X1658839Y682552D02*
Y682557D01*
G01Y682543D02*
Y682552D01*
G01Y677557D02*
X1658840Y677559D01*
G01X1658839Y677552D02*
Y677557D01*
G01Y677543D02*
Y677552D01*
G01Y672557D02*
X1658840Y672559D01*
G01X1658839Y672552D02*
Y672557D01*
G01Y672543D02*
Y672552D01*
G01X1645413Y669640D02*
Y669632D01*
G01X1645412Y669644D02*
X1645413Y669640D01*
G01X1645412Y669637D02*
Y669644D01*
G01X1645450Y669435D02*
X1645449Y669448D01*
G01X1645454Y669422D02*
X1645450Y669435D01*
G01X1645453Y669409D02*
X1645454Y669422D01*
G01X1645450Y666285D02*
X1645449Y666299D01*
G01X1645454Y666272D02*
X1645450Y666285D01*
G01X1645453Y666260D02*
X1645454Y666272D01*
G01X1645450Y663136D02*
X1645449Y663149D01*
G01X1645454Y663123D02*
X1645450Y663136D01*
G01X1645453Y663110D02*
X1645454Y663123D01*
G01X1645450Y659986D02*
X1645449Y660000D01*
G01X1645454Y659973D02*
X1645450Y659986D01*
G01X1645453Y659961D02*
X1645454Y659973D01*
G01X1645450Y656837D02*
X1645449Y656850D01*
G01X1645454Y656824D02*
X1645450Y656837D01*
G01X1645453Y656811D02*
X1645454Y656824D01*
G01X1645450Y653687D02*
X1645449Y653700D01*
G01X1645454Y653674D02*
X1645450Y653687D01*
G01X1645453Y653661D02*
X1645454Y653674D01*
G01X1645450Y650537D02*
X1645449Y650551D01*
G01X1645454Y650524D02*
X1645450Y650537D01*
G01X1645453Y650512D02*
X1645454Y650524D01*
G01X1646361Y670959D02*
X1646362Y670945D01*
G01X1646357Y670972D02*
X1646361Y670959D01*
G01X1646358Y670984D02*
X1646357Y670972D01*
G01X1646361Y667809D02*
X1646362Y667796D01*
G01X1646357Y667822D02*
X1646361Y667809D01*
G01X1646358Y667835D02*
X1646357Y667822D01*
G01X1646361Y664659D02*
X1646362Y664646D01*
G01X1646357Y664672D02*
X1646361Y664659D01*
G01X1646358Y664685D02*
X1646357Y664672D01*
G01X1646361Y661510D02*
X1646362Y661496D01*
G01X1646357Y661523D02*
X1646361Y661510D01*
G01X1646358Y661535D02*
X1646357Y661523D01*
G01X1646361Y658360D02*
X1646362Y658347D01*
G01X1646357Y658373D02*
X1646361Y658360D01*
G01X1646358Y658386D02*
X1646357Y658373D01*
G01X1646361Y655211D02*
X1646362Y655197D01*
G01X1646357Y655224D02*
X1646361Y655211D01*
G01X1646358Y655236D02*
X1646357Y655224D01*
G01X1646361Y652061D02*
X1646362Y652048D01*
G01X1646357Y652074D02*
X1646361Y652061D01*
G01X1646358Y652087D02*
X1646357Y652074D01*
G01X1645413Y657041D02*
Y657034D01*
G01X1645412Y657046D02*
X1645413Y657041D01*
G01X1645412Y657039D02*
Y657046D01*
G01X1645413Y666490D02*
Y666483D01*
G01X1645412Y666495D02*
X1645413Y666490D01*
G01X1645412Y666488D02*
Y666495D01*
G01X1646357Y669422D02*
X1646358Y669409D01*
G01X1646360Y669435D02*
X1646357Y669422D01*
G01X1646361Y669448D02*
X1646360Y669435D01*
G01X1646357Y666272D02*
X1646358Y666260D01*
G01X1646360Y666285D02*
X1646357Y666272D01*
G01X1646361Y666299D02*
X1646360Y666285D01*
G01X1646357Y663123D02*
X1646358Y663110D01*
G01X1646360Y663136D02*
X1646357Y663123D01*
G01X1646361Y663149D02*
X1646360Y663136D01*
G01X1646357Y659973D02*
X1646358Y659961D01*
G01X1646360Y659986D02*
X1646357Y659973D01*
G01X1646361Y660000D02*
X1646360Y659986D01*
G01X1646357Y656824D02*
X1646358Y656811D01*
G01X1646360Y656837D02*
X1646357Y656824D01*
G01X1646361Y656850D02*
X1646360Y656837D01*
G01X1646357Y653674D02*
X1646358Y653661D01*
G01X1646360Y653687D02*
X1646357Y653674D01*
G01X1646361Y653700D02*
X1646360Y653687D01*
G01X1646357Y650524D02*
X1646358Y650512D01*
G01X1646360Y650537D02*
X1646357Y650524D01*
G01X1646361Y650551D02*
X1646360Y650537D01*
G01X1645413Y650743D02*
Y650735D01*
G01X1645412Y650747D02*
X1645413Y650743D01*
G01X1645412Y650741D02*
Y650747D01*
G01X1645426Y670779D02*
X1645450Y670787D01*
G01X1645415Y670765D02*
X1645426Y670779D01*
G01X1645413Y670758D02*
X1645415Y670765D01*
G01X1645426Y667630D02*
X1645450Y667638D01*
G01X1645415Y667615D02*
X1645426Y667630D01*
G01X1645413Y667608D02*
X1645415Y667615D01*
G01X1645426Y664480D02*
X1645450Y664488D01*
G01X1645415Y664465D02*
X1645426Y664480D01*
G01X1645413Y664459D02*
X1645415Y664465D01*
G01X1645426Y661330D02*
X1645450Y661339D01*
G01X1645415Y661316D02*
X1645426Y661330D01*
G01X1645413Y661309D02*
X1645415Y661316D01*
G01X1645426Y658181D02*
X1645450Y658189D01*
G01X1645415Y658166D02*
X1645426Y658181D01*
G01X1645413Y658159D02*
X1645415Y658166D01*
G01X1645426Y655031D02*
X1645450Y655039D01*
G01X1645415Y655017D02*
X1645426Y655031D01*
G01X1645413Y655010D02*
X1645415Y655017D01*
G01X1645426Y651881D02*
X1645450Y651890D01*
G01X1645415Y651867D02*
X1645426Y651881D01*
G01X1645413Y651860D02*
X1645415Y651867D01*
G01X1646398Y670754D02*
Y670761D01*
G01X1646397Y670750D02*
X1646398Y670754D01*
G01X1646396Y670748D02*
X1646397Y670750D01*
G01X1646398Y667605D02*
Y667612D01*
G01X1646397Y667600D02*
X1646398Y667605D01*
G01X1646396Y667598D02*
X1646397Y667600D01*
G01X1646398Y664455D02*
Y664462D01*
G01X1646397Y664451D02*
X1646398Y664455D01*
G01X1646396Y664449D02*
X1646397Y664451D01*
G01X1646398Y661306D02*
Y661313D01*
G01X1646397Y661301D02*
X1646398Y661306D01*
G01X1646396Y661299D02*
X1646397Y661301D01*
G01X1646398Y658156D02*
Y658163D01*
G01X1646397Y658152D02*
X1646398Y658156D01*
G01X1646396Y658150D02*
X1646397Y658152D01*
G01X1646398Y655006D02*
Y655013D01*
G01X1646397Y655002D02*
X1646398Y655006D01*
G01X1646396Y655000D02*
X1646397Y655002D01*
G01X1646398Y651857D02*
Y651864D01*
G01X1646397Y651852D02*
X1646398Y651857D01*
G01X1646396Y651850D02*
X1646397Y651852D01*
G01X1645413Y660191D02*
Y660183D01*
G01X1645412Y660196D02*
X1645413Y660191D01*
G01X1645411Y660193D02*
X1645412Y660196D01*
G01X1645413Y653892D02*
Y653884D01*
G01X1645412Y653896D02*
X1645413Y653892D01*
G01X1645411Y653894D02*
X1645412Y653896D01*
G01X1646358Y651895D02*
Y651901D01*
G01X1646357Y651891D02*
X1646358Y651895D01*
G01X1646357Y651890D02*
Y651891D01*
G01X1659806Y673932D02*
X1659786Y673937D01*
G01X1659820Y673918D02*
X1659806Y673932D01*
G01X1659825Y673898D02*
X1659820Y673918D01*
G01X1659806Y678932D02*
X1659786Y678937D01*
G01X1659820Y678918D02*
X1659806Y678932D01*
G01X1659825Y678898D02*
X1659820Y678918D01*
G01X1659806Y683932D02*
X1659786Y683937D01*
G01X1659820Y683918D02*
X1659806Y683932D01*
G01X1659825Y683898D02*
X1659820Y683918D01*
G01X1659806Y688932D02*
X1659786Y688937D01*
G01X1659820Y688918D02*
X1659806Y688932D01*
G01X1659825Y688898D02*
X1659820Y688918D01*
G01X1659806Y693932D02*
X1659786Y693937D01*
G01X1659820Y693918D02*
X1659806Y693932D01*
G01X1659825Y693898D02*
X1659820Y693918D01*
G01X1646390Y658171D02*
X1646383Y658180D01*
G01X1646394Y658161D02*
X1646390Y658171D01*
G01X1646396Y658150D02*
X1646394Y658161D01*
G01X1646390Y651872D02*
X1646383Y651880D01*
G01X1646395Y651861D02*
X1646390Y651872D01*
G01X1646396Y651850D02*
X1646395Y651861D01*
G01X1646390Y655021D02*
X1646383Y655030D01*
G01X1646395Y655011D02*
X1646390Y655021D01*
G01X1646396Y655000D02*
X1646395Y655011D01*
G01X1646390Y661320D02*
X1646383Y661329D01*
G01X1646395Y661310D02*
X1646390Y661320D01*
G01X1646396Y661299D02*
X1646395Y661310D01*
G01X1646390Y664470D02*
X1646383Y664479D01*
G01X1646395Y664460D02*
X1646390Y664470D01*
G01X1646396Y664449D02*
X1646395Y664460D01*
G01X1646390Y667620D02*
X1646383Y667628D01*
G01X1646395Y667609D02*
X1646390Y667620D01*
G01X1646396Y667598D02*
X1646395Y667609D01*
G01X1646390Y670769D02*
X1646383Y670778D01*
G01X1646395Y670759D02*
X1646390Y670769D01*
G01X1646396Y670748D02*
X1646395Y670759D01*
G01X1646397Y651853D02*
X1646398Y651864D01*
G01X1646397Y655002D02*
X1646398Y655013D01*
G01X1646397Y658152D02*
X1646398Y658163D01*
G01X1646397Y661302D02*
X1646398Y661313D01*
G01X1646397Y664451D02*
X1646398Y664462D01*
G01X1646397Y667601D02*
X1646398Y667612D01*
G01X1646397Y670750D02*
X1646398Y670761D01*
G01X1659823Y648911D02*
Y648920D01*
G01Y673911D02*
Y673920D01*
G01Y678911D02*
Y678920D01*
G01Y683911D02*
Y683920D01*
G01Y688911D02*
Y688920D01*
G01Y693911D02*
Y693920D01*
G01X1664173Y692559D02*
Y693937D01*
G01Y687559D02*
Y688937D01*
G01Y682559D02*
Y683937D01*
G01Y677559D02*
Y678937D01*
G01Y672559D02*
Y673937D01*
G01X1661004D02*
Y672559D01*
G01Y678937D02*
Y677559D01*
G01Y683937D02*
Y682559D01*
G01Y688937D02*
Y687559D01*
G01Y693937D02*
Y692559D01*
G01X1660433Y671791D02*
Y649705D01*
G01X1659823Y692067D02*
Y694429D01*
G01Y687067D02*
Y689429D01*
G01Y682067D02*
Y684429D01*
G01Y677067D02*
Y679429D01*
G01Y672067D02*
Y674429D01*
G01X1659252Y670610D02*
Y650886D01*
G01X1658839Y674429D02*
Y672067D01*
G01Y679429D02*
Y677067D01*
G01Y684429D02*
Y682067D01*
G01Y689429D02*
Y687067D01*
G01Y694429D02*
Y692067D01*
G01X1656496Y748248D02*
Y671791D01*
G01X1655315Y747067D02*
Y670610D01*
G01X1646850Y751988D02*
Y672953D01*
G01X1646398Y669449D02*
Y670945D01*
G01Y666299D02*
Y667795D01*
G01Y663150D02*
Y664646D01*
G01Y660000D02*
Y661496D01*
G01Y656850D02*
Y658346D01*
G01Y653701D02*
Y655197D01*
G01Y650551D02*
Y652047D01*
G01X1646358Y650698D02*
Y650551D01*
G01Y652048D02*
Y651901D01*
G01Y656997D02*
Y656850D01*
G01Y653847D02*
Y653700D01*
G01Y655197D02*
Y655051D01*
G01Y660146D02*
Y660000D01*
G01Y661496D02*
Y661350D01*
G01Y658347D02*
Y658200D01*
G01Y666446D02*
Y666299D01*
G01Y663296D02*
Y663149D01*
G01Y664646D02*
Y664500D01*
G01Y669595D02*
Y669448D01*
G01Y670945D02*
Y670799D01*
G01Y667796D02*
Y667649D01*
G01X1645453Y669448D02*
Y669595D01*
G01Y670799D02*
Y670946D01*
G01Y667649D02*
Y667796D01*
G01Y666298D02*
Y666446D01*
G01Y663149D02*
Y663296D01*
G01Y664500D02*
Y664646D01*
G01Y659999D02*
Y660146D01*
G01Y661350D02*
Y661497D01*
G01Y658200D02*
Y658347D01*
G01Y656850D02*
Y656997D01*
G01Y653700D02*
Y653847D01*
G01Y655051D02*
Y655198D01*
G01Y650550D02*
Y650698D01*
G01Y651901D02*
Y652048D01*
G01X1645413Y652047D02*
Y650551D01*
G01Y655197D02*
Y653701D01*
G01Y661496D02*
Y660000D01*
G01Y658346D02*
Y656850D01*
G01Y664646D02*
Y663150D01*
G01Y670945D02*
Y669449D01*
G01Y667795D02*
Y666299D01*
G01X1644232Y651890D02*
Y650709D01*
G01Y658189D02*
Y657008D01*
G01Y655039D02*
Y653858D01*
G01Y661339D02*
Y660157D01*
G01Y667638D02*
Y666457D01*
G01Y664488D02*
Y663307D01*
G01Y670787D02*
Y669606D01*
G01X1643898Y672953D02*
Y648543D01*
G01X1643504D02*
Y672953D01*
G01X1640472Y669606D02*
Y670787D01*
G01Y666457D02*
Y667638D01*
G01Y663307D02*
Y664488D01*
G01Y660157D02*
Y661339D01*
G01Y657008D02*
Y658189D01*
G01Y653858D02*
Y655039D01*
G01Y650709D02*
Y651890D01*
G01X1646398Y669632D02*
X1646397Y669643D01*
G01X1646398Y666483D02*
X1646397Y666494D01*
G01X1646398Y663333D02*
X1646397Y663344D01*
G01X1646398Y660183D02*
X1646397Y660194D01*
G01X1646398Y657034D02*
X1646397Y657045D01*
G01X1646398Y653884D02*
X1646397Y653895D01*
G01X1646398Y650735D02*
X1646397Y650746D01*
G01X1646357Y666457D02*
X1646360Y666446D01*
G01X1659252Y670610D02*
X1660433Y671791D01*
G01X1655315Y670610D02*
X1656496Y671791D01*
G01X1659252Y650886D02*
X1660433Y649705D01*
G01X1655315Y650886D02*
X1656496Y649705D01*
G01X1645300Y669646D02*
X1645412Y669637D01*
G01X1645411Y660193D02*
X1645300Y660197D01*
G01X1645411Y653894D02*
X1645300Y653898D01*
G01X1645411Y663343D02*
X1645300Y663346D01*
G01X1659823Y694429D02*
X1658839D01*
G01X1658840Y693937D02*
X1664173D01*
G01Y693898D02*
X1659825D01*
G01X1664173Y692559D02*
X1658840D01*
G01X1658839Y692067D02*
X1659823D01*
G01Y689429D02*
X1658839D01*
G01X1658840Y688937D02*
X1664173D01*
G01Y688898D02*
X1659825D01*
G01X1664173Y687559D02*
X1658840D01*
G01X1658839Y687067D02*
X1659823D01*
G01Y684429D02*
X1658839D01*
G01X1658840Y683937D02*
X1664173D01*
G01Y683898D02*
X1659825D01*
G01X1664173Y682559D02*
X1658840D01*
G01X1658839Y682067D02*
X1659823D01*
G01Y679429D02*
X1658839D01*
G01X1658840Y678937D02*
X1664173D01*
G01Y678898D02*
X1659825D01*
G01X1664173Y677559D02*
X1658840D01*
G01X1658839Y677067D02*
X1659823D01*
G01Y674429D02*
X1658839D01*
G01X1658840Y673937D02*
X1664173D01*
G01Y673898D02*
X1659825D01*
G01X1646850Y672953D02*
X1643504D01*
G01X1664173Y672559D02*
X1658840D01*
G01X1658839Y672067D02*
X1659823D01*
G01X1656496Y671791D02*
X1660433D01*
G01X1646358Y670984D02*
X1645453D01*
G01X1646398Y670945D02*
X1645413D01*
G01X1646357Y670787D02*
X1640472D01*
G01Y670748D02*
X1646396D01*
G01X1655315Y670610D02*
X1659252D01*
G01X1646396Y669646D02*
X1640472D01*
G01X1646357Y669606D02*
X1640472D01*
G01X1645413Y669449D02*
X1646398D01*
G01X1645453Y669409D02*
X1646358D01*
G01Y667835D02*
X1645453D01*
G01X1646398Y667795D02*
X1645413D01*
G01X1646357Y667638D02*
X1640472D01*
G01Y667598D02*
X1646396D01*
G01Y666496D02*
X1640472D01*
G01X1646357Y666457D02*
X1640472D01*
G01X1645413Y666299D02*
X1646398D01*
G01X1645453Y666260D02*
X1646358D01*
G01Y664685D02*
X1645453D01*
G01X1646398Y664646D02*
X1645413D01*
G01X1646357Y664488D02*
X1640472D01*
G01Y664449D02*
X1646396D01*
G01X1644666Y663346D02*
X1644232D01*
G01X1646396D02*
X1640472D01*
G01X1646357Y663307D02*
X1640472D01*
G01X1645413Y663150D02*
X1646398D01*
G01X1645453Y663110D02*
X1646358D01*
G01Y661535D02*
X1645453D01*
G01X1646398Y661496D02*
X1645413D01*
G01X1646357Y661339D02*
X1640472D01*
G01Y661299D02*
X1646396D01*
G01X1644666Y660197D02*
X1644232D01*
G01X1646396D02*
X1640472D01*
G01X1646357Y660157D02*
X1640472D01*
G01X1645413Y660000D02*
X1646398D01*
G01X1645453Y659961D02*
X1646358D01*
G01Y658386D02*
X1645453D01*
G01X1646398Y658346D02*
X1645413D01*
G01X1646357Y658189D02*
X1640472D01*
G01Y658150D02*
X1646396D01*
G01Y657047D02*
X1640472D01*
G01X1646357Y657008D02*
X1640472D01*
G01X1645413Y656850D02*
X1646398D01*
G01X1645453Y656811D02*
X1646358D01*
G01Y655236D02*
X1645453D01*
G01X1646398Y655197D02*
X1645413D01*
G01X1646357Y655039D02*
X1640472D01*
G01Y655000D02*
X1646396D01*
G01X1644666Y653898D02*
X1644232D01*
G01X1646396D02*
X1640472D01*
G01X1646357Y653858D02*
X1640472D01*
G01X1645413Y653701D02*
X1646398D01*
G01X1645453Y653661D02*
X1646358D01*
G01Y652087D02*
X1645453D01*
G01X1646398Y652047D02*
X1645413D01*
G01X1646357Y651890D02*
X1640472D01*
G01Y651850D02*
X1646396D01*
G01X1659252Y650886D02*
X1655315D01*
G01X1646396Y650748D02*
X1640472D01*
G01X1646357Y650709D02*
X1640472D01*
G01X1645413Y650551D02*
X1646398D01*
G01X1645453Y650512D02*
X1646358D01*
G01X1660433Y649705D02*
X1656496D01*
G01X1659823Y649429D02*
X1658839D01*
G01X1658840Y648937D02*
X1664173D01*
G01Y648898D02*
X1659825D01*
G01X1646850Y648543D02*
X1643504D01*
G01X1658839Y694133D02*
X1659794Y694134D01*
G01X1659823Y692363D02*
X1658839Y692362D01*
G01Y689133D02*
X1659794Y689134D01*
G01X1659823Y687363D02*
X1658839Y687362D01*
G01Y684133D02*
X1659794Y684134D01*
G01X1659823Y682363D02*
X1658839Y682362D01*
G01Y679133D02*
X1659794Y679134D01*
G01X1659823Y677363D02*
X1658839Y677362D01*
G01Y674133D02*
X1659794Y674134D01*
G01X1659823Y672363D02*
X1658839Y672362D01*
G01Y649133D02*
X1659794Y649134D01*
G01X1659810Y698929D02*
X1659821Y698913D01*
G01X1659786Y698937D02*
X1659810Y698929D01*
G01Y703929D02*
X1659821Y703913D01*
G01X1659786Y703937D02*
X1659810Y703929D01*
G01Y708929D02*
X1659821Y708913D01*
G01X1659786Y708937D02*
X1659810Y708929D01*
G01Y713929D02*
X1659821Y713913D01*
G01X1659786Y713937D02*
X1659810Y713929D01*
G01Y718929D02*
X1659821Y718913D01*
G01X1659786Y718937D02*
X1659810Y718929D01*
G01Y723929D02*
X1659821Y723913D01*
G01X1659786Y723937D02*
X1659810Y723929D01*
G01Y728929D02*
X1659821Y728913D01*
G01X1659786Y728937D02*
X1659810Y728929D01*
G01Y733929D02*
X1659821Y733913D01*
G01X1659786Y733937D02*
X1659810Y733929D01*
G01Y738929D02*
X1659821Y738913D01*
G01X1659786Y738937D02*
X1659810Y738929D01*
G01Y743929D02*
X1659821Y743913D01*
G01X1659786Y743937D02*
X1659810Y743929D01*
G01X1659823Y698904D02*
Y698911D01*
G01X1659824Y698900D02*
X1659823Y698904D01*
G01X1659825Y698898D02*
X1659824Y698900D01*
G01X1659823Y703904D02*
Y703911D01*
G01X1659824Y703900D02*
X1659823Y703904D01*
G01X1659825Y703898D02*
X1659824Y703900D01*
G01X1659823Y708904D02*
Y708911D01*
G01X1659824Y708900D02*
X1659823Y708904D01*
G01X1659825Y708898D02*
X1659824Y708900D01*
G01X1659823Y713904D02*
Y713911D01*
G01X1659824Y713900D02*
X1659823Y713904D01*
G01X1659825Y713898D02*
X1659824Y713900D01*
G01X1659823Y718904D02*
Y718911D01*
G01X1659824Y718900D02*
X1659823Y718904D01*
G01X1659825Y718898D02*
X1659824Y718900D01*
G01X1659823Y723904D02*
Y723911D01*
G01X1659824Y723900D02*
X1659823Y723904D01*
G01X1659825Y723898D02*
X1659824Y723900D01*
G01X1659823Y728904D02*
Y728911D01*
G01X1659824Y728900D02*
X1659823Y728904D01*
G01X1659825Y728898D02*
X1659824Y728900D01*
G01X1659823Y733904D02*
Y733911D01*
G01X1659824Y733900D02*
X1659823Y733904D01*
G01X1659825Y733898D02*
X1659824Y733900D01*
G01X1659823Y738904D02*
Y738911D01*
G01X1659824Y738900D02*
X1659823Y738904D01*
G01X1659825Y738898D02*
X1659824Y738900D01*
G01X1659823Y743904D02*
Y743911D01*
G01X1659824Y743900D02*
X1659823Y743904D01*
G01X1659825Y743898D02*
X1659824Y743900D01*
G01X1659823Y742552D02*
Y742543D01*
G01X1659824Y742557D02*
X1659823Y742552D01*
G01X1659826Y742559D02*
X1659824Y742557D01*
G01X1659823Y737552D02*
Y737543D01*
G01X1659824Y737557D02*
X1659823Y737552D01*
G01X1659826Y737559D02*
X1659824Y737557D01*
G01X1659823Y732552D02*
Y732543D01*
G01X1659824Y732557D02*
X1659823Y732552D01*
G01X1659826Y732559D02*
X1659824Y732557D01*
G01X1659823Y727552D02*
Y727543D01*
G01X1659824Y727557D02*
X1659823Y727552D01*
G01X1659826Y727559D02*
X1659824Y727557D01*
G01X1659823Y722552D02*
Y722543D01*
G01X1659824Y722557D02*
X1659823Y722552D01*
G01X1659826Y722559D02*
X1659824Y722557D01*
G01X1659823Y717552D02*
Y717543D01*
G01X1659824Y717557D02*
X1659823Y717552D01*
G01X1659826Y717559D02*
X1659824Y717557D01*
G01X1659823Y712552D02*
Y712543D01*
G01X1659824Y712557D02*
X1659823Y712552D01*
G01X1659826Y712559D02*
X1659824Y712557D01*
G01X1659823Y707552D02*
Y707543D01*
G01X1659824Y707557D02*
X1659823Y707552D01*
G01X1659826Y707559D02*
X1659824Y707557D01*
G01X1659823Y702552D02*
Y702543D01*
G01X1659824Y702557D02*
X1659823Y702552D01*
G01X1659826Y702559D02*
X1659824Y702557D01*
G01X1659823Y697552D02*
Y697543D01*
G01X1659824Y697557D02*
X1659823Y697552D01*
G01X1659826Y697559D02*
X1659824Y697557D01*
G01X1658839Y698944D02*
Y698954D01*
G01Y698939D02*
Y698944D01*
G01X1658840Y698937D02*
X1658839Y698939D01*
G01Y703944D02*
Y703954D01*
G01Y703939D02*
Y703944D01*
G01X1658840Y703937D02*
X1658839Y703939D01*
G01Y708944D02*
Y708954D01*
G01Y708939D02*
Y708944D01*
G01X1658840Y708937D02*
X1658839Y708939D01*
G01Y713944D02*
Y713954D01*
G01Y713939D02*
Y713944D01*
G01X1658840Y713937D02*
X1658839Y713939D01*
G01Y718944D02*
Y718954D01*
G01Y718939D02*
Y718944D01*
G01X1658840Y718937D02*
X1658839Y718939D01*
G01Y723944D02*
Y723954D01*
G01Y723939D02*
Y723944D01*
G01X1658840Y723937D02*
X1658839Y723939D01*
G01Y728944D02*
Y728954D01*
G01Y728939D02*
Y728944D01*
G01X1658840Y728937D02*
X1658839Y728939D01*
G01Y733944D02*
Y733954D01*
G01Y733939D02*
Y733944D01*
G01X1658840Y733937D02*
X1658839Y733939D01*
G01Y738944D02*
Y738954D01*
G01Y738939D02*
Y738944D01*
G01X1658840Y738937D02*
X1658839Y738939D01*
G01Y743944D02*
Y743954D01*
G01Y743939D02*
Y743944D01*
G01X1658840Y743937D02*
X1658839Y743939D01*
G01X1659815Y699081D02*
X1659823Y699055D01*
G01X1659805Y699107D02*
X1659815Y699081D01*
G01X1659794Y699134D02*
X1659805Y699107D01*
G01X1659815Y704081D02*
X1659823Y704055D01*
G01X1659805Y704107D02*
X1659815Y704081D01*
G01X1659794Y704134D02*
X1659805Y704107D01*
G01X1659815Y709081D02*
X1659823Y709055D01*
G01X1659805Y709107D02*
X1659815Y709081D01*
G01X1659794Y709134D02*
X1659805Y709107D01*
G01X1659815Y714081D02*
X1659823Y714055D01*
G01X1659805Y714107D02*
X1659815Y714081D01*
G01X1659794Y714134D02*
X1659805Y714107D01*
G01X1659815Y719081D02*
X1659823Y719055D01*
G01X1659805Y719107D02*
X1659815Y719081D01*
G01X1659794Y719134D02*
X1659805Y719107D01*
G01X1659815Y724081D02*
X1659823Y724055D01*
G01X1659805Y724107D02*
X1659815Y724081D01*
G01X1659794Y724134D02*
X1659805Y724107D01*
G01X1659815Y729081D02*
X1659823Y729055D01*
G01X1659805Y729107D02*
X1659815Y729081D01*
G01X1659794Y729134D02*
X1659805Y729107D01*
G01X1659815Y734081D02*
X1659823Y734055D01*
G01X1659805Y734107D02*
X1659815Y734081D01*
G01X1659794Y734134D02*
X1659805Y734107D01*
G01X1659815Y739081D02*
X1659823Y739055D01*
G01X1659805Y739107D02*
X1659815Y739081D01*
G01X1659794Y739134D02*
X1659805Y739107D01*
G01X1659815Y744081D02*
X1659823Y744055D01*
G01X1659805Y744107D02*
X1659815Y744081D01*
G01X1659794Y744134D02*
X1659805Y744107D01*
G01X1659790Y699035D02*
X1659794Y699134D01*
G01X1659784Y698963D02*
X1659790Y699035D01*
G01X1659786Y698937D02*
X1659784Y698963D01*
G01X1659790Y704035D02*
X1659794Y704134D01*
G01X1659784Y703963D02*
X1659790Y704035D01*
G01X1659786Y703937D02*
X1659784Y703963D01*
G01X1659790Y709035D02*
X1659794Y709134D01*
G01X1659784Y708963D02*
X1659790Y709035D01*
G01X1659786Y708937D02*
X1659784Y708963D01*
G01X1659790Y714035D02*
X1659794Y714134D01*
G01X1659784Y713963D02*
X1659790Y714035D01*
G01X1659786Y713937D02*
X1659784Y713963D01*
G01X1659790Y719035D02*
X1659794Y719134D01*
G01X1659784Y718963D02*
X1659790Y719035D01*
G01X1659786Y718937D02*
X1659784Y718963D01*
G01X1659790Y724035D02*
X1659794Y724134D01*
G01X1659784Y723963D02*
X1659790Y724035D01*
G01X1659786Y723937D02*
X1659784Y723963D01*
G01X1659790Y729035D02*
X1659794Y729134D01*
G01X1659784Y728963D02*
X1659790Y729035D01*
G01X1659786Y728937D02*
X1659784Y728963D01*
G01X1659790Y734035D02*
X1659794Y734134D01*
G01X1659784Y733963D02*
X1659790Y734035D01*
G01X1659786Y733937D02*
X1659784Y733963D01*
G01X1659790Y739035D02*
X1659794Y739134D01*
G01X1659784Y738963D02*
X1659790Y739035D01*
G01X1659786Y738937D02*
X1659784Y738963D01*
G01X1659790Y744035D02*
X1659794Y744134D01*
G01X1659784Y743963D02*
X1659790Y744035D01*
G01X1659786Y743937D02*
X1659784Y743963D01*
G01X1658839Y742557D02*
X1658840Y742559D01*
G01X1658839Y742552D02*
Y742557D01*
G01Y742543D02*
Y742552D01*
G01Y737557D02*
X1658840Y737559D01*
G01X1658839Y737552D02*
Y737557D01*
G01Y737543D02*
Y737552D01*
G01Y732557D02*
X1658840Y732559D01*
G01X1658839Y732552D02*
Y732557D01*
G01Y732543D02*
Y732552D01*
G01Y727557D02*
X1658840Y727559D01*
G01X1658839Y727552D02*
Y727557D01*
G01Y727543D02*
Y727552D01*
G01Y722557D02*
X1658840Y722559D01*
G01X1658839Y722552D02*
Y722557D01*
G01Y722543D02*
Y722552D01*
G01Y717557D02*
X1658840Y717559D01*
G01X1658839Y717552D02*
Y717557D01*
G01Y717543D02*
Y717552D01*
G01Y712557D02*
X1658840Y712559D01*
G01X1658839Y712552D02*
Y712557D01*
G01Y712543D02*
Y712552D01*
G01Y707557D02*
X1658840Y707559D01*
G01X1658839Y707552D02*
Y707557D01*
G01Y707543D02*
Y707552D01*
G01Y702557D02*
X1658840Y702559D01*
G01X1658839Y702552D02*
Y702557D01*
G01Y702543D02*
Y702552D01*
G01Y697557D02*
X1658840Y697559D01*
G01X1658839Y697552D02*
Y697557D01*
G01Y697543D02*
Y697552D01*
G01X1659806Y698932D02*
X1659786Y698937D01*
G01X1659820Y698918D02*
X1659806Y698932D01*
G01X1659825Y698898D02*
X1659820Y698918D01*
G01X1659806Y703932D02*
X1659786Y703937D01*
G01X1659820Y703918D02*
X1659806Y703932D01*
G01X1659825Y703898D02*
X1659820Y703918D01*
G01X1659806Y708932D02*
X1659786Y708937D01*
G01X1659820Y708918D02*
X1659806Y708932D01*
G01X1659825Y708898D02*
X1659820Y708918D01*
G01X1659806Y713932D02*
X1659786Y713937D01*
G01X1659820Y713918D02*
X1659806Y713932D01*
G01X1659825Y713898D02*
X1659820Y713918D01*
G01X1659806Y718932D02*
X1659786Y718937D01*
G01X1659820Y718918D02*
X1659806Y718932D01*
G01X1659825Y718898D02*
X1659820Y718918D01*
G01X1659806Y723932D02*
X1659786Y723937D01*
G01X1659820Y723918D02*
X1659806Y723932D01*
G01X1659825Y723898D02*
X1659820Y723918D01*
G01X1659806Y728932D02*
X1659786Y728937D01*
G01X1659820Y728918D02*
X1659806Y728932D01*
G01X1659825Y728898D02*
X1659820Y728918D01*
G01X1659806Y733932D02*
X1659786Y733937D01*
G01X1659820Y733918D02*
X1659806Y733932D01*
G01X1659825Y733898D02*
X1659820Y733918D01*
G01X1659806Y738932D02*
X1659786Y738937D01*
G01X1659820Y738918D02*
X1659806Y738932D01*
G01X1659825Y738898D02*
X1659820Y738918D01*
G01X1659806Y743932D02*
X1659786Y743937D01*
G01X1659820Y743918D02*
X1659806Y743932D01*
G01X1659825Y743898D02*
X1659820Y743918D01*
G01X1659823Y698911D02*
Y698920D01*
G01Y703911D02*
Y703920D01*
G01Y708911D02*
Y708920D01*
G01Y713911D02*
Y713920D01*
G01Y718911D02*
Y718920D01*
G01Y723911D02*
Y723920D01*
G01Y728911D02*
Y728920D01*
G01Y733911D02*
Y733920D01*
G01Y738911D02*
Y738920D01*
G01Y743911D02*
Y743920D01*
G01X1664173Y742559D02*
Y743937D01*
G01Y737559D02*
Y738937D01*
G01Y732559D02*
Y733937D01*
G01Y727559D02*
Y728937D01*
G01Y722559D02*
Y723937D01*
G01Y717559D02*
Y718937D01*
G01Y712559D02*
Y713937D01*
G01Y707559D02*
Y708937D01*
G01Y702559D02*
Y703937D01*
G01Y697559D02*
Y698937D01*
G01X1661004D02*
Y697559D01*
G01Y703937D02*
Y702559D01*
G01Y708937D02*
Y707559D01*
G01Y713937D02*
Y712559D01*
G01Y718937D02*
Y717559D01*
G01Y723937D02*
Y722559D01*
G01Y728937D02*
Y727559D01*
G01Y733937D02*
Y732559D01*
G01Y738937D02*
Y737559D01*
G01Y743937D02*
Y742559D01*
G01X1659823Y742067D02*
Y744429D01*
G01Y737067D02*
Y739429D01*
G01Y732067D02*
Y734429D01*
G01Y727067D02*
Y729429D01*
G01Y722067D02*
Y724429D01*
G01Y717067D02*
Y719429D01*
G01Y712067D02*
Y714429D01*
G01Y707067D02*
Y709429D01*
G01Y702067D02*
Y704429D01*
G01Y697067D02*
Y699429D01*
G01X1658839D02*
Y697067D01*
G01Y704429D02*
Y702067D01*
G01Y709429D02*
Y707067D01*
G01Y714429D02*
Y712067D01*
G01Y719429D02*
Y717067D01*
G01Y724429D02*
Y722067D01*
G01Y729429D02*
Y727067D01*
G01Y734429D02*
Y732067D01*
G01Y739429D02*
Y737067D01*
G01Y744429D02*
Y742067D01*
G01X1659823Y744429D02*
X1658839D01*
G01X1658840Y743937D02*
X1664173D01*
G01Y743898D02*
X1659825D01*
G01X1664173Y742559D02*
X1658840D01*
G01X1658839Y742067D02*
X1659823D01*
G01Y739429D02*
X1658839D01*
G01X1658840Y738937D02*
X1664173D01*
G01Y738898D02*
X1659825D01*
G01X1664173Y737559D02*
X1658840D01*
G01X1658839Y737067D02*
X1659823D01*
G01Y734429D02*
X1658839D01*
G01X1658840Y733937D02*
X1664173D01*
G01Y733898D02*
X1659825D01*
G01X1664173Y732559D02*
X1658840D01*
G01X1658839Y732067D02*
X1659823D01*
G01Y729429D02*
X1658839D01*
G01X1658840Y728937D02*
X1664173D01*
G01Y728898D02*
X1659825D01*
G01X1664173Y727559D02*
X1658840D01*
G01X1658839Y727067D02*
X1659823D01*
G01Y724429D02*
X1658839D01*
G01X1658840Y723937D02*
X1664173D01*
G01Y723898D02*
X1659825D01*
G01X1664173Y722559D02*
X1658840D01*
G01X1658839Y722067D02*
X1659823D01*
G01Y719429D02*
X1658839D01*
G01X1658840Y718937D02*
X1664173D01*
G01Y718898D02*
X1659825D01*
G01X1664173Y717559D02*
X1658840D01*
G01X1658839Y717067D02*
X1659823D01*
G01Y714429D02*
X1658839D01*
G01X1658840Y713937D02*
X1664173D01*
G01Y713898D02*
X1659825D01*
G01X1664173Y712559D02*
X1658840D01*
G01X1658839Y712067D02*
X1659823D01*
G01Y709429D02*
X1658839D01*
G01X1658840Y708937D02*
X1664173D01*
G01Y708898D02*
X1659825D01*
G01X1664173Y707559D02*
X1658840D01*
G01X1658839Y707067D02*
X1659823D01*
G01X1658839Y744133D02*
X1659794Y744134D01*
G01X1659823Y742363D02*
X1658839Y742362D01*
G01Y739133D02*
X1659794Y739134D01*
G01X1659823Y737363D02*
X1658839Y737362D01*
G01Y734133D02*
X1659794Y734134D01*
G01X1659823Y732363D02*
X1658839Y732362D01*
G01Y729133D02*
X1659794Y729134D01*
G01X1659823Y727363D02*
X1658839Y727362D01*
G01Y724133D02*
X1659794Y724134D01*
G01X1659823Y722363D02*
X1658839Y722362D01*
G01Y719133D02*
X1659794Y719134D01*
G01X1659823Y717363D02*
X1658839Y717362D01*
G01Y714133D02*
X1659794Y714134D01*
G01X1659823Y712363D02*
X1658839Y712362D01*
G01Y709133D02*
X1659794Y709134D01*
G01X1659823Y707363D02*
X1658839Y707362D01*
G01X1659823Y704429D02*
X1658839D01*
G01X1658840Y703937D02*
X1664173D01*
G01Y703898D02*
X1659825D01*
G01X1664173Y702559D02*
X1658840D01*
G01X1658839Y702067D02*
X1659823D01*
G01Y699429D02*
X1658839D01*
G01X1658840Y698937D02*
X1664173D01*
G01Y698898D02*
X1659825D01*
G01X1664173Y697559D02*
X1658840D01*
G01X1658839Y697067D02*
X1659823D01*
G01X1658839Y704133D02*
X1659794Y704134D01*
G01X1659823Y702363D02*
X1658839Y702362D01*
G01Y699133D02*
X1659794Y699134D01*
G01X1659823Y697363D02*
X1658839Y697362D01*
G01X1658268Y769429D02*
G03X1657677Y770020I-591J0D01*
G01X1650984D02*
G03X1650394Y769429I1J-591D01*
G01X1653150Y768248D02*
G03Y766280I0J-984D01*
G01X1655512D02*
G03Y768248I0J984D01*
G01X1665157Y768839D02*
G03X1663189Y770807I-1968J0D01*
G01X1645472D02*
G03X1643504Y768839I0J-1968D01*
G01X1651772Y760335D02*
G03X1650591Y759154I0J-1181D01*
G01X1658071D02*
G03X1656890Y760335I-1181J0D01*
G01X1656220Y755059D02*
G03I-1889J0D01*
G01X1656693D02*
G03I-2362J0D01*
G01X1665157Y753091D02*
Y768839D01*
G01X1658268Y763327D02*
Y769429D01*
G01X1658071Y759154D02*
Y750610D01*
G01X1655512Y755650D02*
Y753957D01*
G01X1653150D02*
Y755650D01*
G01X1650591Y750610D02*
Y759154D01*
G01X1650394Y763327D02*
Y769429D01*
G01X1643504Y768839D02*
Y753091D01*
G01X1653150Y755650D02*
X1650839Y759879D01*
G01X1655512Y753957D02*
X1656815Y751988D01*
G01X1651846D02*
X1653150Y753957D01*
G01X1657822Y759879D02*
X1655512Y755650D01*
G01X1665157Y753091D02*
X1661811Y749744D01*
G01X1655315Y747067D02*
X1656496Y748248D01*
G01X1648622D02*
X1649803Y747067D01*
G01X1643504Y753091D02*
X1646850Y749744D01*
G01X1663189Y770807D02*
X1645472D01*
G01X1657677Y770020D02*
X1650984D01*
G01X1655512Y768248D02*
X1653150D01*
G01Y766280D02*
X1655512D01*
G01X1658268Y764902D02*
X1650394D01*
G01Y763327D02*
X1658268D01*
G01X1665157Y760374D02*
X1643504D01*
G01X1651772Y760335D02*
X1656890D01*
G01X1653150Y755650D02*
X1655512D01*
G01X1653150Y753957D02*
X1655512D01*
G01X1646850Y751988D02*
X1661220D01*
G01X1646850Y750610D02*
X1650591D01*
G01X1661220D02*
X1658071D01*
G01X1646850Y749744D02*
X1661811D01*
G01X1648622Y748248D02*
X1656496D01*
G01X1649803Y747067D02*
X1655315D01*
G01X1653839Y829921D02*
G03X1693996I20078J0D01*
G01D02*
G03X1653839I-20078J0D01*
G01X1693996D02*
G03I-20079J0D01*
G01X1659823Y1080308D02*
Y1080299D01*
G01X1659824Y1080313D02*
X1659823Y1080308D01*
G01X1659826Y1080315D02*
X1659824Y1080313D01*
G01X1659823Y1075308D02*
Y1075299D01*
G01X1659824Y1075313D02*
X1659823Y1075308D01*
G01X1659826Y1075315D02*
X1659824Y1075313D01*
G01X1659823Y1070308D02*
Y1070299D01*
G01X1659824Y1070313D02*
X1659823Y1070308D01*
G01X1659826Y1070315D02*
X1659824Y1070313D01*
G01X1659810Y1071685D02*
X1659821Y1071669D01*
G01X1659786Y1071693D02*
X1659810Y1071685D01*
G01Y1076685D02*
X1659821Y1076669D01*
G01X1659786Y1076693D02*
X1659810Y1076685D01*
G01Y1081685D02*
X1659821Y1081669D01*
G01X1659786Y1081693D02*
X1659810Y1081685D01*
G01X1659790Y1071791D02*
X1659794Y1071890D01*
G01X1659784Y1071719D02*
X1659790Y1071791D01*
G01X1659786Y1071693D02*
X1659784Y1071719D01*
G01X1659790Y1076791D02*
X1659794Y1076890D01*
G01X1659784Y1076719D02*
X1659790Y1076791D01*
G01X1659786Y1076693D02*
X1659784Y1076719D01*
G01X1659790Y1081791D02*
X1659794Y1081890D01*
G01X1659784Y1081719D02*
X1659790Y1081791D01*
G01X1659786Y1081693D02*
X1659784Y1081719D01*
G01X1658839Y1080313D02*
X1658840Y1080315D01*
G01X1658839Y1080308D02*
Y1080313D01*
G01Y1080299D02*
Y1080308D01*
G01Y1075313D02*
X1658840Y1075315D01*
G01X1658839Y1075308D02*
Y1075313D01*
G01Y1075299D02*
Y1075308D01*
G01Y1070313D02*
X1658840Y1070315D01*
G01X1658839Y1070308D02*
Y1070313D01*
G01Y1070299D02*
Y1070308D01*
G01X1659823Y1071660D02*
Y1071667D01*
G01X1659824Y1071656D02*
X1659823Y1071660D01*
G01X1659825Y1071654D02*
X1659824Y1071656D01*
G01X1659823Y1076660D02*
Y1076667D01*
G01X1659824Y1076656D02*
X1659823Y1076660D01*
G01X1659825Y1076654D02*
X1659824Y1076656D01*
G01X1659823Y1081660D02*
Y1081667D01*
G01X1659824Y1081656D02*
X1659823Y1081660D01*
G01X1659825Y1081654D02*
X1659824Y1081656D01*
G01X1658839Y1071700D02*
Y1071709D01*
G01Y1071695D02*
Y1071700D01*
G01X1658840Y1071693D02*
X1658839Y1071695D01*
G01Y1076700D02*
Y1076709D01*
G01Y1076695D02*
Y1076700D01*
G01X1658840Y1076693D02*
X1658839Y1076695D01*
G01Y1081700D02*
Y1081709D01*
G01Y1081695D02*
Y1081700D01*
G01X1658840Y1081693D02*
X1658839Y1081695D01*
G01X1659815Y1071837D02*
X1659823Y1071811D01*
G01X1659805Y1071863D02*
X1659815Y1071837D01*
G01X1659794Y1071890D02*
X1659805Y1071863D01*
G01X1659815Y1076837D02*
X1659823Y1076811D01*
G01X1659805Y1076863D02*
X1659815Y1076837D01*
G01X1659794Y1076890D02*
X1659805Y1076863D01*
G01X1659815Y1081837D02*
X1659823Y1081811D01*
G01X1659805Y1081863D02*
X1659815Y1081837D01*
G01X1659794Y1081890D02*
X1659805Y1081863D01*
G01X1659806Y1071688D02*
X1659786Y1071693D01*
G01X1659820Y1071674D02*
X1659806Y1071688D01*
G01X1659825Y1071654D02*
X1659820Y1071674D01*
G01X1659806Y1076688D02*
X1659786Y1076693D01*
G01X1659820Y1076674D02*
X1659806Y1076688D01*
G01X1659825Y1076654D02*
X1659820Y1076674D01*
G01X1659806Y1081688D02*
X1659786Y1081693D01*
G01X1659820Y1081674D02*
X1659806Y1081688D01*
G01X1659825Y1081654D02*
X1659820Y1081674D01*
G01X1650394Y1044823D02*
G03X1650984Y1044232I591J0D01*
G01X1657677D02*
G03X1658268Y1044823I0J591D01*
G01X1655512Y1046004D02*
G03Y1047972I0J984D01*
G01X1653150D02*
G03Y1046004I0J-984D01*
G01X1655433Y1059193D02*
G03I-1102J0D01*
G01X1656890Y1053917D02*
G03X1658071Y1055098I0J1181D01*
G01X1650591D02*
G03X1651772Y1053917I1181J0D01*
G01X1655906Y1059193D02*
G03I-1575J0D01*
G01X1643504Y1045413D02*
G03X1645472Y1043445I1968J0D01*
G01X1663189D02*
G03X1665157Y1045413I0J1968D01*
G01X1655512Y1058602D02*
X1657822Y1054373D01*
G01X1653150Y1060295D02*
X1651846Y1062264D01*
G01X1661811Y1064508D02*
X1665157Y1061161D01*
G01X1655315Y1067185D02*
X1656496Y1066004D01*
G01X1659823Y1071667D02*
Y1071676D01*
G01Y1076667D02*
Y1076676D01*
G01Y1081667D02*
Y1081676D01*
G01X1665157Y1045413D02*
Y1061161D01*
G01X1664173Y1080315D02*
Y1081693D01*
G01Y1075315D02*
Y1076693D01*
G01Y1070315D02*
Y1071693D01*
G01X1661811Y1202500D02*
Y1064508D01*
G01X1661220Y1204744D02*
Y1062264D01*
G01X1661004Y1071693D02*
Y1070315D01*
G01Y1076693D02*
Y1075315D01*
G01Y1081693D02*
Y1080315D01*
G01X1659823Y1079823D02*
Y1082185D01*
G01Y1074823D02*
Y1077185D01*
G01Y1069823D02*
Y1072185D01*
G01Y1071667D02*
Y1071811D01*
G01Y1081667D02*
Y1081811D01*
G01Y1076667D02*
Y1076811D01*
G01X1658839Y1072185D02*
Y1069823D01*
G01Y1077185D02*
Y1074823D01*
G01Y1082185D02*
Y1079823D01*
G01X1658268Y1050925D02*
Y1044823D01*
G01X1658071Y1063642D02*
Y1055098D01*
G01X1656496Y1102461D02*
Y1066004D01*
G01X1655512Y1060295D02*
Y1058602D01*
G01X1655315Y1103642D02*
Y1067185D01*
G01X1653150Y1058602D02*
Y1060295D01*
G01X1650591Y1055098D02*
Y1063642D01*
G01X1650394Y1050925D02*
Y1044823D01*
G01X1649803Y1067185D02*
Y1199823D01*
G01X1648622Y1066004D02*
Y1201004D01*
G01X1646850Y1101299D02*
Y1062264D01*
G01X1643504Y1061161D02*
Y1045413D01*
G01X1650839Y1054373D02*
X1653150Y1058602D01*
G01X1656815Y1062264D02*
X1655512Y1060295D01*
G01X1659823Y1082185D02*
X1658839D01*
G01X1658840Y1081693D02*
X1664173D01*
G01Y1081654D02*
X1659825D01*
G01X1664173Y1080315D02*
X1658840D01*
G01X1658839Y1079823D02*
X1659823D01*
G01Y1077185D02*
X1658839D01*
G01X1658840Y1076693D02*
X1664173D01*
G01Y1076654D02*
X1659825D01*
G01X1664173Y1075315D02*
X1658840D01*
G01X1658839Y1074823D02*
X1659823D01*
G01Y1072185D02*
X1658839D01*
G01X1658840Y1071693D02*
X1664173D01*
G01Y1071654D02*
X1659825D01*
G01X1664173Y1070315D02*
X1658840D01*
G01X1658839Y1069823D02*
X1659823D01*
G01X1655315Y1067185D02*
X1649803D01*
G01X1656496Y1066004D02*
X1648622D01*
G01X1661811Y1064508D02*
X1646850D01*
G01X1658839Y1081889D02*
X1659794Y1081890D01*
G01X1659823Y1080119D02*
X1658839Y1080118D01*
G01Y1076889D02*
X1659794Y1076890D01*
G01X1659823Y1075119D02*
X1658839Y1075118D01*
G01Y1071889D02*
X1659794Y1071890D01*
G01X1659823Y1070119D02*
X1658839Y1070118D01*
G01X1649803Y1067185D02*
X1648622Y1066004D01*
G01X1646850Y1064508D02*
X1643504Y1061161D01*
G01X1658071Y1063642D02*
X1661220D01*
G01X1650591D02*
X1646850D01*
G01Y1062264D02*
X1661220D01*
G01X1655512Y1060295D02*
X1653150D01*
G01X1655512Y1058602D02*
X1653150D01*
G01X1656890Y1053917D02*
X1651772D01*
G01X1665157Y1053878D02*
X1643504D01*
G01X1658268Y1050925D02*
X1650394D01*
G01Y1049350D02*
X1658268D01*
G01X1655512Y1047972D02*
X1653150D01*
G01Y1046004D02*
X1655512D01*
G01X1657677Y1044232D02*
X1650984D01*
G01X1663189Y1043445D02*
X1645472D01*
G01X1646369Y1122364D02*
X1646357Y1122362D01*
G01X1646379Y1122369D02*
X1646369Y1122364D01*
G01Y1119215D02*
X1646357Y1119213D01*
G01X1646379Y1119220D02*
X1646369Y1119215D01*
G01Y1116065D02*
X1646357Y1116063D01*
G01X1646379Y1116070D02*
X1646369Y1116065D01*
G01Y1112915D02*
X1646357Y1112913D01*
G01X1646379Y1112920D02*
X1646369Y1112915D01*
G01Y1109766D02*
X1646357Y1109764D01*
G01X1646379Y1109771D02*
X1646369Y1109766D01*
G01Y1106616D02*
X1646357Y1106614D01*
G01X1646379Y1106621D02*
X1646369Y1106616D01*
G01X1645414Y1123524D02*
X1645413Y1123518D01*
G01X1645416Y1123530D02*
X1645414Y1123524D01*
G01X1645419Y1123536D02*
X1645416Y1123530D01*
G01X1645422Y1123541D02*
X1645419Y1123536D01*
G01X1645427Y1123546D02*
X1645422Y1123541D01*
G01X1645433Y1123550D02*
X1645427Y1123546D01*
G01X1646369Y1103467D02*
X1646357Y1103465D01*
G01X1646379Y1103472D02*
X1646369Y1103467D01*
G01X1646395Y1122376D02*
X1646398Y1122388D01*
G01X1646389Y1122365D02*
X1646395Y1122376D01*
G01X1646378Y1122356D02*
X1646389Y1122365D01*
G01X1646395Y1116076D02*
X1646398Y1116089D01*
G01X1646389Y1116065D02*
X1646395Y1116076D01*
G01X1646378Y1116057D02*
X1646389Y1116065D01*
G01X1646395Y1112927D02*
X1646398Y1112939D01*
G01X1646389Y1112916D02*
X1646395Y1112927D01*
G01X1646378Y1112907D02*
X1646389Y1112916D01*
G01X1646395Y1109777D02*
X1646398Y1109790D01*
G01X1646389Y1109766D02*
X1646395Y1109777D01*
G01X1646378Y1109758D02*
X1646389Y1109766D01*
G01X1646395Y1106628D02*
X1646398Y1106640D01*
G01X1646389Y1106617D02*
X1646395Y1106628D01*
G01X1646378Y1106608D02*
X1646389Y1106617D01*
G01X1646395Y1103478D02*
X1646398Y1103491D01*
G01X1646389Y1103467D02*
X1646395Y1103478D01*
G01X1646378Y1103459D02*
X1646389Y1103467D01*
G01X1645452Y1123548D02*
Y1123555D01*
G01Y1123544D02*
Y1123548D01*
G01X1645450Y1123543D02*
X1645452Y1123544D01*
G01Y1120399D02*
Y1120405D01*
G01Y1120395D02*
Y1120399D01*
G01X1645450Y1120394D02*
X1645452Y1120395D01*
G01Y1117249D02*
Y1117256D01*
G01Y1117245D02*
Y1117249D01*
G01X1645450Y1117244D02*
X1645452Y1117245D01*
G01Y1114100D02*
Y1114106D01*
G01Y1114096D02*
Y1114100D01*
G01X1645450Y1114094D02*
X1645452Y1114096D01*
G01Y1110950D02*
Y1110956D01*
G01Y1110946D02*
Y1110950D01*
G01X1645450Y1110945D02*
X1645452Y1110946D01*
G01Y1107800D02*
Y1107807D01*
G01Y1107796D02*
Y1107800D01*
G01X1645450Y1107795D02*
X1645452Y1107796D01*
G01Y1104651D02*
Y1104657D01*
G01Y1104647D02*
Y1104651D01*
G01X1645450Y1104646D02*
X1645452Y1104647D01*
G01X1645414Y1120374D02*
X1645413Y1120368D01*
G01X1645416Y1120381D02*
X1645414Y1120374D01*
G01X1645419Y1120386D02*
X1645416Y1120381D01*
G01X1645422Y1120392D02*
X1645419Y1120386D01*
G01X1645427Y1120396D02*
X1645422Y1120392D01*
G01X1645433Y1120400D02*
X1645427Y1120396D01*
G01X1645414Y1117225D02*
X1645413Y1117219D01*
G01X1645416Y1117231D02*
X1645414Y1117225D01*
G01X1645419Y1117237D02*
X1645416Y1117231D01*
G01X1645422Y1117242D02*
X1645419Y1117237D01*
G01X1645427Y1117246D02*
X1645422Y1117242D01*
G01X1645433Y1117250D02*
X1645427Y1117246D01*
G01X1645414Y1114075D02*
X1645413Y1114069D01*
G01X1645416Y1114081D02*
X1645414Y1114075D01*
G01X1645419Y1114087D02*
X1645416Y1114081D01*
G01X1645422Y1114093D02*
X1645419Y1114087D01*
G01X1645427Y1114097D02*
X1645422Y1114093D01*
G01X1645433Y1114101D02*
X1645427Y1114097D01*
G01X1645414Y1110926D02*
X1645413Y1110919D01*
G01X1645416Y1110932D02*
X1645414Y1110926D01*
G01X1645419Y1110937D02*
X1645416Y1110932D01*
G01X1645422Y1110943D02*
X1645419Y1110937D01*
G01X1645427Y1110947D02*
X1645422Y1110943D01*
G01X1645433Y1110951D02*
X1645427Y1110947D01*
G01X1645414Y1107776D02*
X1645413Y1107770D01*
G01X1645416Y1107782D02*
X1645414Y1107776D01*
G01X1645419Y1107788D02*
X1645416Y1107782D01*
G01X1645422Y1107793D02*
X1645419Y1107788D01*
G01X1645427Y1107798D02*
X1645422Y1107793D01*
G01X1645433Y1107802D02*
X1645427Y1107798D01*
G01X1645414Y1104626D02*
X1645413Y1104620D01*
G01X1645416Y1104633D02*
X1645414Y1104626D01*
G01X1645419Y1104638D02*
X1645416Y1104633D01*
G01X1645422Y1104644D02*
X1645419Y1104638D01*
G01X1645427Y1104648D02*
X1645422Y1104644D01*
G01X1645433Y1104652D02*
X1645427Y1104648D01*
G01X1645416Y1104626D02*
X1645411Y1104606D01*
G01X1645431Y1104641D02*
X1645416Y1104626D01*
G01X1645450Y1104646D02*
X1645431Y1104641D01*
G01X1645416Y1107776D02*
X1645411Y1107756D01*
G01X1645431Y1107790D02*
X1645416Y1107776D01*
G01X1645450Y1107795D02*
X1645431Y1107790D01*
G01X1645416Y1110925D02*
X1645411Y1110906D01*
G01X1645431Y1110940D02*
X1645416Y1110925D01*
G01X1645450Y1110945D02*
X1645431Y1110940D01*
G01X1645416Y1114075D02*
X1645411Y1114055D01*
G01X1645431Y1114089D02*
X1645416Y1114075D01*
G01X1645450Y1114094D02*
X1645431Y1114089D01*
G01X1645416Y1117224D02*
X1645411Y1117205D01*
G01X1645431Y1117239D02*
X1645416Y1117224D01*
G01X1645450Y1117244D02*
X1645431Y1117239D01*
G01X1645416Y1120374D02*
X1645411Y1120354D01*
G01X1645431Y1120389D02*
X1645416Y1120374D01*
G01X1645450Y1120394D02*
X1645431Y1120389D01*
G01X1645416Y1123524D02*
X1645411Y1123504D01*
G01X1645431Y1123538D02*
X1645416Y1123524D01*
G01X1645450Y1123543D02*
X1645431Y1123538D01*
G01X1646391Y1103484D02*
X1646396Y1103504D01*
G01X1646376Y1103470D02*
X1646391Y1103484D01*
G01X1646357Y1103465D02*
X1646376Y1103470D01*
G01X1646391Y1106634D02*
X1646396Y1106654D01*
G01X1646376Y1106620D02*
X1646391Y1106634D01*
G01X1646357Y1106614D02*
X1646376Y1106620D01*
G01X1646391Y1109783D02*
X1646396Y1109803D01*
G01X1646376Y1109769D02*
X1646391Y1109783D01*
G01X1646357Y1109764D02*
X1646376Y1109769D01*
G01X1646391Y1112933D02*
X1646396Y1112953D01*
G01X1646376Y1112919D02*
X1646391Y1112933D01*
G01X1646357Y1112913D02*
X1646376Y1112919D01*
G01X1646391Y1116083D02*
X1646396Y1116102D01*
G01X1646376Y1116069D02*
X1646391Y1116083D01*
G01X1646357Y1116063D02*
X1646376Y1116069D01*
G01X1646391Y1119232D02*
X1646396Y1119252D01*
G01X1646376Y1119218D02*
X1646391Y1119232D01*
G01X1646357Y1119213D02*
X1646376Y1119218D01*
G01X1646391Y1122382D02*
X1646396Y1122402D01*
G01X1646376Y1122368D02*
X1646391Y1122382D01*
G01X1646357Y1122362D02*
X1646376Y1122368D01*
G01X1645413Y1123510D02*
Y1123518D01*
G01X1645412Y1123506D02*
X1645413Y1123510D01*
G01X1645411Y1123504D02*
X1645412Y1123506D01*
G01X1645413Y1120361D02*
Y1120368D01*
G01X1645412Y1120356D02*
X1645413Y1120361D01*
G01X1645411Y1120354D02*
X1645412Y1120356D01*
G01X1645413Y1117211D02*
Y1117219D01*
G01X1645412Y1117206D02*
X1645413Y1117211D01*
G01X1645411Y1117205D02*
X1645412Y1117206D01*
G01X1645413Y1114061D02*
Y1114069D01*
G01X1645412Y1114057D02*
X1645413Y1114061D01*
G01X1645411Y1114055D02*
X1645412Y1114057D01*
G01X1645413Y1110912D02*
Y1110919D01*
G01X1645412Y1110907D02*
X1645413Y1110912D01*
G01X1645411Y1110906D02*
X1645412Y1110907D01*
G01X1645413Y1107762D02*
Y1107770D01*
G01X1645412Y1107757D02*
X1645413Y1107762D01*
G01X1645411Y1107756D02*
X1645412Y1107757D01*
G01X1646397Y1119231D02*
X1646398Y1119239D01*
G01X1646394Y1119224D02*
X1646397Y1119231D01*
G01X1646391Y1119218D02*
X1646394Y1119224D01*
G01X1646386Y1119212D02*
X1646391Y1119218D01*
G01X1646380Y1119207D02*
X1646386Y1119212D01*
G01X1646373Y1119204D02*
X1646380Y1119207D01*
G01X1646366Y1119202D02*
X1646373Y1119204D01*
G01X1646358Y1119202D02*
X1646366D01*
G01X1659823Y1130308D02*
Y1130299D01*
G01X1659824Y1130313D02*
X1659823Y1130308D01*
G01X1659826Y1130315D02*
X1659824Y1130313D01*
G01X1659823Y1125308D02*
Y1125299D01*
G01X1659824Y1125313D02*
X1659823Y1125308D01*
G01X1659826Y1125315D02*
X1659824Y1125313D01*
G01X1659823Y1100308D02*
Y1100299D01*
G01X1659824Y1100313D02*
X1659823Y1100308D01*
G01X1659826Y1100315D02*
X1659824Y1100313D01*
G01X1659823Y1095308D02*
Y1095299D01*
G01X1659824Y1095313D02*
X1659823Y1095308D01*
G01X1659826Y1095315D02*
X1659824Y1095313D01*
G01X1659823Y1090308D02*
Y1090299D01*
G01X1659824Y1090313D02*
X1659823Y1090308D01*
G01X1659826Y1090315D02*
X1659824Y1090313D01*
G01X1659823Y1085308D02*
Y1085299D01*
G01X1659824Y1085313D02*
X1659823Y1085308D01*
G01X1659826Y1085315D02*
X1659824Y1085313D01*
G01X1645413Y1104613D02*
Y1104620D01*
G01X1645412Y1104608D02*
X1645413Y1104613D01*
G01X1645411Y1104606D02*
X1645412Y1104608D01*
G01X1646375Y1103457D02*
X1646378Y1103459D01*
G01X1646372Y1103456D02*
X1646375Y1103457D01*
G01X1646369Y1103455D02*
X1646372Y1103456D01*
G01X1646365Y1103454D02*
X1646369Y1103455D01*
G01X1646362Y1103454D02*
X1646365D01*
G01X1646358D02*
X1646362D01*
G01X1645436Y1104654D02*
X1645433Y1104652D01*
G01X1645439Y1104655D02*
X1645436Y1104654D01*
G01X1645442Y1104656D02*
X1645439Y1104655D01*
G01X1645446Y1104656D02*
X1645442D01*
G01X1645449Y1104657D02*
X1645446Y1104656D01*
G01X1645453Y1104657D02*
X1645449D01*
G01X1646375Y1106607D02*
X1646378Y1106608D01*
G01X1646372Y1106606D02*
X1646375Y1106607D01*
G01X1646369Y1106604D02*
X1646372Y1106606D01*
G01X1646365Y1106604D02*
X1646369D01*
G01X1646362Y1106603D02*
X1646365Y1106604D01*
G01X1646358Y1106603D02*
X1646362D01*
G01X1645436Y1107803D02*
X1645433Y1107802D01*
G01X1645439Y1107804D02*
X1645436Y1107803D01*
G01X1645442Y1107806D02*
X1645439Y1107804D01*
G01X1645446Y1107806D02*
X1645442D01*
G01X1645449Y1107807D02*
X1645446Y1107806D01*
G01X1645453Y1107807D02*
X1645449D01*
G01X1646375Y1109756D02*
X1646378Y1109758D01*
G01X1646372Y1109755D02*
X1646375Y1109756D01*
G01X1646369Y1109754D02*
X1646372Y1109755D01*
G01X1646365Y1109753D02*
X1646369Y1109754D01*
G01X1646362Y1109753D02*
X1646365D01*
G01X1646358D02*
X1646362D01*
G01X1645436Y1110953D02*
X1645433Y1110951D01*
G01X1645439Y1110954D02*
X1645436Y1110953D01*
G01X1645442Y1110955D02*
X1645439Y1110954D01*
G01X1645446Y1110956D02*
X1645442Y1110955D01*
G01X1645449Y1110956D02*
X1645446D01*
G01X1645453D02*
X1645449D01*
G01X1646375Y1112906D02*
X1646378Y1112907D01*
G01X1646372Y1112905D02*
X1646375Y1112906D01*
G01X1646369Y1112904D02*
X1646372Y1112905D01*
G01X1646365Y1112903D02*
X1646369Y1112904D01*
G01X1646362Y1112902D02*
X1646365Y1112903D01*
G01X1646358Y1112902D02*
X1646362D01*
G01X1645436Y1114102D02*
X1645433Y1114101D01*
G01X1645439Y1114104D02*
X1645436Y1114102D01*
G01X1645442Y1114105D02*
X1645439Y1114104D01*
G01X1645446Y1114105D02*
X1645442D01*
G01X1645449Y1114106D02*
X1645446Y1114105D01*
G01X1645453Y1114106D02*
X1645449D01*
G01X1646375Y1116056D02*
X1646378Y1116057D01*
G01X1646372Y1116054D02*
X1646375Y1116056D01*
G01X1646369Y1116053D02*
X1646372Y1116054D01*
G01X1646365Y1116052D02*
X1646369Y1116053D01*
G01X1646362Y1116052D02*
X1646365D01*
G01X1646358D02*
X1646362D01*
G01X1645436Y1117252D02*
X1645433Y1117250D01*
G01X1645439Y1117253D02*
X1645436Y1117252D01*
G01X1645442Y1117254D02*
X1645439Y1117253D01*
G01X1645446Y1117255D02*
X1645442Y1117254D01*
G01X1645449Y1117256D02*
X1645446Y1117255D01*
G01X1645453Y1117256D02*
X1645449D01*
G01X1645436Y1120402D02*
X1645433Y1120400D01*
G01X1645439Y1120403D02*
X1645436Y1120402D01*
G01X1645442Y1120404D02*
X1645439Y1120403D01*
G01X1645446Y1120404D02*
X1645442D01*
G01X1645449Y1120405D02*
X1645446Y1120404D01*
G01X1645453Y1120405D02*
X1645449D01*
G01X1646375Y1122355D02*
X1646378Y1122356D01*
G01X1646372Y1122354D02*
X1646375Y1122355D01*
G01X1646369Y1122352D02*
X1646372Y1122354D01*
G01X1646365Y1122352D02*
X1646369D01*
G01X1646362Y1122351D02*
X1646365Y1122352D01*
G01X1646358Y1122351D02*
X1646362D01*
G01X1645436Y1123551D02*
X1645433Y1123550D01*
G01X1645439Y1123552D02*
X1645436Y1123551D01*
G01X1645442Y1123554D02*
X1645439Y1123552D01*
G01X1645446Y1123554D02*
X1645442D01*
G01X1645449Y1123555D02*
X1645446Y1123554D01*
G01X1645453Y1123555D02*
X1645449D01*
G01X1645413Y1106648D02*
Y1106640D01*
G01X1645412Y1106652D02*
X1645413Y1106648D01*
G01X1645411Y1106650D02*
X1645412Y1106652D01*
G01X1646358Y1123548D02*
Y1123555D01*
G01X1646357Y1123545D02*
X1646358Y1123548D01*
G01X1646357Y1123543D02*
Y1123545D01*
G01X1646358Y1120399D02*
Y1120405D01*
G01X1646357Y1120395D02*
X1646358Y1120399D01*
G01X1646357Y1120394D02*
Y1120395D01*
G01X1646358Y1117249D02*
Y1117256D01*
G01X1646357Y1117246D02*
X1646358Y1117249D01*
G01X1646357Y1117244D02*
Y1117246D01*
G01X1646358Y1114100D02*
Y1114106D01*
G01X1646357Y1114096D02*
X1646358Y1114100D01*
G01X1646357Y1114094D02*
Y1114096D01*
G01X1646358Y1110950D02*
Y1110956D01*
G01X1646357Y1110946D02*
X1646358Y1110950D01*
G01X1646357Y1110945D02*
Y1110946D01*
G01X1646358Y1107800D02*
Y1107807D01*
G01X1646357Y1107797D02*
X1646358Y1107800D01*
G01X1646357Y1107795D02*
Y1107797D01*
G01X1646358Y1104651D02*
Y1104657D01*
G01X1646357Y1104647D02*
X1646358Y1104651D01*
G01X1646357Y1104646D02*
Y1104647D01*
G01X1646388Y1104644D02*
X1646392Y1104639D01*
G01X1646383Y1104648D02*
X1646388Y1104644D01*
G01X1646378Y1104652D02*
X1646383Y1104648D01*
G01X1646372Y1104655D02*
X1646378Y1104652D01*
G01X1646365Y1104657D02*
X1646372Y1104655D01*
G01X1646358Y1104657D02*
X1646365D01*
G01X1646388Y1107794D02*
X1646392Y1107789D01*
G01X1646383Y1107798D02*
X1646388Y1107794D01*
G01X1646378Y1107802D02*
X1646383Y1107798D01*
G01X1646372Y1107804D02*
X1646378Y1107802D01*
G01X1646365Y1107806D02*
X1646372Y1107804D01*
G01X1646358Y1107807D02*
X1646365Y1107806D01*
G01X1646388Y1110943D02*
X1646392Y1110938D01*
G01X1646383Y1110948D02*
X1646388Y1110943D01*
G01X1646378Y1110952D02*
X1646383Y1110948D01*
G01X1646372Y1110954D02*
X1646378Y1110952D01*
G01X1646365Y1110956D02*
X1646372Y1110954D01*
G01X1646358Y1110956D02*
X1646365D01*
G01X1646388Y1114093D02*
X1646392Y1114088D01*
G01X1646383Y1114097D02*
X1646388Y1114093D01*
G01X1646378Y1114101D02*
X1646383Y1114097D01*
G01X1646372Y1114104D02*
X1646378Y1114101D01*
G01X1646365Y1114106D02*
X1646372Y1114104D01*
G01X1646358Y1114106D02*
X1646365D01*
G01X1646388Y1117243D02*
X1646392Y1117237D01*
G01X1646383Y1117247D02*
X1646388Y1117243D01*
G01X1646378Y1117251D02*
X1646383Y1117247D01*
G01X1646372Y1117253D02*
X1646378Y1117251D01*
G01X1646365Y1117255D02*
X1646372Y1117253D01*
G01X1646358Y1117256D02*
X1646365Y1117255D01*
G01X1646388Y1120392D02*
X1646392Y1120387D01*
G01X1646383Y1120396D02*
X1646388Y1120392D01*
G01X1646378Y1120400D02*
X1646383Y1120396D01*
G01X1646372Y1120403D02*
X1646378Y1120400D01*
G01X1646365Y1120405D02*
X1646372Y1120403D01*
G01X1646358Y1120405D02*
X1646365D01*
G01X1646388Y1123542D02*
X1646392Y1123537D01*
G01X1646383Y1123546D02*
X1646388Y1123542D01*
G01X1646378Y1123550D02*
X1646383Y1123546D01*
G01X1646372Y1123552D02*
X1646378Y1123550D01*
G01X1646365Y1123554D02*
X1646372Y1123552D01*
G01X1646358Y1123555D02*
X1646365Y1123554D01*
G01X1645414Y1103483D02*
X1645413Y1103491D01*
G01X1645417Y1103476D02*
X1645414Y1103483D01*
G01X1645420Y1103470D02*
X1645417Y1103476D01*
G01X1645425Y1103464D02*
X1645420Y1103470D01*
G01X1645431Y1103459D02*
X1645425Y1103464D01*
G01X1645438Y1103456D02*
X1645431Y1103459D01*
G01X1645445Y1103454D02*
X1645438Y1103456D01*
G01X1645453Y1103454D02*
X1645445D01*
G01X1645414Y1106633D02*
X1645413Y1106640D01*
G01X1645417Y1106626D02*
X1645414Y1106633D01*
G01X1645420Y1106620D02*
X1645417Y1106626D01*
G01X1645425Y1106614D02*
X1645420Y1106620D01*
G01X1645431Y1106609D02*
X1645425Y1106614D01*
G01X1645438Y1106606D02*
X1645431Y1106609D01*
G01X1645445Y1106604D02*
X1645438Y1106606D01*
G01X1645453Y1106603D02*
X1645445Y1106604D01*
G01X1645414Y1109782D02*
X1645413Y1109790D01*
G01X1645417Y1109776D02*
X1645414Y1109782D01*
G01X1645420Y1109769D02*
X1645417Y1109776D01*
G01X1645425Y1109763D02*
X1645420Y1109769D01*
G01X1645431Y1109759D02*
X1645425Y1109763D01*
G01X1645438Y1109756D02*
X1645431Y1109759D01*
G01X1645445Y1109754D02*
X1645438Y1109756D01*
G01X1645453Y1109753D02*
X1645445Y1109754D01*
G01X1645414Y1112932D02*
X1645413Y1112939D01*
G01X1645417Y1112925D02*
X1645414Y1112932D01*
G01X1645420Y1112919D02*
X1645417Y1112925D01*
G01X1645425Y1112913D02*
X1645420Y1112919D01*
G01X1645431Y1112908D02*
X1645425Y1112913D01*
G01X1645438Y1112905D02*
X1645431Y1112908D01*
G01X1645445Y1112903D02*
X1645438Y1112905D01*
G01X1645453Y1112902D02*
X1645445Y1112903D01*
G01X1645414Y1116081D02*
X1645413Y1116089D01*
G01X1645417Y1116075D02*
X1645414Y1116081D01*
G01X1645420Y1116069D02*
X1645417Y1116075D01*
G01X1645425Y1116063D02*
X1645420Y1116069D01*
G01X1645431Y1116058D02*
X1645425Y1116063D01*
G01X1645438Y1116055D02*
X1645431Y1116058D01*
G01X1645445Y1116053D02*
X1645438Y1116055D01*
G01X1645453Y1116052D02*
X1645445Y1116053D01*
G01X1645414Y1119231D02*
X1645413Y1119239D01*
G01X1645417Y1119224D02*
X1645414Y1119231D01*
G01X1645420Y1119218D02*
X1645417Y1119224D01*
G01X1645425Y1119212D02*
X1645420Y1119218D01*
G01X1645431Y1119207D02*
X1645425Y1119212D01*
G01X1645438Y1119204D02*
X1645431Y1119207D01*
G01X1645445Y1119202D02*
X1645438Y1119204D01*
G01X1645453Y1119202D02*
X1645445D01*
G01X1645414Y1122381D02*
X1645413Y1122388D01*
G01X1645417Y1122374D02*
X1645414Y1122381D01*
G01X1645420Y1122368D02*
X1645417Y1122374D01*
G01X1645425Y1122362D02*
X1645420Y1122368D01*
G01X1645431Y1122357D02*
X1645425Y1122362D01*
G01X1645438Y1122354D02*
X1645431Y1122357D01*
G01X1645445Y1122352D02*
X1645438Y1122354D01*
G01X1645453Y1122351D02*
X1645445Y1122352D01*
G01X1646367Y1104644D02*
X1646377Y1104640D01*
G01X1646357Y1104646D02*
X1646367Y1104644D01*
G01Y1107794D02*
X1646377Y1107790D01*
G01X1646357Y1107795D02*
X1646367Y1107794D01*
G01Y1110944D02*
X1646377Y1110939D01*
G01X1646357Y1110945D02*
X1646367Y1110944D01*
G01Y1114093D02*
X1646377Y1114089D01*
G01X1646357Y1114094D02*
X1646367Y1114093D01*
G01Y1117243D02*
X1646377Y1117239D01*
G01X1646357Y1117244D02*
X1646367Y1117243D01*
G01Y1120393D02*
X1646377Y1120388D01*
G01X1646357Y1120394D02*
X1646367Y1120393D01*
G01Y1123542D02*
X1646377Y1123538D01*
G01X1646357Y1123543D02*
X1646367Y1123542D01*
G01X1646398Y1123510D02*
Y1123517D01*
G01X1646397Y1123506D02*
X1646398Y1123510D01*
G01X1646396Y1123504D02*
X1646397Y1123506D01*
G01X1646398Y1120361D02*
Y1120368D01*
G01X1646397Y1120356D02*
X1646398Y1120361D01*
G01X1646396Y1120354D02*
X1646397Y1120356D01*
G01X1646398Y1117211D02*
Y1117218D01*
G01X1646397Y1117207D02*
X1646398Y1117211D01*
G01X1646396Y1117205D02*
X1646397Y1117207D01*
G01X1646398Y1114061D02*
Y1114069D01*
G01X1646397Y1114057D02*
X1646398Y1114061D01*
G01X1646396Y1114055D02*
X1646397Y1114057D01*
G01X1646398Y1110912D02*
Y1110919D01*
G01X1646397Y1110907D02*
X1646398Y1110912D01*
G01X1646396Y1110906D02*
X1646397Y1110907D01*
G01X1646398Y1107762D02*
Y1107769D01*
G01X1646397Y1107758D02*
X1646398Y1107762D01*
G01X1646396Y1107756D02*
X1646397Y1107758D01*
G01X1646398Y1104613D02*
Y1104620D01*
G01X1646397Y1104608D02*
X1646398Y1104613D01*
G01X1646396Y1104606D02*
X1646397Y1104608D01*
G01X1645413Y1112947D02*
Y1112939D01*
G01X1645412Y1112952D02*
X1645413Y1112947D01*
G01X1645411Y1112949D02*
X1645412Y1112952D01*
G01X1645413Y1106644D02*
Y1106640D01*
G01X1645415Y1106638D02*
X1645413Y1106644D01*
G01X1645427Y1106622D02*
X1645415Y1106638D01*
G01X1645452Y1106614D02*
X1645427Y1106622D01*
G01X1645413Y1109794D02*
Y1109790D01*
G01X1645415Y1109787D02*
X1645413Y1109794D01*
G01X1645426Y1109772D02*
X1645415Y1109787D01*
G01X1645451Y1109764D02*
X1645426Y1109772D01*
G01X1645413Y1116093D02*
Y1116089D01*
G01X1645415Y1116087D02*
X1645413Y1116093D01*
G01X1645426Y1116071D02*
X1645415Y1116087D01*
G01X1645451Y1116063D02*
X1645426Y1116071D01*
G01X1645413Y1119243D02*
Y1119239D01*
G01X1645415Y1119236D02*
X1645413Y1119243D01*
G01X1645426Y1119221D02*
X1645415Y1119236D01*
G01X1645451Y1119213D02*
X1645426Y1119221D01*
G01X1645413Y1103494D02*
Y1103491D01*
G01X1645415Y1103488D02*
X1645413Y1103494D01*
G01X1645426Y1103473D02*
X1645415Y1103488D01*
G01X1645451Y1103465D02*
X1645426Y1103473D01*
G01X1645413Y1122392D02*
Y1122388D01*
G01X1645415Y1122386D02*
X1645413Y1122392D01*
G01X1645426Y1122370D02*
X1645415Y1122386D01*
G01X1645451Y1122362D02*
X1645426Y1122370D01*
G01X1659810Y1086685D02*
X1659821Y1086669D01*
G01X1659786Y1086693D02*
X1659810Y1086685D01*
G01Y1091685D02*
X1659821Y1091669D01*
G01X1659786Y1091693D02*
X1659810Y1091685D01*
G01Y1096685D02*
X1659821Y1096669D01*
G01X1659786Y1096693D02*
X1659810Y1096685D01*
G01Y1101685D02*
X1659821Y1101669D01*
G01X1659786Y1101693D02*
X1659810Y1101685D01*
G01X1645426Y1123535D02*
X1645450Y1123543D01*
G01X1645415Y1123520D02*
X1645426Y1123535D01*
G01X1645413Y1123514D02*
X1645415Y1123520D01*
G01X1645426Y1120385D02*
X1645450Y1120394D01*
G01X1645415Y1120371D02*
X1645426Y1120385D01*
G01X1645413Y1120364D02*
X1645415Y1120371D01*
G01X1645426Y1117236D02*
X1645450Y1117244D01*
G01X1645415Y1117221D02*
X1645426Y1117236D01*
G01X1645413Y1117215D02*
X1645415Y1117221D01*
G01X1645426Y1114086D02*
X1645450Y1114094D01*
G01X1645415Y1114072D02*
X1645426Y1114086D01*
G01X1645413Y1114065D02*
X1645415Y1114072D01*
G01X1645426Y1110937D02*
X1645450Y1110945D01*
G01X1645415Y1110922D02*
X1645426Y1110937D01*
G01X1645413Y1110915D02*
X1645415Y1110922D01*
G01X1645426Y1107787D02*
X1645450Y1107795D01*
G01X1645415Y1107772D02*
X1645426Y1107787D01*
G01X1645413Y1107766D02*
X1645415Y1107772D01*
G01X1645426Y1104637D02*
X1645450Y1104646D01*
G01X1645415Y1104623D02*
X1645426Y1104637D01*
G01X1645413Y1104616D02*
X1645415Y1104623D01*
G01X1659810Y1126685D02*
X1659821Y1126669D01*
G01X1659786Y1126693D02*
X1659810Y1126685D01*
G01X1645413Y1112943D02*
Y1112939D01*
G01X1645415Y1112938D02*
X1645413Y1112943D01*
G01X1645425Y1112923D02*
X1645415Y1112938D01*
G01X1645448Y1112914D02*
X1645425Y1112923D01*
G01X1659790Y1086791D02*
X1659794Y1086890D01*
G01X1659784Y1086719D02*
X1659790Y1086791D01*
G01X1659786Y1086693D02*
X1659784Y1086719D01*
G01X1659790Y1091791D02*
X1659794Y1091890D01*
G01X1659784Y1091719D02*
X1659790Y1091791D01*
G01X1659786Y1091693D02*
X1659784Y1091719D01*
G01X1659790Y1096791D02*
X1659794Y1096890D01*
G01X1659784Y1096719D02*
X1659790Y1096791D01*
G01X1659786Y1096693D02*
X1659784Y1096719D01*
G01X1659790Y1101791D02*
X1659794Y1101890D01*
G01X1659784Y1101719D02*
X1659790Y1101791D01*
G01X1659786Y1101693D02*
X1659784Y1101719D01*
G01X1659790Y1126791D02*
X1659794Y1126890D01*
G01X1659784Y1126719D02*
X1659790Y1126791D01*
G01X1659786Y1126693D02*
X1659784Y1126719D01*
G01X1645413Y1116096D02*
Y1116089D01*
G01X1645412Y1116101D02*
X1645413Y1116096D01*
G01Y1116092D02*
X1645412Y1116101D01*
G01X1645454Y1123728D02*
X1645453Y1123740D01*
G01X1645450Y1123715D02*
X1645454Y1123728D01*
G01X1645450Y1123701D02*
Y1123715D01*
G01X1645454Y1120578D02*
X1645453Y1120591D01*
G01X1645450Y1120565D02*
X1645454Y1120578D01*
G01X1645450Y1120552D02*
Y1120565D01*
G01X1645454Y1117429D02*
X1645453Y1117441D01*
G01X1645450Y1117416D02*
X1645454Y1117429D01*
G01X1645450Y1117402D02*
Y1117416D01*
G01X1645454Y1114279D02*
X1645453Y1114291D01*
G01X1645450Y1114266D02*
X1645454Y1114279D01*
G01X1645450Y1114252D02*
Y1114266D01*
G01X1645454Y1111130D02*
X1645453Y1111142D01*
G01X1645450Y1111117D02*
X1645454Y1111130D01*
G01X1645450Y1111103D02*
Y1111117D01*
G01X1645454Y1107980D02*
X1645453Y1107992D01*
G01X1645450Y1107967D02*
X1645454Y1107980D01*
G01X1645450Y1107953D02*
Y1107967D01*
G01X1645454Y1104830D02*
X1645453Y1104843D01*
G01X1645450Y1104817D02*
X1645454Y1104830D01*
G01X1645450Y1104804D02*
Y1104817D01*
G01X1658839Y1130313D02*
X1658840Y1130315D01*
G01X1658839Y1130308D02*
Y1130313D01*
G01Y1130299D02*
Y1130308D01*
G01Y1125313D02*
X1658840Y1125315D01*
G01X1658839Y1125308D02*
Y1125313D01*
G01Y1125299D02*
Y1125308D01*
G01Y1100313D02*
X1658840Y1100315D01*
G01X1658839Y1100308D02*
Y1100313D01*
G01Y1100299D02*
Y1100308D01*
G01Y1095313D02*
X1658840Y1095315D01*
G01X1658839Y1095308D02*
Y1095313D01*
G01Y1095299D02*
Y1095308D01*
G01Y1090313D02*
X1658840Y1090315D01*
G01X1658839Y1090308D02*
Y1090313D01*
G01Y1090299D02*
Y1090308D01*
G01Y1085313D02*
X1658840Y1085315D01*
G01X1658839Y1085308D02*
Y1085313D01*
G01Y1085299D02*
Y1085308D01*
G01X1645413Y1122396D02*
Y1122388D01*
G01X1645412Y1122400D02*
X1645413Y1122396D01*
G01X1645412Y1122393D02*
Y1122400D01*
G01X1645450Y1122191D02*
X1645449Y1122204D01*
G01X1645454Y1122178D02*
X1645450Y1122191D01*
G01X1645453Y1122165D02*
X1645454Y1122178D01*
G01X1645450Y1119041D02*
X1645449Y1119055D01*
G01X1645454Y1119028D02*
X1645450Y1119041D01*
G01X1645453Y1119016D02*
X1645454Y1119028D01*
G01X1645450Y1115892D02*
X1645449Y1115905D01*
G01X1645454Y1115879D02*
X1645450Y1115892D01*
G01X1645453Y1115866D02*
X1645454Y1115879D01*
G01X1645450Y1112742D02*
X1645449Y1112756D01*
G01X1645454Y1112729D02*
X1645450Y1112742D01*
G01X1645453Y1112717D02*
X1645454Y1112729D01*
G01X1645450Y1109593D02*
X1645449Y1109606D01*
G01X1645454Y1109580D02*
X1645450Y1109593D01*
G01X1645453Y1109567D02*
X1645454Y1109580D01*
G01X1645450Y1106443D02*
X1645449Y1106456D01*
G01X1645454Y1106430D02*
X1645450Y1106443D01*
G01X1645453Y1106417D02*
X1645454Y1106430D01*
G01X1645450Y1103293D02*
X1645449Y1103307D01*
G01X1645454Y1103280D02*
X1645450Y1103293D01*
G01X1645453Y1103268D02*
X1645454Y1103280D01*
G01X1646361Y1123715D02*
X1646362Y1123701D01*
G01X1646357Y1123728D02*
X1646361Y1123715D01*
G01X1646358Y1123740D02*
X1646357Y1123728D01*
G01X1646361Y1120565D02*
X1646362Y1120552D01*
G01X1646357Y1120578D02*
X1646361Y1120565D01*
G01X1646358Y1120591D02*
X1646357Y1120578D01*
G01X1646361Y1117415D02*
X1646362Y1117402D01*
G01X1646357Y1117428D02*
X1646361Y1117415D01*
G01X1646358Y1117441D02*
X1646357Y1117428D01*
G01X1646361Y1114266D02*
X1646362Y1114252D01*
G01X1646357Y1114279D02*
X1646361Y1114266D01*
G01X1646358Y1114291D02*
X1646357Y1114279D01*
G01X1646361Y1111116D02*
X1646362Y1111103D01*
G01X1646357Y1111129D02*
X1646361Y1111116D01*
G01X1646358Y1111142D02*
X1646357Y1111129D01*
G01X1646361Y1107967D02*
X1646362Y1107953D01*
G01X1646357Y1107980D02*
X1646361Y1107967D01*
G01X1646358Y1107992D02*
X1646357Y1107980D01*
G01X1646361Y1104817D02*
X1646362Y1104804D01*
G01X1646357Y1104830D02*
X1646361Y1104817D01*
G01X1646358Y1104843D02*
X1646357Y1104830D01*
G01X1645413Y1109797D02*
Y1109790D01*
G01X1645412Y1109802D02*
X1645413Y1109797D01*
G01X1645412Y1109795D02*
Y1109802D01*
G01X1645413Y1119246D02*
Y1119239D01*
G01X1645412Y1119251D02*
X1645413Y1119246D01*
G01X1645412Y1119244D02*
Y1119251D01*
G01X1646357Y1122178D02*
X1646358Y1122165D01*
G01X1646360Y1122191D02*
X1646357Y1122178D01*
G01X1646361Y1122204D02*
X1646360Y1122191D01*
G01X1646357Y1119028D02*
X1646358Y1119016D01*
G01X1646360Y1119041D02*
X1646357Y1119028D01*
G01X1646361Y1119055D02*
X1646360Y1119041D01*
G01X1646357Y1115879D02*
X1646358Y1115866D01*
G01X1646360Y1115892D02*
X1646357Y1115879D01*
G01X1646361Y1115905D02*
X1646360Y1115892D01*
G01X1646357Y1112729D02*
X1646358Y1112717D01*
G01X1646360Y1112742D02*
X1646357Y1112729D01*
G01X1646361Y1112756D02*
X1646360Y1112742D01*
G01X1646357Y1109580D02*
X1646358Y1109567D01*
G01X1646360Y1109593D02*
X1646357Y1109580D01*
G01X1646361Y1109606D02*
X1646360Y1109593D01*
G01X1646357Y1106430D02*
X1646358Y1106417D01*
G01X1646360Y1106443D02*
X1646357Y1106430D01*
G01X1646361Y1106456D02*
X1646360Y1106443D01*
G01X1646357Y1103280D02*
X1646358Y1103268D01*
G01X1646360Y1103293D02*
X1646357Y1103280D01*
G01X1646361Y1103307D02*
X1646360Y1103293D01*
G01X1645413Y1103498D02*
Y1103491D01*
G01X1645412Y1103503D02*
X1645413Y1103498D01*
G01X1645412Y1103496D02*
Y1103503D01*
G01X1646366Y1110944D02*
X1646357Y1110945D01*
G01X1646375Y1110941D02*
X1646366Y1110944D01*
G01X1646383Y1110935D02*
X1646375Y1110941D01*
G01X1646366Y1104644D02*
X1646357Y1104646D01*
G01X1646375Y1104641D02*
X1646366Y1104644D01*
G01X1646383Y1104636D02*
X1646375Y1104641D01*
G01X1646366Y1107794D02*
X1646357Y1107795D01*
G01X1646375Y1107791D02*
X1646366Y1107794D01*
G01X1646383Y1107786D02*
X1646375Y1107791D01*
G01X1646366Y1114093D02*
X1646357Y1114094D01*
G01X1646375Y1114090D02*
X1646366Y1114093D01*
G01X1646383Y1114085D02*
X1646375Y1114090D01*
G01X1646366Y1117243D02*
X1646357Y1117244D01*
G01X1646375Y1117240D02*
X1646366Y1117243D01*
G01X1646383Y1117235D02*
X1646375Y1117240D01*
G01X1646366Y1120393D02*
X1646357Y1120394D01*
G01X1646375Y1120389D02*
X1646366Y1120393D01*
G01X1646383Y1120384D02*
X1646375Y1120389D01*
G01X1646366Y1123542D02*
X1646357Y1123543D01*
G01X1646375Y1123539D02*
X1646366Y1123542D01*
G01X1646383Y1123534D02*
X1646375Y1123539D01*
G01X1645452Y1103460D02*
X1645453Y1103454D01*
G01X1645452Y1103463D02*
Y1103460D01*
G01X1645450Y1103465D02*
X1645452Y1103463D01*
G01Y1106609D02*
X1645453Y1106603D01*
G01X1645452Y1106613D02*
Y1106609D01*
G01X1645450Y1106614D02*
X1645452Y1106613D01*
G01Y1109759D02*
X1645453Y1109753D01*
G01X1645452Y1109763D02*
Y1109759D01*
G01X1645450Y1109764D02*
X1645452Y1109763D01*
G01Y1112909D02*
X1645453Y1112902D01*
G01X1645452Y1112912D02*
Y1112909D01*
G01X1645450Y1112913D02*
X1645452Y1112912D01*
G01Y1116058D02*
X1645453Y1116052D01*
G01X1645452Y1116062D02*
Y1116058D01*
G01X1645450Y1116063D02*
X1645452Y1116062D01*
G01Y1119208D02*
X1645453Y1119202D01*
G01X1645452Y1119211D02*
Y1119208D01*
G01X1645450Y1119213D02*
X1645452Y1119211D01*
G01Y1122357D02*
X1645453Y1122351D01*
G01X1645452Y1122361D02*
Y1122357D01*
G01X1645450Y1122362D02*
X1645452Y1122361D01*
G01X1646390Y1110927D02*
X1646383Y1110935D01*
G01X1646394Y1110917D02*
X1646390Y1110927D01*
G01X1646396Y1110906D02*
X1646394Y1110917D01*
G01X1646390Y1104628D02*
X1646383Y1104636D01*
G01X1646395Y1104617D02*
X1646390Y1104628D01*
G01X1646396Y1104606D02*
X1646395Y1104617D01*
G01X1646390Y1107777D02*
X1646383Y1107786D01*
G01X1646395Y1107767D02*
X1646390Y1107777D01*
G01X1646396Y1107756D02*
X1646395Y1107767D01*
G01X1646390Y1114076D02*
X1646383Y1114085D01*
G01X1646395Y1114066D02*
X1646390Y1114076D01*
G01X1646396Y1114055D02*
X1646395Y1114066D01*
G01X1646390Y1117226D02*
X1646383Y1117235D01*
G01X1646395Y1117216D02*
X1646390Y1117226D01*
G01X1646396Y1117205D02*
X1646395Y1117216D01*
G01X1646390Y1120376D02*
X1646383Y1120384D01*
G01X1646395Y1120365D02*
X1646390Y1120376D01*
G01X1646396Y1120354D02*
X1646395Y1120365D01*
G01X1646390Y1123525D02*
X1646383Y1123534D01*
G01X1646395Y1123515D02*
X1646390Y1123525D01*
G01X1646396Y1123504D02*
X1646395Y1123515D01*
G01X1659823Y1086660D02*
Y1086667D01*
G01X1659824Y1086656D02*
X1659823Y1086660D01*
G01X1659825Y1086654D02*
X1659824Y1086656D01*
G01X1659823Y1091660D02*
Y1091667D01*
G01X1659824Y1091656D02*
X1659823Y1091660D01*
G01X1659825Y1091654D02*
X1659824Y1091656D01*
G01X1659823Y1096660D02*
Y1096667D01*
G01X1659824Y1096656D02*
X1659823Y1096660D01*
G01X1659825Y1096654D02*
X1659824Y1096656D01*
G01X1659823Y1101660D02*
Y1101667D01*
G01X1659824Y1101656D02*
X1659823Y1101660D01*
G01X1659825Y1101654D02*
X1659824Y1101656D01*
G01X1659823Y1126660D02*
Y1126667D01*
G01X1659824Y1126656D02*
X1659823Y1126660D01*
G01X1659825Y1126654D02*
X1659824Y1126656D01*
G01X1645436Y1106617D02*
X1645450Y1106614D01*
G01X1645425Y1106624D02*
X1645436Y1106617D01*
G01X1645413Y1106643D02*
X1645425Y1106624D01*
G01X1645436Y1116066D02*
X1645450Y1116063D01*
G01X1645424Y1116073D02*
X1645436Y1116066D01*
G01X1645413Y1116091D02*
X1645424Y1116073D01*
G01X1645436Y1109767D02*
X1645450Y1109764D01*
G01X1645424Y1109774D02*
X1645436Y1109767D01*
G01X1645412Y1109794D02*
X1645424Y1109774D01*
G01X1645436Y1119215D02*
X1645450Y1119213D01*
G01X1645424Y1119223D02*
X1645436Y1119215D01*
G01X1645412Y1119243D02*
X1645424Y1119223D01*
G01X1646398Y1103498D02*
Y1103491D01*
G01X1646397Y1103503D02*
X1646398Y1103498D01*
G01X1646396Y1103504D02*
X1646397Y1103503D01*
G01X1646398Y1106648D02*
Y1106640D01*
G01X1646397Y1106652D02*
X1646398Y1106648D01*
G01X1646396Y1106654D02*
X1646397Y1106652D01*
G01X1646398Y1109797D02*
Y1109790D01*
G01X1646397Y1109802D02*
X1646398Y1109797D01*
G01X1646396Y1109803D02*
X1646397Y1109802D01*
G01X1646398Y1112947D02*
Y1112939D01*
G01X1646397Y1112952D02*
X1646398Y1112947D01*
G01X1646396Y1112953D02*
X1646397Y1112952D01*
G01X1646398Y1116096D02*
Y1116089D01*
G01X1646397Y1116101D02*
X1646398Y1116096D01*
G01X1646396Y1116102D02*
X1646397Y1116101D01*
G01X1646398Y1119246D02*
Y1119239D01*
G01X1646397Y1119251D02*
X1646398Y1119246D01*
G01X1646396Y1119252D02*
X1646397Y1119251D01*
G01X1646398Y1122396D02*
Y1122388D01*
G01X1646397Y1122400D02*
X1646398Y1122396D01*
G01X1646396Y1122402D02*
X1646397Y1122400D01*
G01X1645436Y1122365D02*
X1645450Y1122362D01*
G01X1645423Y1122373D02*
X1645436Y1122365D01*
G01X1645412Y1122393D02*
X1645423Y1122373D01*
G01X1645435Y1103468D02*
X1645450Y1103465D01*
G01X1645422Y1103476D02*
X1645435Y1103468D01*
G01X1645412Y1103496D02*
X1645422Y1103476D01*
G01X1646397Y1104627D02*
X1646398Y1104620D01*
G01X1646395Y1104633D02*
X1646397Y1104627D01*
G01X1646392Y1104639D02*
X1646395Y1104633D01*
G01X1646397Y1107776D02*
X1646398Y1107770D01*
G01X1646395Y1107783D02*
X1646397Y1107776D01*
G01X1646392Y1107789D02*
X1646395Y1107783D01*
G01X1646397Y1110926D02*
X1646398Y1110919D01*
G01X1646395Y1110932D02*
X1646397Y1110926D01*
G01X1646392Y1110938D02*
X1646395Y1110932D01*
G01X1646397Y1114076D02*
X1646398Y1114069D01*
G01X1646395Y1114082D02*
X1646397Y1114076D01*
G01X1646392Y1114088D02*
X1646395Y1114082D01*
G01X1646397Y1117225D02*
X1646398Y1117219D01*
G01X1646395Y1117231D02*
X1646397Y1117225D01*
G01X1646392Y1117237D02*
X1646395Y1117231D01*
G01X1646397Y1120375D02*
X1646398Y1120368D01*
G01X1646395Y1120381D02*
X1646397Y1120375D01*
G01X1646392Y1120387D02*
X1646395Y1120381D01*
G01X1646397Y1123524D02*
X1646398Y1123518D01*
G01X1646395Y1123531D02*
X1646397Y1123524D01*
G01X1646392Y1123537D02*
X1646395Y1123531D01*
G01X1646359Y1103459D02*
Y1103454D01*
G01X1646357Y1103463D02*
X1646359Y1103459D01*
G01X1646357Y1103465D02*
Y1103463D01*
G01X1646359Y1106609D02*
Y1106603D01*
G01X1646357Y1106613D02*
X1646359Y1106609D01*
G01X1646357Y1106614D02*
Y1106613D01*
G01X1646359Y1109759D02*
Y1109753D01*
G01X1646357Y1109763D02*
X1646359Y1109759D01*
G01X1646357Y1109764D02*
Y1109763D01*
G01X1646359Y1112908D02*
Y1112902D01*
G01X1646357Y1112912D02*
X1646359Y1112908D01*
G01X1646357Y1112913D02*
Y1112912D01*
G01X1646359Y1116058D02*
Y1116052D01*
G01X1646357Y1116062D02*
X1646359Y1116058D01*
G01X1646357Y1116063D02*
Y1116062D01*
G01X1646359Y1122357D02*
Y1122351D01*
G01X1646357Y1122361D02*
X1646359Y1122357D01*
G01X1646357Y1122362D02*
Y1122361D01*
G01X1658839Y1086700D02*
Y1086709D01*
G01Y1086695D02*
Y1086700D01*
G01X1658840Y1086693D02*
X1658839Y1086695D01*
G01Y1091700D02*
Y1091709D01*
G01Y1091695D02*
Y1091700D01*
G01X1658840Y1091693D02*
X1658839Y1091695D01*
G01Y1096700D02*
Y1096709D01*
G01Y1096695D02*
Y1096700D01*
G01X1658840Y1096693D02*
X1658839Y1096695D01*
G01Y1101700D02*
Y1101709D01*
G01Y1101695D02*
Y1101700D01*
G01X1658840Y1101693D02*
X1658839Y1101695D01*
G01Y1126700D02*
Y1126709D01*
G01Y1126695D02*
Y1126700D01*
G01X1658840Y1126693D02*
X1658839Y1126695D01*
G01X1659815Y1086837D02*
X1659823Y1086811D01*
G01X1659805Y1086863D02*
X1659815Y1086837D01*
G01X1659794Y1086890D02*
X1659805Y1086863D01*
G01X1659815Y1091837D02*
X1659823Y1091811D01*
G01X1659805Y1091863D02*
X1659815Y1091837D01*
G01X1659794Y1091890D02*
X1659805Y1091863D01*
G01X1659815Y1096837D02*
X1659823Y1096811D01*
G01X1659805Y1096863D02*
X1659815Y1096837D01*
G01X1659794Y1096890D02*
X1659805Y1096863D01*
G01X1659815Y1101837D02*
X1659823Y1101811D01*
G01X1659805Y1101863D02*
X1659815Y1101837D01*
G01X1659794Y1101890D02*
X1659805Y1101863D01*
G01X1659815Y1126837D02*
X1659823Y1126811D01*
G01X1659805Y1126863D02*
X1659815Y1126837D01*
G01X1659794Y1126890D02*
X1659805Y1126863D01*
G01X1645431Y1112919D02*
X1645450Y1112913D01*
G01X1645418Y1112931D02*
X1645431Y1112919D01*
G01X1645411Y1112949D02*
X1645418Y1112931D01*
G01X1659806Y1086688D02*
X1659786Y1086693D01*
G01X1659820Y1086674D02*
X1659806Y1086688D01*
G01X1659825Y1086654D02*
X1659820Y1086674D01*
G01X1659806Y1091688D02*
X1659786Y1091693D01*
G01X1659820Y1091674D02*
X1659806Y1091688D01*
G01X1659825Y1091654D02*
X1659820Y1091674D01*
G01X1659806Y1096688D02*
X1659786Y1096693D01*
G01X1659820Y1096674D02*
X1659806Y1096688D01*
G01X1659825Y1096654D02*
X1659820Y1096674D01*
G01X1659806Y1101688D02*
X1659786Y1101693D01*
G01X1659820Y1101674D02*
X1659806Y1101688D01*
G01X1659825Y1101654D02*
X1659820Y1101674D01*
G01X1659806Y1126688D02*
X1659786Y1126693D01*
G01X1659820Y1126674D02*
X1659806Y1126688D01*
G01X1659825Y1126654D02*
X1659820Y1126674D01*
G01X1646357Y1119213D02*
X1646360Y1119202D01*
G01X1659252Y1103642D02*
X1660433Y1102461D01*
G01X1655315Y1103642D02*
X1656496Y1102461D01*
G01X1646397Y1104609D02*
X1646398Y1104620D01*
G01X1646397Y1107758D02*
X1646398Y1107769D01*
G01X1646397Y1110908D02*
X1646398Y1110919D01*
G01X1646397Y1114057D02*
X1646398Y1114069D01*
G01X1646397Y1117207D02*
X1646398Y1117218D01*
G01X1646397Y1120357D02*
X1646398Y1120368D01*
G01X1646397Y1123506D02*
X1646398Y1123517D01*
G01X1659823Y1086667D02*
Y1086676D01*
G01Y1091667D02*
Y1091676D01*
G01Y1096667D02*
Y1096676D01*
G01Y1101667D02*
Y1101676D01*
G01Y1126667D02*
Y1126676D01*
G01X1664173Y1130315D02*
Y1131693D01*
G01Y1125315D02*
Y1126693D01*
G01Y1100315D02*
Y1101693D01*
G01Y1095315D02*
Y1096693D01*
G01Y1090315D02*
Y1091693D01*
G01Y1085315D02*
Y1086693D01*
G01X1661004D02*
Y1085315D01*
G01Y1091693D02*
Y1090315D01*
G01Y1096693D02*
Y1095315D01*
G01Y1101693D02*
Y1100315D01*
G01Y1126693D02*
Y1125315D01*
G01Y1131693D02*
Y1130315D01*
G01X1660433Y1124547D02*
Y1102461D01*
G01X1659823Y1129823D02*
Y1132185D01*
G01Y1124823D02*
Y1127185D01*
G01Y1099823D02*
Y1102185D01*
G01Y1094823D02*
Y1097185D01*
G01Y1089823D02*
Y1092185D01*
G01Y1084823D02*
Y1087185D01*
G01Y1091667D02*
Y1091811D01*
G01Y1086667D02*
Y1086811D01*
G01Y1101667D02*
Y1101811D01*
G01Y1096667D02*
Y1096811D01*
G01Y1126667D02*
Y1126811D01*
G01X1659252Y1123366D02*
Y1103642D01*
G01X1658839Y1087185D02*
Y1084823D01*
G01Y1092185D02*
Y1089823D01*
G01Y1097185D02*
Y1094823D01*
G01Y1102185D02*
Y1099823D01*
G01Y1127185D02*
Y1124823D01*
G01Y1132185D02*
Y1129823D01*
G01X1656496Y1201004D02*
Y1124547D01*
G01X1655315Y1199823D02*
Y1123366D01*
G01X1646850Y1204744D02*
Y1125709D01*
G01X1646398Y1122205D02*
Y1123701D01*
G01Y1119055D02*
Y1120551D01*
G01Y1115906D02*
Y1117402D01*
G01Y1112756D02*
Y1114252D01*
G01Y1109606D02*
Y1111102D01*
G01Y1106457D02*
Y1107953D01*
G01Y1103307D02*
Y1104803D01*
G01X1646358Y1106603D02*
Y1106456D01*
G01Y1103454D02*
Y1103307D01*
G01Y1104804D02*
Y1104657D01*
G01Y1109753D02*
Y1109606D01*
G01Y1111103D02*
Y1110956D01*
G01Y1107953D02*
Y1107807D01*
G01Y1116052D02*
Y1115905D01*
G01Y1112902D02*
Y1112756D01*
G01Y1114252D02*
Y1114106D01*
G01Y1119202D02*
Y1119055D01*
G01Y1120552D02*
Y1120405D01*
G01Y1117402D02*
Y1117256D01*
G01Y1122351D02*
Y1122204D01*
G01Y1123701D02*
Y1123555D01*
G01X1645453Y1122204D02*
Y1122351D01*
G01Y1123555D02*
Y1123702D01*
G01Y1119054D02*
Y1119202D01*
G01Y1120405D02*
Y1120552D01*
G01Y1117256D02*
Y1117402D01*
G01Y1115905D02*
Y1116052D01*
G01Y1112755D02*
Y1112902D01*
G01Y1114106D02*
Y1114253D01*
G01Y1109606D02*
Y1109753D01*
G01Y1110956D02*
Y1111103D01*
G01Y1107807D02*
Y1107954D01*
G01Y1106456D02*
Y1106603D01*
G01Y1103306D02*
Y1103454D01*
G01Y1104657D02*
Y1104804D01*
G01X1645413Y1104803D02*
Y1103307D01*
G01Y1111102D02*
Y1109606D01*
G01Y1107953D02*
Y1106457D01*
G01Y1114252D02*
Y1112756D01*
G01Y1120551D02*
Y1119055D01*
G01Y1117402D02*
Y1115906D01*
G01Y1123701D02*
Y1122205D01*
G01X1644232Y1107795D02*
Y1106614D01*
G01Y1104646D02*
Y1103465D01*
G01Y1110945D02*
Y1109764D01*
G01Y1117244D02*
Y1116063D01*
G01Y1114094D02*
Y1112913D01*
G01Y1120394D02*
Y1119213D01*
G01Y1123543D02*
Y1122362D01*
G01X1643898Y1125709D02*
Y1101299D01*
G01X1643504D02*
Y1125709D01*
G01X1640472Y1122362D02*
Y1123543D01*
G01Y1119213D02*
Y1120394D01*
G01Y1116063D02*
Y1117244D01*
G01Y1112913D02*
Y1114094D01*
G01Y1109764D02*
Y1110945D01*
G01Y1106614D02*
Y1107795D01*
G01Y1103465D02*
Y1104646D01*
G01X1646398Y1122388D02*
X1646397Y1122399D01*
G01X1646398Y1119239D02*
X1646397Y1119250D01*
G01X1646398Y1116089D02*
X1646397Y1116100D01*
G01X1646398Y1112939D02*
X1646397Y1112950D01*
G01X1646398Y1109790D02*
X1646397Y1109801D01*
G01X1646398Y1106640D02*
X1646397Y1106651D01*
G01X1646398Y1103491D02*
X1646397Y1103502D01*
G01X1645300Y1122402D02*
X1645412Y1122393D01*
G01X1645411Y1112949D02*
X1645300Y1112953D01*
G01X1645411Y1106650D02*
X1645300Y1106654D01*
G01X1645411Y1116099D02*
X1645300Y1116102D01*
G01X1664173Y1130315D02*
X1658840D01*
G01X1658839Y1129823D02*
X1659823D01*
G01Y1127185D02*
X1658839D01*
G01X1658840Y1126693D02*
X1664173D01*
G01Y1126654D02*
X1659825D01*
G01X1646850Y1125709D02*
X1643504D01*
G01X1664173Y1125315D02*
X1658840D01*
G01X1658839Y1124823D02*
X1659823D01*
G01X1656496Y1124547D02*
X1660433D01*
G01X1646358Y1123740D02*
X1645453D01*
G01X1646398Y1123701D02*
X1645413D01*
G01X1646357Y1123543D02*
X1640472D01*
G01Y1123504D02*
X1646396D01*
G01X1655315Y1123366D02*
X1659252D01*
G01X1646396Y1122402D02*
X1640472D01*
G01X1646357Y1122362D02*
X1640472D01*
G01X1645413Y1122205D02*
X1646398D01*
G01X1645453Y1122165D02*
X1646358D01*
G01Y1120591D02*
X1645453D01*
G01X1646398Y1120551D02*
X1645413D01*
G01X1646357Y1120394D02*
X1640472D01*
G01Y1120354D02*
X1646396D01*
G01Y1119252D02*
X1640472D01*
G01X1646357Y1119213D02*
X1640472D01*
G01X1645413Y1119055D02*
X1646398D01*
G01X1645453Y1119016D02*
X1646358D01*
G01Y1117441D02*
X1645453D01*
G01X1646398Y1117402D02*
X1645413D01*
G01X1646357Y1117244D02*
X1640472D01*
G01Y1117205D02*
X1646396D01*
G01X1644666Y1116102D02*
X1644232D01*
G01X1646396D02*
X1640472D01*
G01X1646357Y1116063D02*
X1640472D01*
G01X1645413Y1115906D02*
X1646398D01*
G01X1645453Y1115866D02*
X1646358D01*
G01Y1114291D02*
X1645453D01*
G01X1646398Y1114252D02*
X1645413D01*
G01X1646357Y1114094D02*
X1640472D01*
G01Y1114055D02*
X1646396D01*
G01X1644666Y1112953D02*
X1644232D01*
G01X1646396D02*
X1640472D01*
G01X1646357Y1112913D02*
X1640472D01*
G01X1645413Y1112756D02*
X1646398D01*
G01X1645453Y1112717D02*
X1646358D01*
G01Y1111142D02*
X1645453D01*
G01X1646398Y1111102D02*
X1645413D01*
G01X1646357Y1110945D02*
X1640472D01*
G01Y1110906D02*
X1646396D01*
G01Y1109803D02*
X1640472D01*
G01X1646357Y1109764D02*
X1640472D01*
G01X1645413Y1109606D02*
X1646398D01*
G01X1645453Y1109567D02*
X1646358D01*
G01Y1107992D02*
X1645453D01*
G01X1646398Y1107953D02*
X1645413D01*
G01X1646357Y1107795D02*
X1640472D01*
G01Y1107756D02*
X1646396D01*
G01X1644666Y1106654D02*
X1644232D01*
G01X1646396D02*
X1640472D01*
G01X1646357Y1106614D02*
X1640472D01*
G01X1645413Y1106457D02*
X1646398D01*
G01X1645453Y1106417D02*
X1646358D01*
G01Y1104843D02*
X1645453D01*
G01X1646398Y1104803D02*
X1645413D01*
G01X1646357Y1104646D02*
X1640472D01*
G01Y1104606D02*
X1646396D01*
G01X1659252Y1103642D02*
X1655315D01*
G01X1646396Y1103504D02*
X1640472D01*
G01X1646357Y1103465D02*
X1640472D01*
G01X1645413Y1103307D02*
X1646398D01*
G01X1645453Y1103268D02*
X1646358D01*
G01X1660433Y1102461D02*
X1656496D01*
G01X1659823Y1102185D02*
X1658839D01*
G01X1658840Y1101693D02*
X1664173D01*
G01Y1101654D02*
X1659825D01*
G01X1646850Y1101299D02*
X1643504D01*
G01X1664173Y1100315D02*
X1658840D01*
G01X1658839Y1099823D02*
X1659823D01*
G01Y1097185D02*
X1658839D01*
G01X1658840Y1096693D02*
X1664173D01*
G01Y1096654D02*
X1659825D01*
G01X1664173Y1095315D02*
X1658840D01*
G01X1658839Y1094823D02*
X1659823D01*
G01Y1092185D02*
X1658839D01*
G01X1658840Y1091693D02*
X1664173D01*
G01Y1091654D02*
X1659825D01*
G01X1664173Y1090315D02*
X1658840D01*
G01X1658839Y1089823D02*
X1659823D01*
G01Y1087185D02*
X1658839D01*
G01X1658840Y1086693D02*
X1664173D01*
G01Y1086654D02*
X1659825D01*
G01X1664173Y1085315D02*
X1658840D01*
G01X1658839Y1084823D02*
X1659823D01*
G01Y1130119D02*
X1658839Y1130118D01*
G01Y1126889D02*
X1659794Y1126890D01*
G01X1659823Y1125119D02*
X1658839Y1125118D01*
G01Y1101889D02*
X1659794Y1101890D01*
G01X1659823Y1100119D02*
X1658839Y1100118D01*
G01Y1096889D02*
X1659794Y1096890D01*
G01X1659823Y1095119D02*
X1658839Y1095118D01*
G01Y1091889D02*
X1659794Y1091890D01*
G01X1659823Y1090119D02*
X1658839Y1090118D01*
G01Y1086889D02*
X1659794Y1086890D01*
G01X1659823Y1085119D02*
X1658839Y1085118D01*
G01X1659252Y1123366D02*
X1660433Y1124547D01*
G01X1655315Y1123366D02*
X1656496Y1124547D01*
G01X1659823Y1175308D02*
Y1175299D01*
G01X1659824Y1175313D02*
X1659823Y1175308D01*
G01X1659826Y1175315D02*
X1659824Y1175313D01*
G01X1659823Y1170308D02*
Y1170299D01*
G01X1659824Y1170313D02*
X1659823Y1170308D01*
G01X1659826Y1170315D02*
X1659824Y1170313D01*
G01X1659823Y1165308D02*
Y1165299D01*
G01X1659824Y1165313D02*
X1659823Y1165308D01*
G01X1659826Y1165315D02*
X1659824Y1165313D01*
G01X1659823Y1160308D02*
Y1160299D01*
G01X1659824Y1160313D02*
X1659823Y1160308D01*
G01X1659826Y1160315D02*
X1659824Y1160313D01*
G01X1659823Y1155308D02*
Y1155299D01*
G01X1659824Y1155313D02*
X1659823Y1155308D01*
G01X1659826Y1155315D02*
X1659824Y1155313D01*
G01X1659823Y1150308D02*
Y1150299D01*
G01X1659824Y1150313D02*
X1659823Y1150308D01*
G01X1659826Y1150315D02*
X1659824Y1150313D01*
G01X1659823Y1145308D02*
Y1145299D01*
G01X1659824Y1145313D02*
X1659823Y1145308D01*
G01X1659826Y1145315D02*
X1659824Y1145313D01*
G01X1659823Y1140308D02*
Y1140299D01*
G01X1659824Y1140313D02*
X1659823Y1140308D01*
G01X1659826Y1140315D02*
X1659824Y1140313D01*
G01X1659823Y1135308D02*
Y1135299D01*
G01X1659824Y1135313D02*
X1659823Y1135308D01*
G01X1659826Y1135315D02*
X1659824Y1135313D01*
G01X1659810Y1131685D02*
X1659821Y1131669D01*
G01X1659786Y1131693D02*
X1659810Y1131685D01*
G01Y1136685D02*
X1659821Y1136669D01*
G01X1659786Y1136693D02*
X1659810Y1136685D01*
G01Y1141685D02*
X1659821Y1141669D01*
G01X1659786Y1141693D02*
X1659810Y1141685D01*
G01Y1146685D02*
X1659821Y1146669D01*
G01X1659786Y1146693D02*
X1659810Y1146685D01*
G01Y1151685D02*
X1659821Y1151669D01*
G01X1659786Y1151693D02*
X1659810Y1151685D01*
G01Y1156685D02*
X1659821Y1156669D01*
G01X1659786Y1156693D02*
X1659810Y1156685D01*
G01Y1161685D02*
X1659821Y1161669D01*
G01X1659786Y1161693D02*
X1659810Y1161685D01*
G01Y1166685D02*
X1659821Y1166669D01*
G01X1659786Y1166693D02*
X1659810Y1166685D01*
G01Y1171685D02*
X1659821Y1171669D01*
G01X1659786Y1171693D02*
X1659810Y1171685D01*
G01Y1176685D02*
X1659821Y1176669D01*
G01X1659786Y1176693D02*
X1659810Y1176685D01*
G01X1659790Y1131791D02*
X1659794Y1131890D01*
G01X1659784Y1131719D02*
X1659790Y1131791D01*
G01X1659786Y1131693D02*
X1659784Y1131719D01*
G01X1659790Y1136791D02*
X1659794Y1136890D01*
G01X1659784Y1136719D02*
X1659790Y1136791D01*
G01X1659786Y1136693D02*
X1659784Y1136719D01*
G01X1659790Y1141791D02*
X1659794Y1141890D01*
G01X1659784Y1141719D02*
X1659790Y1141791D01*
G01X1659786Y1141693D02*
X1659784Y1141719D01*
G01X1659790Y1146791D02*
X1659794Y1146890D01*
G01X1659784Y1146719D02*
X1659790Y1146791D01*
G01X1659786Y1146693D02*
X1659784Y1146719D01*
G01X1659790Y1151791D02*
X1659794Y1151890D01*
G01X1659784Y1151719D02*
X1659790Y1151791D01*
G01X1659786Y1151693D02*
X1659784Y1151719D01*
G01X1659790Y1156791D02*
X1659794Y1156890D01*
G01X1659784Y1156719D02*
X1659790Y1156791D01*
G01X1659786Y1156693D02*
X1659784Y1156719D01*
G01X1659790Y1161791D02*
X1659794Y1161890D01*
G01X1659784Y1161719D02*
X1659790Y1161791D01*
G01X1659786Y1161693D02*
X1659784Y1161719D01*
G01X1659790Y1166791D02*
X1659794Y1166890D01*
G01X1659784Y1166719D02*
X1659790Y1166791D01*
G01X1659786Y1166693D02*
X1659784Y1166719D01*
G01X1659790Y1171791D02*
X1659794Y1171890D01*
G01X1659784Y1171719D02*
X1659790Y1171791D01*
G01X1659786Y1171693D02*
X1659784Y1171719D01*
G01X1659790Y1176791D02*
X1659794Y1176890D01*
G01X1659784Y1176719D02*
X1659790Y1176791D01*
G01X1659786Y1176693D02*
X1659784Y1176719D01*
G01X1658839Y1175313D02*
X1658840Y1175315D01*
G01X1658839Y1175308D02*
Y1175313D01*
G01Y1175299D02*
Y1175308D01*
G01Y1170313D02*
X1658840Y1170315D01*
G01X1658839Y1170308D02*
Y1170313D01*
G01Y1170299D02*
Y1170308D01*
G01Y1165313D02*
X1658840Y1165315D01*
G01X1658839Y1165308D02*
Y1165313D01*
G01Y1165299D02*
Y1165308D01*
G01Y1160313D02*
X1658840Y1160315D01*
G01X1658839Y1160308D02*
Y1160313D01*
G01Y1160299D02*
Y1160308D01*
G01Y1155313D02*
X1658840Y1155315D01*
G01X1658839Y1155308D02*
Y1155313D01*
G01Y1155299D02*
Y1155308D01*
G01Y1150313D02*
X1658840Y1150315D01*
G01X1658839Y1150308D02*
Y1150313D01*
G01Y1150299D02*
Y1150308D01*
G01Y1145313D02*
X1658840Y1145315D01*
G01X1658839Y1145308D02*
Y1145313D01*
G01Y1145299D02*
Y1145308D01*
G01Y1140313D02*
X1658840Y1140315D01*
G01X1658839Y1140308D02*
Y1140313D01*
G01Y1140299D02*
Y1140308D01*
G01Y1135313D02*
X1658840Y1135315D01*
G01X1658839Y1135308D02*
Y1135313D01*
G01Y1135299D02*
Y1135308D01*
G01X1659823Y1131660D02*
Y1131667D01*
G01X1659824Y1131656D02*
X1659823Y1131660D01*
G01X1659825Y1131654D02*
X1659824Y1131656D01*
G01X1659823Y1136660D02*
Y1136667D01*
G01X1659824Y1136656D02*
X1659823Y1136660D01*
G01X1659825Y1136654D02*
X1659824Y1136656D01*
G01X1659823Y1141660D02*
Y1141667D01*
G01X1659824Y1141656D02*
X1659823Y1141660D01*
G01X1659825Y1141654D02*
X1659824Y1141656D01*
G01X1659823Y1146660D02*
Y1146667D01*
G01X1659824Y1146656D02*
X1659823Y1146660D01*
G01X1659825Y1146654D02*
X1659824Y1146656D01*
G01X1659823Y1151660D02*
Y1151667D01*
G01X1659824Y1151656D02*
X1659823Y1151660D01*
G01X1659825Y1151654D02*
X1659824Y1151656D01*
G01X1659823Y1156660D02*
Y1156667D01*
G01X1659824Y1156656D02*
X1659823Y1156660D01*
G01X1659825Y1156654D02*
X1659824Y1156656D01*
G01X1659823Y1161660D02*
Y1161667D01*
G01X1659824Y1161656D02*
X1659823Y1161660D01*
G01X1659825Y1161654D02*
X1659824Y1161656D01*
G01X1659823Y1166660D02*
Y1166667D01*
G01X1659824Y1166656D02*
X1659823Y1166660D01*
G01X1659825Y1166654D02*
X1659824Y1166656D01*
G01X1659823Y1171660D02*
Y1171667D01*
G01X1659824Y1171656D02*
X1659823Y1171660D01*
G01X1659825Y1171654D02*
X1659824Y1171656D01*
G01X1659823Y1176660D02*
Y1176667D01*
G01X1659824Y1176656D02*
X1659823Y1176660D01*
G01X1659825Y1176654D02*
X1659824Y1176656D01*
G01X1658839Y1131700D02*
Y1131709D01*
G01Y1131695D02*
Y1131700D01*
G01X1658840Y1131693D02*
X1658839Y1131695D01*
G01Y1136700D02*
Y1136709D01*
G01Y1136695D02*
Y1136700D01*
G01X1658840Y1136693D02*
X1658839Y1136695D01*
G01Y1141700D02*
Y1141709D01*
G01Y1141695D02*
Y1141700D01*
G01X1658840Y1141693D02*
X1658839Y1141695D01*
G01Y1146700D02*
Y1146709D01*
G01Y1146695D02*
Y1146700D01*
G01X1658840Y1146693D02*
X1658839Y1146695D01*
G01Y1151700D02*
Y1151709D01*
G01Y1151695D02*
Y1151700D01*
G01X1658840Y1151693D02*
X1658839Y1151695D01*
G01Y1156700D02*
Y1156709D01*
G01Y1156695D02*
Y1156700D01*
G01X1658840Y1156693D02*
X1658839Y1156695D01*
G01Y1161700D02*
Y1161709D01*
G01Y1161695D02*
Y1161700D01*
G01X1658840Y1161693D02*
X1658839Y1161695D01*
G01Y1166700D02*
Y1166709D01*
G01Y1166695D02*
Y1166700D01*
G01X1658840Y1166693D02*
X1658839Y1166695D01*
G01Y1171700D02*
Y1171709D01*
G01Y1171695D02*
Y1171700D01*
G01X1658840Y1171693D02*
X1658839Y1171695D01*
G01Y1176700D02*
Y1176709D01*
G01Y1176695D02*
Y1176700D01*
G01X1658840Y1176693D02*
X1658839Y1176695D01*
G01X1659815Y1131837D02*
X1659823Y1131811D01*
G01X1659805Y1131863D02*
X1659815Y1131837D01*
G01X1659794Y1131890D02*
X1659805Y1131863D01*
G01X1659815Y1136837D02*
X1659823Y1136811D01*
G01X1659805Y1136863D02*
X1659815Y1136837D01*
G01X1659794Y1136890D02*
X1659805Y1136863D01*
G01X1659815Y1141837D02*
X1659823Y1141811D01*
G01X1659805Y1141863D02*
X1659815Y1141837D01*
G01X1659794Y1141890D02*
X1659805Y1141863D01*
G01X1659815Y1146837D02*
X1659823Y1146811D01*
G01X1659805Y1146863D02*
X1659815Y1146837D01*
G01X1659794Y1146890D02*
X1659805Y1146863D01*
G01X1659815Y1151837D02*
X1659823Y1151811D01*
G01X1659805Y1151863D02*
X1659815Y1151837D01*
G01X1659794Y1151890D02*
X1659805Y1151863D01*
G01X1659815Y1156837D02*
X1659823Y1156811D01*
G01X1659805Y1156863D02*
X1659815Y1156837D01*
G01X1659794Y1156890D02*
X1659805Y1156863D01*
G01X1659815Y1161837D02*
X1659823Y1161811D01*
G01X1659805Y1161863D02*
X1659815Y1161837D01*
G01X1659794Y1161890D02*
X1659805Y1161863D01*
G01X1659815Y1166837D02*
X1659823Y1166811D01*
G01X1659805Y1166863D02*
X1659815Y1166837D01*
G01X1659794Y1166890D02*
X1659805Y1166863D01*
G01X1659815Y1171837D02*
X1659823Y1171811D01*
G01X1659805Y1171863D02*
X1659815Y1171837D01*
G01X1659794Y1171890D02*
X1659805Y1171863D01*
G01X1659815Y1176837D02*
X1659823Y1176811D01*
G01X1659805Y1176863D02*
X1659815Y1176837D01*
G01X1659794Y1176890D02*
X1659805Y1176863D01*
G01X1659806Y1131688D02*
X1659786Y1131693D01*
G01X1659820Y1131674D02*
X1659806Y1131688D01*
G01X1659825Y1131654D02*
X1659820Y1131674D01*
G01X1659806Y1136688D02*
X1659786Y1136693D01*
G01X1659820Y1136674D02*
X1659806Y1136688D01*
G01X1659825Y1136654D02*
X1659820Y1136674D01*
G01X1659806Y1141688D02*
X1659786Y1141693D01*
G01X1659820Y1141674D02*
X1659806Y1141688D01*
G01X1659825Y1141654D02*
X1659820Y1141674D01*
G01X1659806Y1146688D02*
X1659786Y1146693D01*
G01X1659820Y1146674D02*
X1659806Y1146688D01*
G01X1659825Y1146654D02*
X1659820Y1146674D01*
G01X1659806Y1151688D02*
X1659786Y1151693D01*
G01X1659820Y1151674D02*
X1659806Y1151688D01*
G01X1659825Y1151654D02*
X1659820Y1151674D01*
G01X1659806Y1156688D02*
X1659786Y1156693D01*
G01X1659820Y1156674D02*
X1659806Y1156688D01*
G01X1659825Y1156654D02*
X1659820Y1156674D01*
G01X1659806Y1161688D02*
X1659786Y1161693D01*
G01X1659820Y1161674D02*
X1659806Y1161688D01*
G01X1659825Y1161654D02*
X1659820Y1161674D01*
G01X1659806Y1166688D02*
X1659786Y1166693D01*
G01X1659820Y1166674D02*
X1659806Y1166688D01*
G01X1659825Y1166654D02*
X1659820Y1166674D01*
G01X1659806Y1171688D02*
X1659786Y1171693D01*
G01X1659820Y1171674D02*
X1659806Y1171688D01*
G01X1659825Y1171654D02*
X1659820Y1171674D01*
G01X1659806Y1176688D02*
X1659786Y1176693D01*
G01X1659820Y1176674D02*
X1659806Y1176688D01*
G01X1659825Y1176654D02*
X1659820Y1176674D01*
G01X1659823Y1131667D02*
Y1131676D01*
G01Y1136667D02*
Y1136676D01*
G01Y1141667D02*
Y1141676D01*
G01Y1146667D02*
Y1146676D01*
G01Y1151667D02*
Y1151676D01*
G01Y1156667D02*
Y1156676D01*
G01Y1161667D02*
Y1161676D01*
G01Y1166667D02*
Y1166676D01*
G01Y1171667D02*
Y1171676D01*
G01Y1176667D02*
Y1176676D01*
G01X1664173Y1175315D02*
Y1176693D01*
G01Y1170315D02*
Y1171693D01*
G01Y1165315D02*
Y1166693D01*
G01Y1160315D02*
Y1161693D01*
G01Y1155315D02*
Y1156693D01*
G01Y1150315D02*
Y1151693D01*
G01Y1145315D02*
Y1146693D01*
G01Y1140315D02*
Y1141693D01*
G01Y1135315D02*
Y1136693D01*
G01X1661004D02*
Y1135315D01*
G01Y1141693D02*
Y1140315D01*
G01Y1146693D02*
Y1145315D01*
G01Y1151693D02*
Y1150315D01*
G01Y1156693D02*
Y1155315D01*
G01Y1161693D02*
Y1160315D01*
G01Y1166693D02*
Y1165315D01*
G01Y1171693D02*
Y1170315D01*
G01Y1176693D02*
Y1175315D01*
G01X1659823Y1174823D02*
Y1177185D01*
G01Y1169823D02*
Y1172185D01*
G01Y1164823D02*
Y1167185D01*
G01Y1159823D02*
Y1162185D01*
G01Y1154823D02*
Y1157185D01*
G01Y1149823D02*
Y1152185D01*
G01Y1144823D02*
Y1147185D01*
G01Y1139823D02*
Y1142185D01*
G01Y1134823D02*
Y1137185D01*
G01Y1131667D02*
Y1131811D01*
G01Y1141667D02*
Y1141811D01*
G01Y1136667D02*
Y1136811D01*
G01Y1151667D02*
Y1151811D01*
G01Y1146667D02*
Y1146811D01*
G01Y1161667D02*
Y1161811D01*
G01Y1156667D02*
Y1156811D01*
G01Y1171667D02*
Y1171811D01*
G01Y1166667D02*
Y1166811D01*
G01Y1176667D02*
Y1176811D01*
G01X1658839Y1137185D02*
Y1134823D01*
G01Y1142185D02*
Y1139823D01*
G01Y1147185D02*
Y1144823D01*
G01Y1152185D02*
Y1149823D01*
G01Y1157185D02*
Y1154823D01*
G01Y1162185D02*
Y1159823D01*
G01Y1167185D02*
Y1164823D01*
G01Y1172185D02*
Y1169823D01*
G01Y1177185D02*
Y1174823D01*
G01X1659823Y1177185D02*
X1658839D01*
G01X1658840Y1176693D02*
X1664173D01*
G01Y1176654D02*
X1659825D01*
G01X1664173Y1175315D02*
X1658840D01*
G01X1658839Y1174823D02*
X1659823D01*
G01Y1172185D02*
X1658839D01*
G01X1658840Y1171693D02*
X1664173D01*
G01Y1171654D02*
X1659825D01*
G01X1664173Y1170315D02*
X1658840D01*
G01X1658839Y1169823D02*
X1659823D01*
G01Y1167185D02*
X1658839D01*
G01X1658840Y1166693D02*
X1664173D01*
G01Y1166654D02*
X1659825D01*
G01X1664173Y1165315D02*
X1658840D01*
G01X1658839Y1164823D02*
X1659823D01*
G01Y1162185D02*
X1658839D01*
G01X1658840Y1161693D02*
X1664173D01*
G01Y1161654D02*
X1659825D01*
G01X1664173Y1160315D02*
X1658840D01*
G01X1658839Y1159823D02*
X1659823D01*
G01Y1157185D02*
X1658839D01*
G01X1658840Y1156693D02*
X1664173D01*
G01Y1156654D02*
X1659825D01*
G01X1664173Y1155315D02*
X1658840D01*
G01X1658839Y1154823D02*
X1659823D01*
G01X1658839Y1176889D02*
X1659794Y1176890D01*
G01X1659823Y1175119D02*
X1658839Y1175118D01*
G01Y1171889D02*
X1659794Y1171890D01*
G01X1659823Y1170119D02*
X1658839Y1170118D01*
G01Y1166889D02*
X1659794Y1166890D01*
G01X1659823Y1165119D02*
X1658839Y1165118D01*
G01Y1161889D02*
X1659794Y1161890D01*
G01X1659823Y1160119D02*
X1658839Y1160118D01*
G01Y1156889D02*
X1659794Y1156890D01*
G01X1659823Y1155119D02*
X1658839Y1155118D01*
G01X1659823Y1152185D02*
X1658839D01*
G01X1658840Y1151693D02*
X1664173D01*
G01Y1151654D02*
X1659825D01*
G01X1664173Y1150315D02*
X1658840D01*
G01X1658839Y1149823D02*
X1659823D01*
G01Y1147185D02*
X1658839D01*
G01X1658840Y1146693D02*
X1664173D01*
G01Y1146654D02*
X1659825D01*
G01X1664173Y1145315D02*
X1658840D01*
G01X1658839Y1144823D02*
X1659823D01*
G01Y1142185D02*
X1658839D01*
G01X1658840Y1141693D02*
X1664173D01*
G01Y1141654D02*
X1659825D01*
G01X1664173Y1140315D02*
X1658840D01*
G01X1658839Y1139823D02*
X1659823D01*
G01Y1137185D02*
X1658839D01*
G01X1658840Y1136693D02*
X1664173D01*
G01Y1136654D02*
X1659825D01*
G01X1664173Y1135315D02*
X1658840D01*
G01X1658839Y1134823D02*
X1659823D01*
G01Y1132185D02*
X1658839D01*
G01X1658840Y1131693D02*
X1664173D01*
G01Y1131654D02*
X1659825D01*
G01X1658839Y1151889D02*
X1659794Y1151890D01*
G01X1659823Y1150119D02*
X1658839Y1150118D01*
G01Y1146889D02*
X1659794Y1146890D01*
G01X1659823Y1145119D02*
X1658839Y1145118D01*
G01Y1141889D02*
X1659794Y1141890D01*
G01X1659823Y1140119D02*
X1658839Y1140118D01*
G01Y1136889D02*
X1659794Y1136890D01*
G01X1659823Y1135119D02*
X1658839Y1135118D01*
G01Y1131889D02*
X1659794Y1131890D01*
G01X1659823Y1195308D02*
Y1195299D01*
G01X1659824Y1195313D02*
X1659823Y1195308D01*
G01X1659826Y1195315D02*
X1659824Y1195313D01*
G01X1659823Y1190308D02*
Y1190299D01*
G01X1659824Y1190313D02*
X1659823Y1190308D01*
G01X1659826Y1190315D02*
X1659824Y1190313D01*
G01X1659823Y1185308D02*
Y1185299D01*
G01X1659824Y1185313D02*
X1659823Y1185308D01*
G01X1659826Y1185315D02*
X1659824Y1185313D01*
G01X1659823Y1180308D02*
Y1180299D01*
G01X1659824Y1180313D02*
X1659823Y1180308D01*
G01X1659826Y1180315D02*
X1659824Y1180313D01*
G01X1659810Y1181685D02*
X1659821Y1181669D01*
G01X1659786Y1181693D02*
X1659810Y1181685D01*
G01Y1186685D02*
X1659821Y1186669D01*
G01X1659786Y1186693D02*
X1659810Y1186685D01*
G01Y1191685D02*
X1659821Y1191669D01*
G01X1659786Y1191693D02*
X1659810Y1191685D01*
G01Y1196685D02*
X1659821Y1196669D01*
G01X1659786Y1196693D02*
X1659810Y1196685D01*
G01X1659790Y1181791D02*
X1659794Y1181890D01*
G01X1659784Y1181719D02*
X1659790Y1181791D01*
G01X1659786Y1181693D02*
X1659784Y1181719D01*
G01X1659790Y1186791D02*
X1659794Y1186890D01*
G01X1659784Y1186719D02*
X1659790Y1186791D01*
G01X1659786Y1186693D02*
X1659784Y1186719D01*
G01X1659790Y1191791D02*
X1659794Y1191890D01*
G01X1659784Y1191719D02*
X1659790Y1191791D01*
G01X1659786Y1191693D02*
X1659784Y1191719D01*
G01X1659790Y1196791D02*
X1659794Y1196890D01*
G01X1659784Y1196719D02*
X1659790Y1196791D01*
G01X1659786Y1196693D02*
X1659784Y1196719D01*
G01X1658839Y1195313D02*
X1658840Y1195315D01*
G01X1658839Y1195308D02*
Y1195313D01*
G01Y1195299D02*
Y1195308D01*
G01Y1190313D02*
X1658840Y1190315D01*
G01X1658839Y1190308D02*
Y1190313D01*
G01Y1190299D02*
Y1190308D01*
G01Y1185313D02*
X1658840Y1185315D01*
G01X1658839Y1185308D02*
Y1185313D01*
G01Y1185299D02*
Y1185308D01*
G01Y1180313D02*
X1658840Y1180315D01*
G01X1658839Y1180308D02*
Y1180313D01*
G01Y1180299D02*
Y1180308D01*
G01X1659823Y1181660D02*
Y1181667D01*
G01X1659824Y1181656D02*
X1659823Y1181660D01*
G01X1659825Y1181654D02*
X1659824Y1181656D01*
G01X1659823Y1186660D02*
Y1186667D01*
G01X1659824Y1186656D02*
X1659823Y1186660D01*
G01X1659825Y1186654D02*
X1659824Y1186656D01*
G01X1659823Y1191660D02*
Y1191667D01*
G01X1659824Y1191656D02*
X1659823Y1191660D01*
G01X1659825Y1191654D02*
X1659824Y1191656D01*
G01X1659823Y1196660D02*
Y1196667D01*
G01X1659824Y1196656D02*
X1659823Y1196660D01*
G01X1659825Y1196654D02*
X1659824Y1196656D01*
G01X1658839Y1181700D02*
Y1181709D01*
G01Y1181695D02*
Y1181700D01*
G01X1658840Y1181693D02*
X1658839Y1181695D01*
G01Y1186700D02*
Y1186709D01*
G01Y1186695D02*
Y1186700D01*
G01X1658840Y1186693D02*
X1658839Y1186695D01*
G01Y1191700D02*
Y1191709D01*
G01Y1191695D02*
Y1191700D01*
G01X1658840Y1191693D02*
X1658839Y1191695D01*
G01Y1196700D02*
Y1196709D01*
G01Y1196695D02*
Y1196700D01*
G01X1658840Y1196693D02*
X1658839Y1196695D01*
G01X1659815Y1181837D02*
X1659823Y1181811D01*
G01X1659805Y1181863D02*
X1659815Y1181837D01*
G01X1659794Y1181890D02*
X1659805Y1181863D01*
G01X1659815Y1186837D02*
X1659823Y1186811D01*
G01X1659805Y1186863D02*
X1659815Y1186837D01*
G01X1659794Y1186890D02*
X1659805Y1186863D01*
G01X1659815Y1191837D02*
X1659823Y1191811D01*
G01X1659805Y1191863D02*
X1659815Y1191837D01*
G01X1659794Y1191890D02*
X1659805Y1191863D01*
G01X1659815Y1196837D02*
X1659823Y1196811D01*
G01X1659805Y1196863D02*
X1659815Y1196837D01*
G01X1659794Y1196890D02*
X1659805Y1196863D01*
G01X1659806Y1181688D02*
X1659786Y1181693D01*
G01X1659820Y1181674D02*
X1659806Y1181688D01*
G01X1659825Y1181654D02*
X1659820Y1181674D01*
G01X1659806Y1186688D02*
X1659786Y1186693D01*
G01X1659820Y1186674D02*
X1659806Y1186688D01*
G01X1659825Y1186654D02*
X1659820Y1186674D01*
G01X1659806Y1191688D02*
X1659786Y1191693D01*
G01X1659820Y1191674D02*
X1659806Y1191688D01*
G01X1659825Y1191654D02*
X1659820Y1191674D01*
G01X1659806Y1196688D02*
X1659786Y1196693D01*
G01X1659820Y1196674D02*
X1659806Y1196688D01*
G01X1659825Y1196654D02*
X1659820Y1196674D01*
G01X1658268Y1222185D02*
G03X1657677Y1222776I-591J0D01*
G01X1650984D02*
G03X1650394Y1222185I1J-591D01*
G01X1653150Y1221004D02*
G03Y1219035I0J-985D01*
G01X1655512D02*
G03Y1221004I0J985D01*
G01X1665157Y1221594D02*
G03X1663189Y1223563I-1968J1D01*
G01X1645472D02*
G03X1643504Y1221594I0J-1968D01*
G01X1651772Y1213091D02*
G03X1650591Y1211909I0J-1181D01*
G01X1658071D02*
G03X1656890Y1213091I-1181J1D01*
G01X1656220Y1207815D02*
G03I-1889J0D01*
G01X1656693D02*
G03I-2362J0D01*
G01X1653150Y1208406D02*
X1650839Y1212635D01*
G01X1655512Y1206713D02*
X1656815Y1204744D01*
G01X1648622Y1201004D02*
X1649803Y1199823D01*
G01X1643504Y1205846D02*
X1646850Y1202500D01*
G01X1659823Y1181667D02*
Y1181676D01*
G01Y1186667D02*
Y1186676D01*
G01Y1191667D02*
Y1191676D01*
G01Y1196667D02*
Y1196676D01*
G01X1665157Y1205846D02*
Y1221594D01*
G01X1664173Y1195315D02*
Y1196693D01*
G01Y1190315D02*
Y1191693D01*
G01Y1185315D02*
Y1186693D01*
G01Y1180315D02*
Y1181693D01*
G01X1661004D02*
Y1180315D01*
G01Y1186693D02*
Y1185315D01*
G01Y1191693D02*
Y1190315D01*
G01Y1196693D02*
Y1195315D01*
G01X1659823Y1194823D02*
Y1197185D01*
G01Y1189823D02*
Y1192185D01*
G01Y1184823D02*
Y1187185D01*
G01Y1179823D02*
Y1182185D01*
G01Y1181667D02*
Y1181811D01*
G01Y1191667D02*
Y1191811D01*
G01Y1186667D02*
Y1186811D01*
G01Y1196667D02*
Y1196811D01*
G01X1658839Y1182185D02*
Y1179823D01*
G01Y1187185D02*
Y1184823D01*
G01Y1192185D02*
Y1189823D01*
G01Y1197185D02*
Y1194823D01*
G01X1658268Y1216083D02*
Y1222185D01*
G01X1658071Y1211909D02*
Y1203366D01*
G01X1655512Y1208406D02*
Y1206713D01*
G01X1653150D02*
Y1208406D01*
G01X1650591Y1203366D02*
Y1211909D01*
G01X1650394Y1216083D02*
Y1222185D01*
G01X1643504Y1221594D02*
Y1205846D01*
G01X1663189Y1223563D02*
X1645472D01*
G01X1657677Y1222776D02*
X1650984D01*
G01X1655512Y1221004D02*
X1653150D01*
G01Y1219035D02*
X1655512D01*
G01X1658268Y1217657D02*
X1650394D01*
G01Y1216083D02*
X1658268D01*
G01X1665157Y1213130D02*
X1643504D01*
G01X1651772Y1213091D02*
X1656890D01*
G01X1653150Y1208406D02*
X1655512D01*
G01X1653150Y1206713D02*
X1655512D01*
G01X1646850Y1204744D02*
X1661220D01*
G01X1646850Y1203366D02*
X1650591D01*
G01X1661220D02*
X1658071D01*
G01X1646850Y1202500D02*
X1661811D01*
G01X1648622Y1201004D02*
X1656496D01*
G01X1649803Y1199823D02*
X1655315D01*
G01X1659823Y1197185D02*
X1658839D01*
G01X1658840Y1196693D02*
X1664173D01*
G01Y1196654D02*
X1659825D01*
G01X1664173Y1195315D02*
X1658840D01*
G01X1658839Y1194823D02*
X1659823D01*
G01Y1192185D02*
X1658839D01*
G01X1658840Y1191693D02*
X1664173D01*
G01Y1191654D02*
X1659825D01*
G01X1664173Y1190315D02*
X1658840D01*
G01X1658839Y1189823D02*
X1659823D01*
G01Y1187185D02*
X1658839D01*
G01X1658840Y1186693D02*
X1664173D01*
G01Y1186654D02*
X1659825D01*
G01X1664173Y1185315D02*
X1658840D01*
G01X1658839Y1184823D02*
X1659823D01*
G01Y1182185D02*
X1658839D01*
G01X1658840Y1181693D02*
X1664173D01*
G01Y1181654D02*
X1659825D01*
G01X1664173Y1180315D02*
X1658840D01*
G01X1658839Y1179823D02*
X1659823D01*
G01X1658839Y1196889D02*
X1659794Y1196890D01*
G01X1659823Y1195119D02*
X1658839Y1195118D01*
G01Y1191889D02*
X1659794Y1191890D01*
G01X1659823Y1190119D02*
X1658839Y1190118D01*
G01Y1186889D02*
X1659794Y1186890D01*
G01X1659823Y1185119D02*
X1658839Y1185118D01*
G01Y1181889D02*
X1659794Y1181890D01*
G01X1659823Y1180119D02*
X1658839Y1180118D01*
G01X1657822Y1212635D02*
X1655512Y1208406D01*
G01X1651846Y1204744D02*
X1653150Y1206713D01*
G01X1665157Y1205846D02*
X1661811Y1202500D01*
G01X1655315Y1199823D02*
X1656496Y1201004D01*
G01X1635290Y1656868D02*
Y1659668D01*
G01X1638583Y1841823D02*
Y1822886D01*
G01X1764685Y210551D02*
Y211732D01*
G01Y207402D02*
Y208583D01*
G01Y204252D02*
Y205433D01*
G01Y201102D02*
Y202283D01*
G01Y197953D02*
Y199134D01*
G01X1770569Y211732D02*
X1764685D01*
G01Y211693D02*
X1770609D01*
G01Y210591D02*
X1764685D01*
G01X1770569Y210551D02*
X1764685D01*
G01X1770569Y208583D02*
X1764685D01*
G01Y208543D02*
X1770609D01*
G01Y207441D02*
X1764685D01*
G01X1770569Y207402D02*
X1764685D01*
G01X1770569Y205433D02*
X1764685D01*
G01Y205394D02*
X1770609D01*
G01Y204291D02*
X1764685D01*
G01X1770569Y204252D02*
X1764685D01*
G01X1770569Y202283D02*
X1764685D01*
G01Y202244D02*
X1770609D01*
G01Y201142D02*
X1764685D01*
G01X1770569Y201102D02*
X1764685D01*
G01X1770569Y199134D02*
X1764685D01*
G01Y199094D02*
X1770609D01*
G01Y197992D02*
X1764685D01*
G01X1770569Y197953D02*
X1764685D01*
G01Y216850D02*
Y218031D01*
G01Y213701D02*
Y214882D01*
G01X1770569Y218031D02*
X1764685D01*
G01Y217992D02*
X1770609D01*
G01Y216890D02*
X1764685D01*
G01X1770569Y216850D02*
X1764685D01*
G01X1770569Y214882D02*
X1764685D01*
G01Y214843D02*
X1770609D01*
G01Y213740D02*
X1764685D01*
G01X1770569Y213701D02*
X1764685D01*
G01X1738583Y374803D02*
G03X1739764I590J0D01*
G01Y368504D02*
G03X1738583I-590J0D01*
G01X1736614D02*
G03X1735433I-591J0D01*
G01Y374803D02*
G03X1736614I590J0D01*
G01X1738583D02*
G03X1739764I590J0D01*
G01Y368504D02*
G03X1738583I-590J0D01*
G01X1736614D02*
G03X1735433I-591J0D01*
G01Y374803D02*
G03X1736614I590J0D01*
G01X1740551Y368504D02*
Y374803D01*
G01Y368504D02*
Y374803D01*
G01X1734646Y368504D02*
Y374803D01*
G01D02*
Y368504D01*
G01X1738583Y374803D02*
X1736614D01*
G01X1735433D02*
X1734646D01*
G01X1738583D02*
X1736614D01*
G01X1735433D02*
X1734646D01*
G01X1740551D02*
X1739764D01*
G01X1740551D02*
X1739764D01*
G01X1740551Y373819D02*
X1734646D01*
G01Y373622D02*
X1740551D01*
G01X1734646Y369685D02*
X1740551D01*
G01Y369488D02*
X1734646D01*
G01X1739764Y368504D02*
X1740551D01*
G01X1739764D02*
X1740551D01*
G01X1736614D02*
X1738583D01*
G01X1734646D02*
X1735433D01*
G01X1736614D02*
X1738583D01*
G01X1734646D02*
X1735433D01*
G01X1764685Y669606D02*
Y670787D01*
G01Y666457D02*
Y667638D01*
G01Y663307D02*
Y664488D01*
G01Y660157D02*
Y661339D01*
G01Y657008D02*
Y658189D01*
G01Y653858D02*
Y655039D01*
G01Y650709D02*
Y651890D01*
G01X1770569Y670787D02*
X1764685D01*
G01Y670748D02*
X1770609D01*
G01Y669646D02*
X1764685D01*
G01X1770569Y669606D02*
X1764685D01*
G01X1770569Y667638D02*
X1764685D01*
G01Y667598D02*
X1770609D01*
G01Y666496D02*
X1764685D01*
G01X1770569Y666457D02*
X1764685D01*
G01X1770569Y664488D02*
X1764685D01*
G01Y664449D02*
X1770609D01*
G01Y663346D02*
X1764685D01*
G01X1770569Y663307D02*
X1764685D01*
G01X1770569Y661339D02*
X1764685D01*
G01Y661299D02*
X1770609D01*
G01Y660197D02*
X1764685D01*
G01X1770569Y660157D02*
X1764685D01*
G01X1770569Y658189D02*
X1764685D01*
G01Y658150D02*
X1770609D01*
G01Y657047D02*
X1764685D01*
G01X1770569Y657008D02*
X1764685D01*
G01X1770569Y655039D02*
X1764685D01*
G01Y655000D02*
X1770609D01*
G01Y653898D02*
X1764685D01*
G01X1770569Y653858D02*
X1764685D01*
G01X1770569Y651890D02*
X1764685D01*
G01Y651850D02*
X1770609D01*
G01Y650748D02*
X1764685D01*
G01X1770569Y650709D02*
X1764685D01*
G01X1738583Y827559D02*
G03X1739764I590J0D01*
G01Y821260D02*
G03X1738583I-590J0D01*
G01X1736614D02*
G03X1735433I-591J0D01*
G01Y827559D02*
G03X1736614I590J0D01*
G01X1738583D02*
G03X1739764I590J0D01*
G01Y821260D02*
G03X1738583I-590J0D01*
G01X1736614D02*
G03X1735433I-591J0D01*
G01Y827559D02*
G03X1736614I590J0D01*
G01X1740551Y821260D02*
Y827559D01*
G01Y821260D02*
Y827559D01*
G01X1734646Y821260D02*
Y827559D01*
G01D02*
Y821260D01*
G01X1738583Y827559D02*
X1736614D01*
G01X1735433D02*
X1734646D01*
G01X1738583D02*
X1736614D01*
G01X1735433D02*
X1734646D01*
G01X1740551D02*
X1739764D01*
G01X1740551D02*
X1739764D01*
G01X1740551Y826575D02*
X1734646D01*
G01Y826378D02*
X1740551D01*
G01X1734646Y822441D02*
X1740551D01*
G01Y822244D02*
X1734646D01*
G01X1739764Y821260D02*
X1740551D01*
G01X1739764D02*
X1740551D01*
G01X1736614D02*
X1738583D01*
G01X1734646D02*
X1735433D01*
G01X1736614D02*
X1738583D01*
G01X1734646D02*
X1735433D01*
G01X1764685Y1122362D02*
Y1123543D01*
G01Y1119213D02*
Y1120394D01*
G01Y1116063D02*
Y1117244D01*
G01Y1112913D02*
Y1114094D01*
G01Y1109764D02*
Y1110945D01*
G01Y1106614D02*
Y1107795D01*
G01Y1103465D02*
Y1104646D01*
G01X1770569Y1123543D02*
X1764685D01*
G01Y1123504D02*
X1770609D01*
G01Y1122402D02*
X1764685D01*
G01X1770569Y1122362D02*
X1764685D01*
G01X1770569Y1120394D02*
X1764685D01*
G01Y1120354D02*
X1770609D01*
G01Y1119252D02*
X1764685D01*
G01X1770569Y1119213D02*
X1764685D01*
G01X1770569Y1117244D02*
X1764685D01*
G01Y1117205D02*
X1770609D01*
G01Y1116102D02*
X1764685D01*
G01X1770569Y1116063D02*
X1764685D01*
G01X1770569Y1114094D02*
X1764685D01*
G01Y1114055D02*
X1770609D01*
G01Y1112953D02*
X1764685D01*
G01X1770569Y1112913D02*
X1764685D01*
G01X1770569Y1110945D02*
X1764685D01*
G01Y1110906D02*
X1770609D01*
G01Y1109803D02*
X1764685D01*
G01X1770569Y1109764D02*
X1764685D01*
G01X1770569Y1107795D02*
X1764685D01*
G01Y1107756D02*
X1770609D01*
G01Y1106654D02*
X1764685D01*
G01X1770569Y1106614D02*
X1764685D01*
G01X1770569Y1104646D02*
X1764685D01*
G01Y1104606D02*
X1770609D01*
G01Y1103504D02*
X1764685D01*
G01X1770569Y1103465D02*
X1764685D01*
G01X1739764Y1274016D02*
G03X1738583I-590J0D01*
G01X1736614D02*
G03X1735433I-591J0D01*
G01X1739764D02*
G03X1738583I-590J0D01*
G01X1736614D02*
G03X1735433I-591J0D01*
G01X1740551D02*
Y1280315D01*
G01Y1274016D02*
Y1280315D01*
G01X1734646Y1274016D02*
Y1280315D01*
G01D02*
Y1274016D01*
G01Y1275197D02*
X1740551D01*
G01Y1275000D02*
X1734646D01*
G01X1739764Y1274016D02*
X1740551D01*
G01X1739764D02*
X1740551D01*
G01X1736614D02*
X1738583D01*
G01X1734646D02*
X1735433D01*
G01X1736614D02*
X1738583D01*
G01X1734646D02*
X1735433D01*
G01X1738583Y1280315D02*
G03X1739764I590J0D01*
G01X1735433D02*
G03X1736614I590J0D01*
G01X1738583D02*
G03X1739764I590J0D01*
G01X1735433D02*
G03X1736614I590J0D01*
G01X1738583D02*
X1736614D01*
G01X1735433D02*
X1734646D01*
G01X1738583D02*
X1736614D01*
G01X1735433D02*
X1734646D01*
G01X1740551D02*
X1739764D01*
G01X1740551D02*
X1739764D01*
G01X1740551Y1279331D02*
X1734646D01*
G01Y1279134D02*
X1740551D01*
G01X1797539Y51969D02*
G03X1806201I4331J0D01*
G01D02*
G03X1797539I-4331J0D01*
G01X1806201D02*
G03I-4331J0D01*
G01X1779646Y153681D02*
G03I-1103J0D01*
G01X1780118D02*
G03I-1575J0D01*
G01X1774606Y139311D02*
G03X1775197Y138720I591J0D01*
G01X1781890D02*
G03X1782480Y139311I-1J591D01*
G01X1779724Y140492D02*
G03Y142461I0J984D01*
G01X1777362D02*
G03Y140492I0J-984D01*
G01X1781102Y148406D02*
G03X1782283Y149587I0J1181D01*
G01X1774803D02*
G03X1775984Y148406I1181J0D01*
G01X1767717Y139902D02*
G03X1769685Y137933I1968J-1D01*
G01X1787402D02*
G03X1789370Y139902I-1J1969D01*
G01X1774016Y161673D02*
X1772835Y160492D01*
G01X1771063Y158996D02*
X1767717Y155650D01*
G01X1781028Y156752D02*
X1779724Y154783D01*
G01X1775052Y148861D02*
X1777362Y153091D01*
G01X1789370Y139902D02*
Y155650D01*
G01X1786024Y296988D02*
Y158996D01*
G01X1785433Y299232D02*
Y156752D01*
G01X1782480Y145413D02*
Y139311D01*
G01X1782283Y158130D02*
Y149587D01*
G01X1780709Y196949D02*
Y160492D01*
G01X1779724Y154783D02*
Y153091D01*
G01X1779528Y198130D02*
Y161673D01*
G01X1777362Y153091D02*
Y154783D01*
G01X1774803Y149587D02*
Y158130D01*
G01X1774606Y145413D02*
Y139311D01*
G01X1774016Y161673D02*
Y294311D01*
G01X1772835Y160492D02*
Y295492D01*
G01X1771063Y195787D02*
Y156752D01*
G01X1767717Y155650D02*
Y139902D01*
G01X1779724Y153091D02*
X1782035Y148861D01*
G01X1777362Y154783D02*
X1776059Y156752D01*
G01X1789370Y155650D02*
X1786024Y158996D01*
G01X1779528Y161673D02*
X1780709Y160492D01*
G01X1779528Y161673D02*
X1774016D01*
G01X1780709Y160492D02*
X1772835D01*
G01X1786024Y158996D02*
X1771063D01*
G01X1782283Y158130D02*
X1785433D01*
G01X1774803D02*
X1771063D01*
G01Y156752D02*
X1785433D01*
G01X1779724Y154783D02*
X1777362D01*
G01X1779724Y153091D02*
X1777362D01*
G01X1781102Y148406D02*
X1775984D01*
G01X1789370Y148366D02*
X1767717D01*
G01X1782480Y145413D02*
X1774606D01*
G01Y143839D02*
X1782480D01*
G01X1779724Y142461D02*
X1777362D01*
G01Y140492D02*
X1779724D01*
G01X1781890Y138720D02*
X1775197D01*
G01X1787402Y137933D02*
X1769685D01*
G01X1769629Y199114D02*
X1769624Y199094D01*
G01X1769643Y199129D02*
X1769629Y199114D01*
G01X1769663Y199134D02*
X1769643Y199129D01*
G01X1769629Y202264D02*
X1769624Y202244D01*
G01X1769643Y202278D02*
X1769629Y202264D01*
G01X1769663Y202283D02*
X1769643Y202278D01*
G01X1769629Y205413D02*
X1769624Y205394D01*
G01X1769643Y205428D02*
X1769629Y205413D01*
G01X1769663Y205433D02*
X1769643Y205428D01*
G01X1769629Y208563D02*
X1769624Y208543D01*
G01X1769643Y208578D02*
X1769629Y208563D01*
G01X1769663Y208583D02*
X1769643Y208578D01*
G01X1769629Y211713D02*
X1769624Y211693D01*
G01X1769643Y211727D02*
X1769629Y211713D01*
G01X1769663Y211732D02*
X1769643Y211727D01*
G01X1770604Y197972D02*
X1770609Y197992D01*
G01X1770589Y197958D02*
X1770604Y197972D01*
G01X1770569Y197953D02*
X1770589Y197958D01*
G01X1770604Y201122D02*
X1770609Y201142D01*
G01X1770589Y201108D02*
X1770604Y201122D01*
G01X1770569Y201102D02*
X1770589Y201108D01*
G01X1770604Y204272D02*
X1770609Y204291D01*
G01X1770589Y204257D02*
X1770604Y204272D01*
G01X1770569Y204252D02*
X1770589Y204257D01*
G01X1770604Y207421D02*
X1770609Y207441D01*
G01X1770589Y207407D02*
X1770604Y207421D01*
G01X1770569Y207402D02*
X1770589Y207407D01*
G01X1770604Y210571D02*
X1770609Y210591D01*
G01X1770589Y210557D02*
X1770604Y210571D01*
G01X1770569Y210551D02*
X1770589Y210557D01*
G01X1770588Y197945D02*
X1770591Y197947D01*
G01X1770585Y197944D02*
X1770588Y197945D01*
G01X1770581Y197943D02*
X1770585Y197944D01*
G01X1770578Y197942D02*
X1770581Y197943D01*
G01X1770574Y197942D02*
X1770578D01*
G01X1770571D02*
X1770574D01*
G01X1769648Y199142D02*
X1769645Y199140D01*
G01X1769652Y199143D02*
X1769648Y199142D01*
G01X1769655Y199144D02*
X1769652Y199143D01*
G01X1769658Y199144D02*
X1769655D01*
G01X1769662Y199145D02*
X1769658Y199144D01*
G01X1769665Y199145D02*
X1769662D01*
G01X1770588Y201095D02*
X1770591Y201096D01*
G01X1770585Y201094D02*
X1770588Y201095D01*
G01X1770581Y201093D02*
X1770585Y201094D01*
G01X1770578Y201092D02*
X1770581Y201093D01*
G01X1770574Y201091D02*
X1770578Y201092D01*
G01X1770571Y201091D02*
X1770574D01*
G01X1769648Y202291D02*
X1769645Y202290D01*
G01X1769652Y202293D02*
X1769648Y202291D01*
G01X1769655Y202294D02*
X1769652Y202293D01*
G01X1769658Y202294D02*
X1769655D01*
G01X1769662Y202295D02*
X1769658Y202294D01*
G01X1769665Y202295D02*
X1769662D01*
G01X1770588Y204244D02*
X1770591Y204246D01*
G01X1770585Y204243D02*
X1770588Y204244D01*
G01X1770581Y204242D02*
X1770585Y204243D01*
G01X1770578Y204241D02*
X1770581Y204242D01*
G01X1770574Y204241D02*
X1770578D01*
G01X1770571D02*
X1770574D01*
G01X1769648Y205441D02*
X1769645Y205439D01*
G01X1769652Y205442D02*
X1769648Y205441D01*
G01X1769655Y205443D02*
X1769652Y205442D01*
G01X1769658Y205444D02*
X1769655Y205443D01*
G01X1769662Y205444D02*
X1769658D01*
G01X1769665D02*
X1769662D01*
G01X1770588Y207394D02*
X1770591Y207396D01*
G01X1770585Y207393D02*
X1770588Y207394D01*
G01X1770581Y207392D02*
X1770585Y207393D01*
G01X1770578Y207391D02*
X1770581Y207392D01*
G01X1770574Y207391D02*
X1770578D01*
G01X1770571D02*
X1770574D01*
G01X1769648Y208591D02*
X1769645Y208589D01*
G01X1769652Y208592D02*
X1769648Y208591D01*
G01X1769655Y208593D02*
X1769652Y208592D01*
G01X1769658Y208593D02*
X1769655D01*
G01X1769662Y208594D02*
X1769658Y208593D01*
G01X1769665Y208594D02*
X1769662D01*
G01X1770588Y210544D02*
X1770591Y210545D01*
G01X1770585Y210543D02*
X1770588Y210544D01*
G01X1770581Y210541D02*
X1770585Y210543D01*
G01X1770578Y210541D02*
X1770581D01*
G01X1770574Y210540D02*
X1770578Y210541D01*
G01X1770571Y210540D02*
X1770574D01*
G01X1769648Y211740D02*
X1769645Y211739D01*
G01X1769652Y211741D02*
X1769648Y211740D01*
G01X1769655Y211743D02*
X1769652Y211741D01*
G01X1769658Y211743D02*
X1769655D01*
G01X1769662Y211744D02*
X1769658Y211743D01*
G01X1769665Y211744D02*
X1769662D01*
G01X1770601Y199132D02*
X1770605Y199127D01*
G01X1770596Y199137D02*
X1770601Y199132D01*
G01X1770590Y199141D02*
X1770596Y199137D01*
G01X1770584Y199143D02*
X1770590Y199141D01*
G01X1770578Y199145D02*
X1770584Y199143D01*
G01X1770571Y199145D02*
X1770578D01*
G01X1770601Y202282D02*
X1770605Y202277D01*
G01X1770596Y202286D02*
X1770601Y202282D01*
G01X1770590Y202290D02*
X1770596Y202286D01*
G01X1770584Y202293D02*
X1770590Y202290D01*
G01X1770578Y202294D02*
X1770584Y202293D01*
G01X1770571Y202295D02*
X1770578Y202294D01*
G01X1770601Y205431D02*
X1770605Y205426D01*
G01X1770596Y205436D02*
X1770601Y205431D01*
G01X1770590Y205440D02*
X1770596Y205436D01*
G01X1770584Y205442D02*
X1770590Y205440D01*
G01X1770578Y205444D02*
X1770584Y205442D01*
G01X1770571Y205444D02*
X1770578D01*
G01X1770601Y208581D02*
X1770605Y208576D01*
G01X1770596Y208585D02*
X1770601Y208581D01*
G01X1770590Y208589D02*
X1770596Y208585D01*
G01X1770584Y208592D02*
X1770590Y208589D01*
G01X1770578Y208594D02*
X1770584Y208592D01*
G01X1770571Y208594D02*
X1770578D01*
G01X1770601Y211731D02*
X1770605Y211726D01*
G01X1770596Y211735D02*
X1770601Y211731D01*
G01X1770590Y211739D02*
X1770596Y211735D01*
G01X1770584Y211741D02*
X1770590Y211739D01*
G01X1770578Y211743D02*
X1770584Y211741D01*
G01X1770571Y211744D02*
X1770578Y211743D01*
G01X1769627Y197971D02*
X1769626Y197979D01*
G01X1769629Y197965D02*
X1769627Y197971D01*
G01X1769633Y197958D02*
X1769629Y197965D01*
G01X1769637Y197952D02*
X1769633Y197958D01*
G01X1769644Y197948D02*
X1769637Y197952D01*
G01X1769650Y197944D02*
X1769644Y197948D01*
G01X1769658Y197943D02*
X1769650Y197944D01*
G01X1769665Y197942D02*
X1769658Y197943D01*
G01X1769627Y201121D02*
X1769626Y201128D01*
G01X1769629Y201114D02*
X1769627Y201121D01*
G01X1769633Y201108D02*
X1769629Y201114D01*
G01X1769637Y201102D02*
X1769633Y201108D01*
G01X1769644Y201097D02*
X1769637Y201102D01*
G01X1769650Y201094D02*
X1769644Y201097D01*
G01X1769658Y201092D02*
X1769650Y201094D01*
G01X1769665Y201091D02*
X1769658Y201092D01*
G01X1769627Y204270D02*
X1769626Y204278D01*
G01X1769629Y204264D02*
X1769627Y204270D01*
G01X1769633Y204257D02*
X1769629Y204264D01*
G01X1769637Y204252D02*
X1769633Y204257D01*
G01X1769644Y204247D02*
X1769637Y204252D01*
G01X1769650Y204244D02*
X1769644Y204247D01*
G01X1769658Y204242D02*
X1769650Y204244D01*
G01X1769665Y204241D02*
X1769658Y204242D01*
G01X1769627Y207420D02*
X1769626Y207428D01*
G01X1769629Y207413D02*
X1769627Y207420D01*
G01X1769633Y207407D02*
X1769629Y207413D01*
G01X1769637Y207401D02*
X1769633Y207407D01*
G01X1769644Y207396D02*
X1769637Y207401D01*
G01X1769650Y207393D02*
X1769644Y207396D01*
G01X1769658Y207391D02*
X1769650Y207393D01*
G01X1769665Y207391D02*
X1769658D01*
G01X1769627Y210570D02*
X1769626Y210577D01*
G01X1769629Y210563D02*
X1769627Y210570D01*
G01X1769633Y210557D02*
X1769629Y210563D01*
G01X1769637Y210551D02*
X1769633Y210557D01*
G01X1769644Y210546D02*
X1769637Y210551D01*
G01X1769650Y210543D02*
X1769644Y210546D01*
G01X1769658Y210541D02*
X1769650Y210543D01*
G01X1769665Y210540D02*
X1769658Y210541D01*
G01X1770580Y199133D02*
X1770589Y199128D01*
G01X1770569Y199134D02*
X1770580Y199133D01*
G01Y202282D02*
X1770589Y202278D01*
G01X1770569Y202283D02*
X1770580Y202282D01*
G01Y205432D02*
X1770589Y205428D01*
G01X1770569Y205433D02*
X1770580Y205432D01*
G01Y208581D02*
X1770589Y208577D01*
G01X1770569Y208583D02*
X1770580Y208581D01*
G01Y211731D02*
X1770589Y211727D01*
G01X1770569Y211732D02*
X1770580Y211731D01*
G01X1769626Y201132D02*
Y201128D01*
G01X1769628Y201126D02*
X1769626Y201132D01*
G01X1769639Y201111D02*
X1769628Y201126D01*
G01X1769664Y201102D02*
X1769639Y201111D01*
G01X1769626Y204282D02*
Y204278D01*
G01X1769628Y204276D02*
X1769626Y204282D01*
G01X1769639Y204260D02*
X1769628Y204276D01*
G01X1769663Y204252D02*
X1769639Y204260D01*
G01X1769626Y210581D02*
Y210577D01*
G01X1769628Y210575D02*
X1769626Y210581D01*
G01X1769639Y210559D02*
X1769628Y210575D01*
G01X1769663Y210551D02*
X1769639Y210559D01*
G01X1769626Y197983D02*
Y197979D01*
G01X1769628Y197976D02*
X1769626Y197983D01*
G01X1769639Y197961D02*
X1769628Y197976D01*
G01X1769663Y197953D02*
X1769639Y197961D01*
G01X1784023Y166173D02*
X1784034Y166157D01*
G01X1783998Y166181D02*
X1784023Y166173D01*
G01Y171173D02*
X1784034Y171157D01*
G01X1783998Y171181D02*
X1784023Y171173D01*
G01Y176173D02*
X1784034Y176157D01*
G01X1783998Y176181D02*
X1784023Y176173D01*
G01Y181173D02*
X1784034Y181157D01*
G01X1783998Y181181D02*
X1784023Y181173D01*
G01Y186173D02*
X1784034Y186157D01*
G01X1783998Y186181D02*
X1784023Y186173D01*
G01Y191173D02*
X1784034Y191157D01*
G01X1783998Y191181D02*
X1784023Y191173D01*
G01Y196173D02*
X1784034Y196157D01*
G01X1783998Y196181D02*
X1784023Y196173D01*
G01X1769626Y207431D02*
Y207428D01*
G01X1769627Y207426D02*
X1769626Y207431D01*
G01X1769637Y207411D02*
X1769627Y207426D01*
G01X1769661Y207402D02*
X1769637Y207411D01*
G01X1770579Y205432D02*
X1770569Y205433D01*
G01X1770587Y205429D02*
X1770579Y205432D01*
G01X1770595Y205424D02*
X1770587Y205429D01*
G01X1770579Y199133D02*
X1770569Y199134D01*
G01X1770588Y199130D02*
X1770579Y199133D01*
G01X1770595Y199124D02*
X1770588Y199130D01*
G01X1770579Y202282D02*
X1770569Y202283D01*
G01X1770588Y202279D02*
X1770579Y202282D01*
G01X1770595Y202274D02*
X1770588Y202279D01*
G01X1770579Y208581D02*
X1770569Y208583D01*
G01X1770588Y208578D02*
X1770579Y208581D01*
G01X1770595Y208573D02*
X1770588Y208578D01*
G01X1770579Y211731D02*
X1770569Y211732D01*
G01X1770588Y211728D02*
X1770579Y211731D01*
G01X1770595Y211723D02*
X1770588Y211728D01*
G01X1769665Y197948D02*
Y197942D01*
G01X1769664Y197952D02*
X1769665Y197948D01*
G01X1769663Y197953D02*
X1769664Y197952D01*
G01X1769665Y201098D02*
Y201091D01*
G01X1769664Y201101D02*
X1769665Y201098D01*
G01X1769663Y201102D02*
X1769664Y201101D01*
G01X1769665Y204247D02*
Y204241D01*
G01X1769664Y204251D02*
X1769665Y204247D01*
G01X1769663Y204252D02*
X1769664Y204251D01*
G01X1769665Y207397D02*
Y207391D01*
G01X1769664Y207400D02*
X1769665Y207397D01*
G01X1769663Y207402D02*
X1769664Y207400D01*
G01X1769665Y210546D02*
Y210540D01*
G01X1769664Y210550D02*
X1769665Y210546D01*
G01X1769663Y210551D02*
X1769664Y210550D01*
G01X1784036Y166148D02*
X1784035Y166156D01*
G01X1784037Y166144D02*
X1784036Y166148D01*
G01X1784038Y166142D02*
X1784037Y166144D01*
G01X1784036Y171148D02*
X1784035Y171156D01*
G01X1784037Y171144D02*
X1784036Y171148D01*
G01X1784038Y171142D02*
X1784037Y171144D01*
G01X1784036Y176148D02*
X1784035Y176156D01*
G01X1784037Y176144D02*
X1784036Y176148D01*
G01X1784038Y176142D02*
X1784037Y176144D01*
G01X1784036Y181148D02*
X1784035Y181156D01*
G01X1784037Y181144D02*
X1784036Y181148D01*
G01X1784038Y181142D02*
X1784037Y181144D01*
G01X1784036Y186148D02*
X1784035Y186156D01*
G01X1784037Y186144D02*
X1784036Y186148D01*
G01X1784038Y186142D02*
X1784037Y186144D01*
G01X1784036Y191148D02*
X1784035Y191156D01*
G01X1784037Y191144D02*
X1784036Y191148D01*
G01X1784038Y191142D02*
X1784037Y191144D01*
G01X1784036Y196148D02*
X1784035Y196156D01*
G01X1784037Y196144D02*
X1784036Y196148D01*
G01X1784038Y196142D02*
X1784037Y196144D01*
G01X1769649Y201105D02*
X1769663Y201102D01*
G01X1769637Y201112D02*
X1769649Y201105D01*
G01X1769625Y201131D02*
X1769637Y201112D01*
G01X1769649Y210554D02*
X1769663Y210551D01*
G01X1769637Y210561D02*
X1769649Y210554D01*
G01X1769625Y210580D02*
X1769637Y210561D01*
G01X1769648Y204255D02*
X1769663Y204252D01*
G01X1769636Y204263D02*
X1769648Y204255D01*
G01X1769624Y204283D02*
X1769636Y204263D01*
G01X1770610Y197986D02*
Y197979D01*
G01X1770609Y197991D02*
X1770610Y197986D01*
G01X1770609Y197992D02*
Y197991D01*
G01X1770610Y201136D02*
Y201128D01*
G01X1770609Y201141D02*
X1770610Y201136D01*
G01X1770609Y201142D02*
Y201141D01*
G01X1770610Y204285D02*
Y204278D01*
G01X1770609Y204290D02*
X1770610Y204285D01*
G01X1770609Y204291D02*
Y204290D01*
G01X1770610Y207435D02*
Y207428D01*
G01X1770609Y207440D02*
X1770610Y207435D01*
G01X1770609Y207441D02*
Y207440D01*
G01X1770610Y210585D02*
Y210577D01*
G01X1770609Y210589D02*
X1770610Y210585D01*
G01X1770609Y210591D02*
Y210589D01*
G01X1769648Y197956D02*
X1769663Y197953D01*
G01X1769635Y197964D02*
X1769648Y197956D01*
G01X1769624Y197985D02*
X1769635Y197964D01*
G01X1770609Y199115D02*
X1770610Y199108D01*
G01X1770608Y199121D02*
X1770609Y199115D01*
G01X1770605Y199127D02*
X1770608Y199121D01*
G01X1770609Y202265D02*
X1770610Y202258D01*
G01X1770608Y202271D02*
X1770609Y202265D01*
G01X1770605Y202277D02*
X1770608Y202271D01*
G01X1770609Y205414D02*
X1770610Y205407D01*
G01X1770608Y205420D02*
X1770609Y205414D01*
G01X1770605Y205426D02*
X1770608Y205420D01*
G01X1770609Y208564D02*
X1770610Y208557D01*
G01X1770608Y208570D02*
X1770609Y208564D01*
G01X1770605Y208576D02*
X1770608Y208570D01*
G01X1770609Y211713D02*
X1770610Y211707D01*
G01X1770608Y211720D02*
X1770609Y211713D01*
G01X1770605Y211726D02*
X1770608Y211720D01*
G01X1770571Y197948D02*
X1770572Y197942D01*
G01X1770570Y197952D02*
X1770571Y197948D01*
G01X1770569Y197953D02*
X1770570Y197952D01*
G01X1770571Y201097D02*
X1770572Y201091D01*
G01X1770570Y201101D02*
X1770571Y201097D01*
G01X1770569Y201102D02*
X1770570Y201101D01*
G01X1770571Y204247D02*
X1770572Y204241D01*
G01X1770570Y204251D02*
X1770571Y204247D01*
G01X1770569Y204252D02*
X1770570Y204251D01*
G01X1770571Y207396D02*
X1770572Y207391D01*
G01X1770570Y207400D02*
X1770571Y207396D01*
G01X1770569Y207402D02*
X1770570Y207400D01*
G01X1770571Y210546D02*
X1770572Y210540D01*
G01X1770570Y210550D02*
X1770571Y210546D01*
G01X1770569Y210551D02*
X1770570Y210550D01*
G01X1783051Y166189D02*
Y166198D01*
G01X1783052Y166183D02*
X1783051Y166189D01*
G01X1783053Y166181D02*
X1783052Y166183D01*
G01X1783051Y171189D02*
Y171198D01*
G01X1783052Y171183D02*
X1783051Y171189D01*
G01X1783053Y171181D02*
X1783052Y171183D01*
G01X1783051Y176189D02*
Y176198D01*
G01X1783052Y176183D02*
X1783051Y176189D01*
G01X1783053Y176181D02*
X1783052Y176183D01*
G01X1783051Y181189D02*
Y181198D01*
G01X1783052Y181183D02*
X1783051Y181189D01*
G01X1783053Y181181D02*
X1783052Y181183D01*
G01X1783051Y186189D02*
Y186198D01*
G01X1783052Y186183D02*
X1783051Y186189D01*
G01X1783053Y186181D02*
X1783052Y186183D01*
G01X1783051Y191189D02*
Y191198D01*
G01X1783052Y191183D02*
X1783051Y191189D01*
G01X1783053Y191181D02*
X1783052Y191183D01*
G01X1783051Y196189D02*
Y196198D01*
G01X1783052Y196183D02*
X1783051Y196189D01*
G01X1783053Y196181D02*
X1783052Y196183D01*
G01X1784028Y166325D02*
X1784035Y166299D01*
G01X1784018Y166352D02*
X1784028Y166325D01*
G01X1784006Y166378D02*
X1784018Y166352D01*
G01X1784028Y171325D02*
X1784035Y171299D01*
G01X1784018Y171352D02*
X1784028Y171325D01*
G01X1784006Y171378D02*
X1784018Y171352D01*
G01X1784028Y176325D02*
X1784035Y176299D01*
G01X1784018Y176352D02*
X1784028Y176325D01*
G01X1784006Y176378D02*
X1784018Y176352D01*
G01X1784028Y181325D02*
X1784035Y181299D01*
G01X1784018Y181352D02*
X1784028Y181325D01*
G01X1784006Y181378D02*
X1784018Y181352D01*
G01X1784028Y186325D02*
X1784035Y186299D01*
G01X1784018Y186352D02*
X1784028Y186325D01*
G01X1784006Y186378D02*
X1784018Y186352D01*
G01X1784028Y191325D02*
X1784035Y191299D01*
G01X1784018Y191352D02*
X1784028Y191325D01*
G01X1784006Y191378D02*
X1784018Y191352D01*
G01X1784028Y196325D02*
X1784035Y196299D01*
G01X1784018Y196352D02*
X1784028Y196325D01*
G01X1784006Y196378D02*
X1784018Y196352D01*
G01X1769644Y207407D02*
X1769663Y207402D01*
G01X1769630Y207419D02*
X1769644Y207407D01*
G01X1769624Y207437D02*
X1769630Y207419D01*
G01X1784018Y166176D02*
X1783999Y166181D01*
G01X1784033Y166162D02*
X1784018Y166176D01*
G01X1784038Y166142D02*
X1784033Y166162D01*
G01X1784018Y171176D02*
X1783999Y171181D01*
G01X1784033Y171162D02*
X1784018Y171176D01*
G01X1784038Y171142D02*
X1784033Y171162D01*
G01X1784018Y176176D02*
X1783999Y176181D01*
G01X1784033Y176162D02*
X1784018Y176176D01*
G01X1784038Y176142D02*
X1784033Y176162D01*
G01X1784018Y181176D02*
X1783999Y181181D01*
G01X1784033Y181162D02*
X1784018Y181176D01*
G01X1784038Y181142D02*
X1784033Y181162D01*
G01X1784018Y186176D02*
X1783999Y186181D01*
G01X1784033Y186162D02*
X1784018Y186176D01*
G01X1784038Y186142D02*
X1784033Y186162D01*
G01X1784018Y191176D02*
X1783999Y191181D01*
G01X1784033Y191162D02*
X1784018Y191176D01*
G01X1784038Y191142D02*
X1784033Y191162D01*
G01X1784018Y196176D02*
X1783999Y196181D01*
G01X1784033Y196162D02*
X1784018Y196176D01*
G01X1784038Y196142D02*
X1784033Y196162D01*
G01X1770603Y205415D02*
X1770595Y205424D01*
G01X1770607Y205405D02*
X1770603Y205415D01*
G01X1770609Y205394D02*
X1770607Y205405D01*
G01X1770603Y199116D02*
X1770595Y199124D01*
G01X1770607Y199106D02*
X1770603Y199116D01*
G01X1770609Y199094D02*
X1770607Y199106D01*
G01X1770603Y202265D02*
X1770595Y202274D01*
G01X1770607Y202255D02*
X1770603Y202265D01*
G01X1770609Y202244D02*
X1770607Y202255D01*
G01X1770603Y208565D02*
X1770595Y208573D01*
G01X1770607Y208554D02*
X1770603Y208565D01*
G01X1770609Y208543D02*
X1770607Y208554D01*
G01X1770603Y211714D02*
X1770595Y211723D01*
G01X1770607Y211704D02*
X1770603Y211714D01*
G01X1770609Y211693D02*
X1770607Y211704D01*
G01X1784002Y166279D02*
X1784006Y166378D01*
G01X1783997Y166207D02*
X1784002Y166279D01*
G01X1783999Y166181D02*
X1783997Y166207D01*
G01X1784002Y171279D02*
X1784006Y171378D01*
G01X1783997Y171207D02*
X1784002Y171279D01*
G01X1783999Y171181D02*
X1783997Y171207D01*
G01X1784002Y176279D02*
X1784006Y176378D01*
G01X1783997Y176207D02*
X1784002Y176279D01*
G01X1783999Y176181D02*
X1783997Y176207D01*
G01X1784002Y181279D02*
X1784006Y181378D01*
G01X1783997Y181207D02*
X1784002Y181279D01*
G01X1783999Y181181D02*
X1783997Y181207D01*
G01X1784002Y186279D02*
X1784006Y186378D01*
G01X1783997Y186207D02*
X1784002Y186279D01*
G01X1783999Y186181D02*
X1783997Y186207D01*
G01X1784002Y191279D02*
X1784006Y191378D01*
G01X1783997Y191207D02*
X1784002Y191279D01*
G01X1783999Y191181D02*
X1783997Y191207D01*
G01X1784002Y196279D02*
X1784006Y196378D01*
G01X1783997Y196207D02*
X1784002Y196279D01*
G01X1783999Y196181D02*
X1783997Y196207D01*
G01X1769626Y210585D02*
Y210577D01*
G01X1769625Y210589D02*
X1769626Y210585D01*
G01X1769625Y210580D02*
Y210589D01*
G01X1769666Y211917D02*
X1769665Y211929D01*
G01X1769663Y211904D02*
X1769666Y211917D01*
G01X1769663Y211890D02*
Y211904D01*
G01X1769666Y208767D02*
X1769665Y208780D01*
G01X1769663Y208754D02*
X1769666Y208767D01*
G01X1769663Y208741D02*
Y208754D01*
G01X1769666Y205618D02*
X1769665Y205630D01*
G01X1769663Y205605D02*
X1769666Y205618D01*
G01X1769663Y205591D02*
Y205605D01*
G01X1769666Y202468D02*
X1769665Y202480D01*
G01X1769663Y202455D02*
X1769666Y202468D01*
G01X1769663Y202441D02*
Y202455D01*
G01X1769666Y199319D02*
X1769665Y199331D01*
G01X1769663Y199306D02*
X1769666Y199319D01*
G01X1769663Y199292D02*
Y199306D01*
G01X1769639Y211724D02*
X1769663Y211732D01*
G01X1769628Y211709D02*
X1769639Y211724D01*
G01X1769626Y211703D02*
X1769628Y211709D01*
G01X1769626Y211706D02*
Y211703D01*
G01X1783052Y194802D02*
X1783053Y194803D01*
G01X1783051Y194796D02*
X1783052Y194802D01*
G01X1783051Y194787D02*
Y194796D01*
G01X1783052Y189802D02*
X1783053Y189803D01*
G01X1783051Y189796D02*
X1783052Y189802D01*
G01X1783051Y189787D02*
Y189796D01*
G01X1783052Y184802D02*
X1783053Y184803D01*
G01X1783051Y184796D02*
X1783052Y184802D01*
G01X1783051Y184787D02*
Y184796D01*
G01X1783052Y179802D02*
X1783053Y179803D01*
G01X1783051Y179796D02*
X1783052Y179802D01*
G01X1783051Y179787D02*
Y179796D01*
G01X1783052Y174802D02*
X1783053Y174803D01*
G01X1783051Y174796D02*
X1783052Y174802D01*
G01X1783051Y174787D02*
Y174796D01*
G01X1783052Y169802D02*
X1783053Y169803D01*
G01X1783051Y169796D02*
X1783052Y169802D01*
G01X1783051Y169787D02*
Y169796D01*
G01X1783052Y164802D02*
X1783053Y164803D01*
G01X1783051Y164796D02*
X1783052Y164802D01*
G01X1783051Y164787D02*
Y164796D01*
G01X1769663Y210380D02*
X1769662Y210393D01*
G01X1769666Y210367D02*
X1769663Y210380D01*
G01X1769665Y210354D02*
X1769666Y210367D01*
G01X1769663Y207230D02*
X1769662Y207244D01*
G01X1769666Y207217D02*
X1769663Y207230D01*
G01X1769665Y207205D02*
X1769666Y207217D01*
G01X1769663Y204081D02*
X1769662Y204094D01*
G01X1769666Y204068D02*
X1769663Y204081D01*
G01X1769665Y204055D02*
X1769666Y204068D01*
G01X1769663Y200931D02*
X1769662Y200944D01*
G01X1769666Y200918D02*
X1769663Y200931D01*
G01X1769665Y200906D02*
X1769666Y200918D01*
G01X1769663Y197781D02*
X1769662Y197795D01*
G01X1769666Y197769D02*
X1769663Y197781D01*
G01X1769665Y197756D02*
X1769666Y197769D01*
G01X1770573Y211904D02*
X1770574Y211890D01*
G01X1770570Y211917D02*
X1770573Y211904D01*
G01X1770571Y211929D02*
X1770570Y211917D01*
G01X1770573Y208754D02*
X1770574Y208741D01*
G01X1770570Y208767D02*
X1770573Y208754D01*
G01X1770571Y208780D02*
X1770570Y208767D01*
G01X1770573Y205604D02*
X1770574Y205591D01*
G01X1770570Y205617D02*
X1770573Y205604D01*
G01X1770571Y205630D02*
X1770570Y205617D01*
G01X1770573Y202455D02*
X1770574Y202441D01*
G01X1770570Y202468D02*
X1770573Y202455D01*
G01X1770571Y202480D02*
X1770570Y202468D01*
G01X1770573Y199305D02*
X1770574Y199292D01*
G01X1770570Y199318D02*
X1770573Y199305D01*
G01X1770571Y199331D02*
X1770570Y199318D01*
G01X1769626Y204285D02*
Y204278D01*
G01X1769625Y204290D02*
X1769626Y204285D01*
G01X1769624Y204283D02*
X1769625Y204290D01*
G01X1770570Y210367D02*
X1770571Y210354D01*
G01X1770573Y210380D02*
X1770570Y210367D01*
G01X1770574Y210393D02*
X1770573Y210380D01*
G01X1770570Y207217D02*
X1770571Y207205D01*
G01X1770573Y207230D02*
X1770570Y207217D01*
G01X1770574Y207244D02*
X1770573Y207230D01*
G01X1770570Y204068D02*
X1770571Y204055D01*
G01X1770573Y204081D02*
X1770570Y204068D01*
G01X1770574Y204094D02*
X1770573Y204081D01*
G01X1770570Y200918D02*
X1770571Y200906D01*
G01X1770573Y200931D02*
X1770570Y200918D01*
G01X1770574Y200944D02*
X1770573Y200931D01*
G01X1770570Y197769D02*
X1770571Y197756D01*
G01X1770573Y197781D02*
X1770570Y197769D01*
G01X1770574Y197795D02*
X1770573Y197781D01*
G01X1769626Y197987D02*
Y197979D01*
G01X1769625Y197991D02*
X1769626Y197987D01*
G01X1769624Y197985D02*
X1769625Y197991D01*
G01X1770581Y210553D02*
X1770569Y210551D01*
G01X1770592Y210558D02*
X1770581Y210553D01*
G01Y207404D02*
X1770569Y207402D01*
G01X1770592Y207409D02*
X1770581Y207404D01*
G01Y204254D02*
X1770569Y204252D01*
G01X1770592Y204259D02*
X1770581Y204254D01*
G01Y201104D02*
X1770569Y201102D01*
G01X1770592Y201109D02*
X1770581Y201104D01*
G01Y197955D02*
X1770569Y197953D01*
G01X1770592Y197960D02*
X1770581Y197955D01*
G01X1769639Y208574D02*
X1769663Y208583D01*
G01X1769628Y208560D02*
X1769639Y208574D01*
G01X1769626Y208553D02*
X1769628Y208560D01*
G01X1769639Y205425D02*
X1769663Y205433D01*
G01X1769628Y205410D02*
X1769639Y205425D01*
G01X1769626Y205404D02*
X1769628Y205410D01*
G01X1769639Y202275D02*
X1769663Y202283D01*
G01X1769628Y202261D02*
X1769639Y202275D01*
G01X1769626Y202254D02*
X1769628Y202261D01*
G01X1769639Y199126D02*
X1769663Y199134D01*
G01X1769628Y199111D02*
X1769639Y199126D01*
G01X1769626Y199104D02*
X1769628Y199111D01*
G01X1770610Y211699D02*
Y211706D01*
G01Y211695D02*
Y211699D01*
G01X1770609Y211693D02*
X1770610Y211695D01*
G01Y208550D02*
Y208557D01*
G01Y208545D02*
Y208550D01*
G01X1770609Y208543D02*
X1770610Y208545D01*
G01Y205400D02*
Y205407D01*
G01Y205396D02*
Y205400D01*
G01X1770609Y205394D02*
X1770610Y205396D01*
G01Y202250D02*
Y202257D01*
G01Y202246D02*
Y202250D01*
G01X1770609Y202244D02*
X1770610Y202246D01*
G01Y199101D02*
Y199108D01*
G01Y199096D02*
Y199101D01*
G01X1770609Y199094D02*
X1770610Y199096D01*
G01X1769626Y207435D02*
Y207428D01*
G01X1769625Y207440D02*
X1769626Y207435D01*
G01X1769624Y207437D02*
X1769625Y207440D01*
G01X1769626Y201136D02*
Y201128D01*
G01X1769625Y201141D02*
X1769626Y201136D01*
G01X1769624Y201138D02*
X1769625Y201141D01*
G01X1770571Y211737D02*
Y211744D01*
G01X1770570Y211734D02*
X1770571Y211737D01*
G01X1770569Y211732D02*
X1770570Y211734D01*
G01X1770571Y208588D02*
Y208594D01*
G01X1770570Y208584D02*
X1770571Y208588D01*
G01X1770569Y208583D02*
X1770570Y208584D01*
G01X1770571Y205438D02*
Y205444D01*
G01X1770570Y205435D02*
X1770571Y205438D01*
G01X1770569Y205433D02*
X1770570Y205435D01*
G01X1770571Y202289D02*
Y202295D01*
G01X1770570Y202285D02*
X1770571Y202289D01*
G01X1770569Y202283D02*
X1770570Y202285D01*
G01X1770571Y199139D02*
Y199145D01*
G01X1770570Y199135D02*
X1770571Y199139D01*
G01X1770569Y199134D02*
X1770570Y199135D01*
G01X1769626Y211699D02*
Y211707D01*
G01X1769625Y211694D02*
X1769626Y211699D01*
G01X1769624Y211693D02*
X1769625Y211694D01*
G01X1769626Y208550D02*
Y208557D01*
G01X1769625Y208545D02*
X1769626Y208550D01*
G01X1769624Y208543D02*
X1769625Y208545D01*
G01X1769626Y205400D02*
Y205407D01*
G01X1769625Y205395D02*
X1769626Y205400D01*
G01X1769624Y205394D02*
X1769625Y205395D01*
G01X1769626Y202250D02*
Y202258D01*
G01X1769625Y202246D02*
X1769626Y202250D01*
G01X1769624Y202244D02*
X1769625Y202246D01*
G01X1769626Y199101D02*
Y199108D01*
G01X1769625Y199096D02*
X1769626Y199101D01*
G01X1769624Y199094D02*
X1769625Y199096D01*
G01X1770608Y210565D02*
X1770610Y210577D01*
G01X1770601Y210554D02*
X1770608Y210565D01*
G01X1770591Y210545D02*
X1770601Y210554D01*
G01X1770608Y207415D02*
X1770610Y207428D01*
G01X1770601Y207404D02*
X1770608Y207415D01*
G01X1770591Y207396D02*
X1770601Y207404D01*
G01X1770608Y204265D02*
X1770610Y204278D01*
G01X1770601Y204254D02*
X1770608Y204265D01*
G01X1770591Y204246D02*
X1770601Y204254D01*
G01X1770608Y201116D02*
X1770610Y201128D01*
G01X1770601Y201105D02*
X1770608Y201116D01*
G01X1770591Y201096D02*
X1770601Y201105D01*
G01X1770608Y197966D02*
X1770610Y197979D01*
G01X1770601Y197955D02*
X1770608Y197966D01*
G01X1770591Y197947D02*
X1770601Y197955D01*
G01X1769665Y211737D02*
Y211744D01*
G01Y211733D02*
Y211737D01*
G01X1769663Y211732D02*
X1769665Y211733D01*
G01Y208588D02*
Y208594D01*
G01Y208584D02*
Y208588D01*
G01X1769663Y208583D02*
X1769665Y208584D01*
G01Y205438D02*
Y205444D01*
G01Y205434D02*
Y205438D01*
G01X1769663Y205433D02*
X1769665Y205434D01*
G01Y202289D02*
Y202295D01*
G01Y202285D02*
Y202289D01*
G01X1769663Y202283D02*
X1769665Y202285D01*
G01Y199139D02*
Y199145D01*
G01Y199135D02*
Y199139D01*
G01X1769663Y199134D02*
X1769665Y199135D01*
G01X1769627Y211713D02*
X1769626Y211707D01*
G01X1769628Y211719D02*
X1769627Y211713D01*
G01X1769631Y211725D02*
X1769628Y211719D01*
G01X1769635Y211730D02*
X1769631Y211725D01*
G01X1769640Y211735D02*
X1769635Y211730D01*
G01X1769645Y211739D02*
X1769640Y211735D01*
G01X1769627Y208563D02*
X1769626Y208557D01*
G01X1769628Y208570D02*
X1769627Y208563D01*
G01X1769631Y208575D02*
X1769628Y208570D01*
G01X1769635Y208581D02*
X1769631Y208575D01*
G01X1769640Y208585D02*
X1769635Y208581D01*
G01X1769645Y208589D02*
X1769640Y208585D01*
G01X1769627Y205414D02*
X1769626Y205407D01*
G01X1769628Y205420D02*
X1769627Y205414D01*
G01X1769631Y205426D02*
X1769628Y205420D01*
G01X1769635Y205431D02*
X1769631Y205426D01*
G01X1769640Y205435D02*
X1769635Y205431D01*
G01X1769645Y205439D02*
X1769640Y205435D01*
G01X1769627Y202264D02*
X1769626Y202258D01*
G01X1769628Y202270D02*
X1769627Y202264D01*
G01X1769631Y202276D02*
X1769628Y202270D01*
G01X1769635Y202281D02*
X1769631Y202276D01*
G01X1769640Y202286D02*
X1769635Y202281D01*
G01X1769645Y202290D02*
X1769640Y202286D01*
G01X1769627Y199115D02*
X1769626Y199108D01*
G01X1769628Y199121D02*
X1769627Y199115D01*
G01X1769631Y199126D02*
X1769628Y199121D01*
G01X1769635Y199132D02*
X1769631Y199126D01*
G01X1769640Y199136D02*
X1769635Y199132D01*
G01X1769645Y199140D02*
X1769640Y199136D01*
G01X1784036Y194796D02*
X1784035Y194787D01*
G01X1784037Y194802D02*
X1784036Y194796D01*
G01X1784038Y194803D02*
X1784037Y194802D01*
G01X1784036Y189796D02*
X1784035Y189787D01*
G01X1784037Y189802D02*
X1784036Y189796D01*
G01X1784038Y189803D02*
X1784037Y189802D01*
G01X1784036Y184796D02*
X1784035Y184787D01*
G01X1784037Y184802D02*
X1784036Y184796D01*
G01X1784038Y184803D02*
X1784037Y184802D01*
G01X1784036Y179796D02*
X1784035Y179787D01*
G01X1784037Y179802D02*
X1784036Y179796D01*
G01X1784038Y179803D02*
X1784037Y179802D01*
G01X1784036Y174796D02*
X1784035Y174787D01*
G01X1784037Y174802D02*
X1784036Y174796D01*
G01X1784038Y174803D02*
X1784037Y174802D01*
G01X1784036Y169796D02*
X1784035Y169787D01*
G01X1784037Y169802D02*
X1784036Y169796D01*
G01X1784038Y169803D02*
X1784037Y169802D01*
G01X1784036Y164796D02*
X1784035Y164787D01*
G01X1784037Y164802D02*
X1784036Y164796D01*
G01X1784038Y164803D02*
X1784037Y164802D01*
G01X1784035Y166155D02*
X1784036Y166164D01*
G01X1784035Y171155D02*
X1784036Y171164D01*
G01X1784035Y176155D02*
X1784036Y176164D01*
G01X1784035Y181155D02*
X1784036Y181164D01*
G01X1784035Y186155D02*
X1784036Y186164D01*
G01X1784035Y191155D02*
X1784036Y191164D01*
G01X1784035Y196155D02*
X1784036Y196164D01*
G01X1788386Y194803D02*
Y196181D01*
G01Y189803D02*
Y191181D01*
G01Y184803D02*
Y186181D01*
G01Y179803D02*
Y181181D01*
G01Y174803D02*
Y176181D01*
G01Y169803D02*
Y171181D01*
G01Y164803D02*
Y166181D01*
G01X1770610Y199097D02*
Y199108D01*
G01Y202246D02*
Y202257D01*
G01Y205396D02*
Y205407D01*
G01Y208546D02*
Y208557D01*
G01Y211695D02*
Y211706D01*
G01X1785217Y166181D02*
Y164803D01*
G01Y171181D02*
Y169803D01*
G01Y176181D02*
Y174803D01*
G01Y181181D02*
Y179803D01*
G01Y186181D02*
Y184803D01*
G01Y191181D02*
Y189803D01*
G01Y196181D02*
Y194803D01*
G01X1784646Y219035D02*
Y196949D01*
G01X1784035Y171156D02*
Y171299D01*
G01Y166156D02*
Y166299D01*
G01Y181156D02*
Y181299D01*
G01Y176156D02*
Y176299D01*
G01Y191156D02*
Y191299D01*
G01Y186156D02*
Y186299D01*
G01Y196156D02*
Y196299D01*
G01Y194311D02*
Y196673D01*
G01Y189311D02*
Y191673D01*
G01Y184311D02*
Y186673D01*
G01Y179311D02*
Y181673D01*
G01Y174311D02*
Y176673D01*
G01Y169311D02*
Y171673D01*
G01Y164311D02*
Y166673D01*
G01X1783465Y217854D02*
Y198130D01*
G01X1783051Y166673D02*
Y164311D01*
G01Y171673D02*
Y169311D01*
G01Y176673D02*
Y174311D01*
G01Y181673D02*
Y179311D01*
G01Y186673D02*
Y184311D01*
G01Y191673D02*
Y189311D01*
G01Y196673D02*
Y194311D01*
G01X1770610Y210394D02*
Y211890D01*
G01Y207244D02*
Y208740D01*
G01Y204094D02*
Y205591D01*
G01Y200945D02*
Y202441D01*
G01Y197795D02*
Y199291D01*
G01X1770571Y197942D02*
Y197795D01*
G01Y201091D02*
Y200944D01*
G01Y202441D02*
Y202295D01*
G01Y199292D02*
Y199145D01*
G01Y207391D02*
Y207244D01*
G01Y204241D02*
Y204094D01*
G01Y205591D02*
Y205444D01*
G01Y210540D02*
Y210393D01*
G01Y211890D02*
Y211744D01*
G01Y208741D02*
Y208594D01*
G01X1769665Y210393D02*
Y210540D01*
G01Y211744D02*
Y211891D01*
G01Y208594D02*
Y208741D01*
G01Y207243D02*
Y207391D01*
G01Y204094D02*
Y204241D01*
G01Y205444D02*
Y205591D01*
G01Y200944D02*
Y201091D01*
G01Y202295D02*
Y202442D01*
G01Y199145D02*
Y199292D01*
G01Y197794D02*
Y197942D01*
G01X1769626Y202441D02*
Y200945D01*
G01Y199291D02*
Y197795D01*
G01Y205591D02*
Y204094D01*
G01Y211890D02*
Y210394D01*
G01Y208740D02*
Y207244D01*
G01X1768445Y199134D02*
Y197953D01*
G01Y202283D02*
Y201102D01*
G01Y208583D02*
Y207402D01*
G01Y205433D02*
Y204252D01*
G01Y211732D02*
Y210551D01*
G01X1768110Y220197D02*
Y195787D01*
G01X1767717D02*
Y220197D01*
G01X1770610Y210577D02*
Y210588D01*
G01Y207428D02*
Y207439D01*
G01Y204278D02*
Y204289D01*
G01Y201128D02*
Y201139D01*
G01Y197979D02*
Y197990D01*
G01X1783465Y198130D02*
X1784646Y196949D01*
G01X1779528Y198130D02*
X1780709Y196949D01*
G01X1769624Y207437D02*
X1769513Y207441D01*
G01X1769624Y201138D02*
X1769513Y201142D01*
G01X1769624Y210587D02*
X1769513Y210591D01*
G01X1770571Y211929D02*
X1769665D01*
G01X1770610Y211890D02*
X1769626D01*
G01X1768879Y210591D02*
X1768445D01*
G01X1769626Y210394D02*
X1770610D01*
G01X1769665Y210354D02*
X1770571D01*
G01Y208780D02*
X1769665D01*
G01X1770610Y208740D02*
X1769626D01*
G01X1768879Y207441D02*
X1768445D01*
G01X1769626Y207244D02*
X1770610D01*
G01X1769665Y207205D02*
X1770571D01*
G01Y205630D02*
X1769665D01*
G01X1770610Y205591D02*
X1769626D01*
G01Y204094D02*
X1770610D01*
G01X1769665Y204055D02*
X1770571D01*
G01Y202480D02*
X1769665D01*
G01X1770610Y202441D02*
X1769626D01*
G01X1768879Y201142D02*
X1768445D01*
G01X1769626Y200945D02*
X1770610D01*
G01X1769665Y200906D02*
X1770571D01*
G01Y199331D02*
X1769665D01*
G01X1770610Y199291D02*
X1769626D01*
G01X1783465Y198130D02*
X1779528D01*
G01X1769626Y197795D02*
X1770610D01*
G01X1769665Y197756D02*
X1770571D01*
G01X1784646Y196949D02*
X1780709D01*
G01X1784035Y196673D02*
X1783051D01*
G01X1783053Y196181D02*
X1788386D01*
G01Y196142D02*
X1784038D01*
G01X1771063Y195787D02*
X1767717D01*
G01X1788386Y194803D02*
X1783053D01*
G01X1783051Y194311D02*
X1784035D01*
G01Y191673D02*
X1783051D01*
G01X1783053Y191181D02*
X1788386D01*
G01Y191142D02*
X1784038D01*
G01X1788386Y189803D02*
X1783053D01*
G01X1783051Y189311D02*
X1784035D01*
G01Y186673D02*
X1783051D01*
G01X1783053Y186181D02*
X1788386D01*
G01Y186142D02*
X1784038D01*
G01X1788386Y184803D02*
X1783053D01*
G01X1783051Y184311D02*
X1784035D01*
G01Y181673D02*
X1783051D01*
G01X1783053Y181181D02*
X1788386D01*
G01Y181142D02*
X1784038D01*
G01X1788386Y179803D02*
X1783053D01*
G01X1783051Y179311D02*
X1784035D01*
G01Y176673D02*
X1783051D01*
G01X1783053Y176181D02*
X1788386D01*
G01Y176142D02*
X1784038D01*
G01X1788386Y174803D02*
X1783053D01*
G01X1783051Y174311D02*
X1784035D01*
G01Y171673D02*
X1783051D01*
G01X1783053Y171181D02*
X1788386D01*
G01Y171142D02*
X1784038D01*
G01X1788386Y169803D02*
X1783053D01*
G01X1783051Y169311D02*
X1784035D01*
G01X1783051Y196377D02*
X1784006Y196378D01*
G01X1784035Y194607D02*
X1783051Y194606D01*
G01Y191377D02*
X1784006Y191378D01*
G01X1784035Y189607D02*
X1783051Y189606D01*
G01Y186377D02*
X1784006Y186378D01*
G01X1784035Y184607D02*
X1783051Y184606D01*
G01Y181377D02*
X1784006Y181378D01*
G01X1784035Y179607D02*
X1783051Y179606D01*
G01Y176377D02*
X1784006Y176378D01*
G01X1784035Y174607D02*
X1783051Y174606D01*
G01Y171377D02*
X1784006Y171378D01*
G01X1784035Y169607D02*
X1783051Y169606D01*
G01X1784035Y166673D02*
X1783051D01*
G01X1783053Y166181D02*
X1788386D01*
G01Y166142D02*
X1784038D01*
G01X1788386Y164803D02*
X1783053D01*
G01X1783051Y164311D02*
X1784035D01*
G01X1783051Y166377D02*
X1784006Y166378D01*
G01X1784035Y164607D02*
X1783051Y164606D01*
G01X1769629Y214862D02*
X1769624Y214843D01*
G01X1769643Y214877D02*
X1769629Y214862D01*
G01X1769663Y214882D02*
X1769643Y214877D01*
G01X1769629Y218012D02*
X1769624Y217992D01*
G01X1769643Y218026D02*
X1769629Y218012D01*
G01X1769663Y218031D02*
X1769643Y218026D01*
G01X1770604Y213720D02*
X1770609Y213740D01*
G01X1770589Y213706D02*
X1770604Y213720D01*
G01X1770569Y213701D02*
X1770589Y213706D01*
G01X1770604Y216870D02*
X1770609Y216890D01*
G01X1770589Y216856D02*
X1770604Y216870D01*
G01X1770569Y216850D02*
X1770589Y216856D01*
G01X1770609Y213719D02*
X1770610Y213727D01*
G01X1770607Y213713D02*
X1770609Y213719D01*
G01X1770604Y213706D02*
X1770607Y213713D01*
G01X1770599Y213700D02*
X1770604Y213706D01*
G01X1770593Y213696D02*
X1770599Y213700D01*
G01X1770586Y213693D02*
X1770593Y213696D01*
G01X1770578Y213691D02*
X1770586Y213693D01*
G01X1770571Y213690D02*
X1770578Y213691D01*
G01X1769648Y214890D02*
X1769645Y214888D01*
G01X1769652Y214891D02*
X1769648Y214890D01*
G01X1769655Y214892D02*
X1769652Y214891D01*
G01X1769658Y214893D02*
X1769655Y214892D01*
G01X1769662Y214893D02*
X1769658D01*
G01X1769665D02*
X1769662D01*
G01X1770588Y216843D02*
X1770591Y216844D01*
G01X1770585Y216842D02*
X1770588Y216843D01*
G01X1770581Y216841D02*
X1770585Y216842D01*
G01X1770578Y216840D02*
X1770581Y216841D01*
G01X1770574Y216839D02*
X1770578Y216840D01*
G01X1770571Y216839D02*
X1770574D01*
G01X1769648Y218039D02*
X1769645Y218038D01*
G01X1769652Y218041D02*
X1769648Y218039D01*
G01X1769655Y218042D02*
X1769652Y218041D01*
G01X1769658Y218042D02*
X1769655D01*
G01X1769662Y218043D02*
X1769658Y218042D01*
G01X1769665Y218043D02*
X1769662D01*
G01X1770601Y214880D02*
X1770605Y214875D01*
G01X1770596Y214885D02*
X1770601Y214880D01*
G01X1770590Y214889D02*
X1770596Y214885D01*
G01X1770584Y214891D02*
X1770590Y214889D01*
G01X1770578Y214893D02*
X1770584Y214891D01*
G01X1770571Y214893D02*
X1770578D01*
G01X1770601Y218030D02*
X1770605Y218025D01*
G01X1770596Y218034D02*
X1770601Y218030D01*
G01X1770590Y218038D02*
X1770596Y218034D01*
G01X1770584Y218041D02*
X1770590Y218038D01*
G01X1770578Y218043D02*
X1770584Y218041D01*
G01X1770571Y218043D02*
X1770578D01*
G01X1769627Y213719D02*
X1769626Y213727D01*
G01X1769629Y213713D02*
X1769627Y213719D01*
G01X1769633Y213706D02*
X1769629Y213713D01*
G01X1769637Y213700D02*
X1769633Y213706D01*
G01X1769644Y213696D02*
X1769637Y213700D01*
G01X1769650Y213693D02*
X1769644Y213696D01*
G01X1769658Y213691D02*
X1769650Y213693D01*
G01X1769665Y213690D02*
X1769658Y213691D01*
G01X1769627Y216869D02*
X1769626Y216876D01*
G01X1769629Y216862D02*
X1769627Y216869D01*
G01X1769633Y216856D02*
X1769629Y216862D01*
G01X1769637Y216850D02*
X1769633Y216856D01*
G01X1769644Y216845D02*
X1769637Y216850D01*
G01X1769650Y216842D02*
X1769644Y216845D01*
G01X1769658Y216840D02*
X1769650Y216842D01*
G01X1769665Y216839D02*
X1769658Y216840D01*
G01X1770580Y214881D02*
X1770589Y214876D01*
G01X1770569Y214882D02*
X1770580Y214881D01*
G01Y218030D02*
X1770589Y218026D01*
G01X1770569Y218031D02*
X1770580Y218030D01*
G01X1769626Y213731D02*
Y213727D01*
G01X1769628Y213724D02*
X1769626Y213731D01*
G01X1769639Y213709D02*
X1769628Y213724D01*
G01X1769663Y213701D02*
X1769639Y213709D01*
G01X1769626Y216880D02*
Y216876D01*
G01X1769628Y216874D02*
X1769626Y216880D01*
G01X1769639Y216859D02*
X1769628Y216874D01*
G01X1769663Y216850D02*
X1769639Y216859D01*
G01X1784023Y221173D02*
X1784034Y221157D01*
G01X1783998Y221181D02*
X1784023Y221173D01*
G01Y226173D02*
X1784034Y226157D01*
G01X1783998Y226181D02*
X1784023Y226173D01*
G01Y231173D02*
X1784034Y231157D01*
G01X1783998Y231181D02*
X1784023Y231173D01*
G01Y236173D02*
X1784034Y236157D01*
G01X1783998Y236181D02*
X1784023Y236173D01*
G01Y241173D02*
X1784034Y241157D01*
G01X1783998Y241181D02*
X1784023Y241173D01*
G01Y246173D02*
X1784034Y246157D01*
G01X1783998Y246181D02*
X1784023Y246173D01*
G01Y251173D02*
X1784034Y251157D01*
G01X1783998Y251181D02*
X1784023Y251173D01*
G01Y256173D02*
X1784034Y256157D01*
G01X1783998Y256181D02*
X1784023Y256173D01*
G01X1770579Y214881D02*
X1770569Y214882D01*
G01X1770588Y214878D02*
X1770579Y214881D01*
G01X1770595Y214872D02*
X1770588Y214878D01*
G01X1770579Y218030D02*
X1770569Y218031D01*
G01X1770588Y218027D02*
X1770579Y218030D01*
G01X1770595Y218022D02*
X1770588Y218027D01*
G01X1769665Y213696D02*
Y213690D01*
G01X1769664Y213700D02*
X1769665Y213696D01*
G01X1769663Y213701D02*
X1769664Y213700D01*
G01X1769665Y216846D02*
Y216839D01*
G01X1769664Y216849D02*
X1769665Y216846D01*
G01X1769663Y216850D02*
X1769664Y216849D01*
G01X1784036Y221148D02*
X1784035Y221156D01*
G01X1784037Y221144D02*
X1784036Y221148D01*
G01X1784038Y221142D02*
X1784037Y221144D01*
G01X1784036Y226148D02*
X1784035Y226156D01*
G01X1784037Y226144D02*
X1784036Y226148D01*
G01X1784038Y226142D02*
X1784037Y226144D01*
G01X1784036Y231148D02*
X1784035Y231156D01*
G01X1784037Y231144D02*
X1784036Y231148D01*
G01X1784038Y231142D02*
X1784037Y231144D01*
G01X1784036Y236148D02*
X1784035Y236156D01*
G01X1784037Y236144D02*
X1784036Y236148D01*
G01X1784038Y236142D02*
X1784037Y236144D01*
G01X1784036Y241148D02*
X1784035Y241156D01*
G01X1784037Y241144D02*
X1784036Y241148D01*
G01X1784038Y241142D02*
X1784037Y241144D01*
G01X1784036Y246148D02*
X1784035Y246156D01*
G01X1784037Y246144D02*
X1784036Y246148D01*
G01X1784038Y246142D02*
X1784037Y246144D01*
G01X1784036Y251148D02*
X1784035Y251156D01*
G01X1784037Y251144D02*
X1784036Y251148D01*
G01X1784038Y251142D02*
X1784037Y251144D01*
G01X1784036Y256148D02*
X1784035Y256156D01*
G01X1784037Y256144D02*
X1784036Y256148D01*
G01X1784038Y256142D02*
X1784037Y256144D01*
G01X1769648Y213704D02*
X1769663Y213701D01*
G01X1769636Y213711D02*
X1769648Y213704D01*
G01X1769624Y213731D02*
X1769636Y213711D01*
G01X1770610Y213734D02*
Y213727D01*
G01X1770609Y213739D02*
X1770610Y213734D01*
G01X1770609Y213740D02*
Y213739D01*
G01X1770610Y216884D02*
Y216876D01*
G01X1770609Y216889D02*
X1770610Y216884D01*
G01X1770609Y216890D02*
Y216889D01*
G01X1769648Y216853D02*
X1769663Y216850D01*
G01X1769636Y216861D02*
X1769648Y216853D01*
G01X1769624Y216881D02*
X1769636Y216861D01*
G01X1770609Y214863D02*
X1770610Y214856D01*
G01X1770608Y214869D02*
X1770609Y214863D01*
G01X1770605Y214875D02*
X1770608Y214869D01*
G01X1770609Y218013D02*
X1770610Y218006D01*
G01X1770608Y218019D02*
X1770609Y218013D01*
G01X1770605Y218025D02*
X1770608Y218019D01*
G01X1770571Y216845D02*
X1770572Y216839D01*
G01X1770570Y216849D02*
X1770571Y216845D01*
G01X1770569Y216850D02*
X1770570Y216849D01*
G01X1783051Y221189D02*
Y221198D01*
G01X1783052Y221183D02*
X1783051Y221189D01*
G01X1783053Y221181D02*
X1783052Y221183D01*
G01X1783051Y226189D02*
Y226198D01*
G01X1783052Y226183D02*
X1783051Y226189D01*
G01X1783053Y226181D02*
X1783052Y226183D01*
G01X1783051Y231189D02*
Y231198D01*
G01X1783052Y231183D02*
X1783051Y231189D01*
G01X1783053Y231181D02*
X1783052Y231183D01*
G01X1783051Y236189D02*
Y236198D01*
G01X1783052Y236183D02*
X1783051Y236189D01*
G01X1783053Y236181D02*
X1783052Y236183D01*
G01X1783051Y241189D02*
Y241198D01*
G01X1783052Y241183D02*
X1783051Y241189D01*
G01X1783053Y241181D02*
X1783052Y241183D01*
G01X1783051Y246189D02*
Y246198D01*
G01X1783052Y246183D02*
X1783051Y246189D01*
G01X1783053Y246181D02*
X1783052Y246183D01*
G01X1783051Y251189D02*
Y251198D01*
G01X1783052Y251183D02*
X1783051Y251189D01*
G01X1783053Y251181D02*
X1783052Y251183D01*
G01X1783051Y256189D02*
Y256198D01*
G01X1783052Y256183D02*
X1783051Y256189D01*
G01X1783053Y256181D02*
X1783052Y256183D01*
G01X1784028Y221325D02*
X1784035Y221299D01*
G01X1784018Y221352D02*
X1784028Y221325D01*
G01X1784006Y221378D02*
X1784018Y221352D01*
G01X1784028Y226325D02*
X1784035Y226299D01*
G01X1784018Y226352D02*
X1784028Y226325D01*
G01X1784006Y226378D02*
X1784018Y226352D01*
G01X1784028Y231325D02*
X1784035Y231299D01*
G01X1784018Y231352D02*
X1784028Y231325D01*
G01X1784006Y231378D02*
X1784018Y231352D01*
G01X1784028Y236325D02*
X1784035Y236299D01*
G01X1784018Y236352D02*
X1784028Y236325D01*
G01X1784006Y236378D02*
X1784018Y236352D01*
G01X1784028Y241325D02*
X1784035Y241299D01*
G01X1784018Y241352D02*
X1784028Y241325D01*
G01X1784006Y241378D02*
X1784018Y241352D01*
G01X1784028Y246325D02*
X1784035Y246299D01*
G01X1784018Y246352D02*
X1784028Y246325D01*
G01X1784006Y246378D02*
X1784018Y246352D01*
G01X1784028Y251325D02*
X1784035Y251299D01*
G01X1784018Y251352D02*
X1784028Y251325D01*
G01X1784006Y251378D02*
X1784018Y251352D01*
G01X1784028Y256325D02*
X1784035Y256299D01*
G01X1784018Y256352D02*
X1784028Y256325D01*
G01X1784006Y256378D02*
X1784018Y256352D01*
G01Y221176D02*
X1783999Y221181D01*
G01X1784033Y221162D02*
X1784018Y221176D01*
G01X1784038Y221142D02*
X1784033Y221162D01*
G01X1784018Y226176D02*
X1783999Y226181D01*
G01X1784033Y226162D02*
X1784018Y226176D01*
G01X1784038Y226142D02*
X1784033Y226162D01*
G01X1784018Y231176D02*
X1783999Y231181D01*
G01X1784033Y231162D02*
X1784018Y231176D01*
G01X1784038Y231142D02*
X1784033Y231162D01*
G01X1784018Y236176D02*
X1783999Y236181D01*
G01X1784033Y236162D02*
X1784018Y236176D01*
G01X1784038Y236142D02*
X1784033Y236162D01*
G01X1784018Y241176D02*
X1783999Y241181D01*
G01X1784033Y241162D02*
X1784018Y241176D01*
G01X1784038Y241142D02*
X1784033Y241162D01*
G01X1784018Y246176D02*
X1783999Y246181D01*
G01X1784033Y246162D02*
X1784018Y246176D01*
G01X1784038Y246142D02*
X1784033Y246162D01*
G01X1784018Y251176D02*
X1783999Y251181D01*
G01X1784033Y251162D02*
X1784018Y251176D01*
G01X1784038Y251142D02*
X1784033Y251162D01*
G01X1784018Y256176D02*
X1783999Y256181D01*
G01X1784033Y256162D02*
X1784018Y256176D01*
G01X1784038Y256142D02*
X1784033Y256162D01*
G01X1770603Y214864D02*
X1770595Y214872D01*
G01X1770607Y214854D02*
X1770603Y214864D01*
G01X1770609Y214843D02*
X1770607Y214854D01*
G01X1770603Y218013D02*
X1770595Y218022D01*
G01X1770607Y218003D02*
X1770603Y218013D01*
G01X1770609Y217992D02*
X1770607Y218003D01*
G01X1784002Y221279D02*
X1784006Y221378D01*
G01X1783997Y221207D02*
X1784002Y221279D01*
G01X1783999Y221181D02*
X1783997Y221207D01*
G01X1784002Y226279D02*
X1784006Y226378D01*
G01X1783997Y226207D02*
X1784002Y226279D01*
G01X1783999Y226181D02*
X1783997Y226207D01*
G01X1784002Y231279D02*
X1784006Y231378D01*
G01X1783997Y231207D02*
X1784002Y231279D01*
G01X1783999Y231181D02*
X1783997Y231207D01*
G01X1784002Y236279D02*
X1784006Y236378D01*
G01X1783997Y236207D02*
X1784002Y236279D01*
G01X1783999Y236181D02*
X1783997Y236207D01*
G01X1784002Y241279D02*
X1784006Y241378D01*
G01X1783997Y241207D02*
X1784002Y241279D01*
G01X1783999Y241181D02*
X1783997Y241207D01*
G01X1784002Y246279D02*
X1784006Y246378D01*
G01X1783997Y246207D02*
X1784002Y246279D01*
G01X1783999Y246181D02*
X1783997Y246207D01*
G01X1784002Y251279D02*
X1784006Y251378D01*
G01X1783997Y251207D02*
X1784002Y251279D01*
G01X1783999Y251181D02*
X1783997Y251207D01*
G01X1784002Y256279D02*
X1784006Y256378D01*
G01X1783997Y256207D02*
X1784002Y256279D01*
G01X1783999Y256181D02*
X1783997Y256207D01*
G01X1769666Y218216D02*
X1769665Y218228D01*
G01X1769663Y218203D02*
X1769666Y218216D01*
G01X1769663Y218189D02*
Y218203D01*
G01X1769666Y215067D02*
X1769665Y215079D01*
G01X1769663Y215054D02*
X1769666Y215067D01*
G01X1769663Y215040D02*
Y215054D01*
G01X1769626Y216884D02*
Y216876D01*
G01X1769625Y216889D02*
X1769626Y216884D01*
G01X1769625Y216881D02*
Y216889D01*
G01X1769639Y218023D02*
X1769663Y218031D01*
G01X1769628Y218009D02*
X1769639Y218023D01*
G01X1769626Y218002D02*
X1769628Y218009D01*
G01X1769626Y218006D02*
Y218002D01*
G01X1769639Y214874D02*
X1769663Y214882D01*
G01X1769628Y214859D02*
X1769639Y214874D01*
G01X1769626Y214852D02*
X1769628Y214859D01*
G01X1769626Y214856D02*
Y214852D01*
G01X1783052Y259802D02*
X1783053Y259803D01*
G01X1783051Y259796D02*
X1783052Y259802D01*
G01X1783051Y259787D02*
Y259796D01*
G01X1783052Y254802D02*
X1783053Y254803D01*
G01X1783051Y254796D02*
X1783052Y254802D01*
G01X1783051Y254787D02*
Y254796D01*
G01X1783052Y249802D02*
X1783053Y249803D01*
G01X1783051Y249796D02*
X1783052Y249802D01*
G01X1783051Y249787D02*
Y249796D01*
G01X1783052Y244802D02*
X1783053Y244803D01*
G01X1783051Y244796D02*
X1783052Y244802D01*
G01X1783051Y244787D02*
Y244796D01*
G01X1783052Y239802D02*
X1783053Y239803D01*
G01X1783051Y239796D02*
X1783052Y239802D01*
G01X1783051Y239787D02*
Y239796D01*
G01X1783052Y234802D02*
X1783053Y234803D01*
G01X1783051Y234796D02*
X1783052Y234802D01*
G01X1783051Y234787D02*
Y234796D01*
G01X1783052Y229802D02*
X1783053Y229803D01*
G01X1783051Y229796D02*
X1783052Y229802D01*
G01X1783051Y229787D02*
Y229796D01*
G01X1783052Y224802D02*
X1783053Y224803D01*
G01X1783051Y224796D02*
X1783052Y224802D01*
G01X1783051Y224787D02*
Y224796D01*
G01X1783052Y219802D02*
X1783053Y219803D01*
G01X1783051Y219796D02*
X1783052Y219802D01*
G01X1783051Y219787D02*
Y219796D01*
G01X1769663Y216679D02*
X1769662Y216693D01*
G01X1769666Y216666D02*
X1769663Y216679D01*
G01X1769665Y216654D02*
X1769666Y216666D01*
G01X1769663Y213530D02*
X1769662Y213543D01*
G01X1769666Y213517D02*
X1769663Y213530D01*
G01X1769665Y213504D02*
X1769666Y213517D01*
G01X1770573Y218203D02*
X1770574Y218189D01*
G01X1770570Y218216D02*
X1770573Y218203D01*
G01X1770571Y218228D02*
X1770570Y218216D01*
G01X1770573Y215053D02*
X1770574Y215040D01*
G01X1770570Y215066D02*
X1770573Y215053D01*
G01X1770571Y215079D02*
X1770570Y215066D01*
G01X1769626Y213734D02*
Y213727D01*
G01X1769625Y213739D02*
X1769626Y213734D01*
G01X1769624Y213732D02*
X1769625Y213739D01*
G01X1770570Y216666D02*
X1770571Y216654D01*
G01X1770573Y216679D02*
X1770570Y216666D01*
G01X1770574Y216693D02*
X1770573Y216679D01*
G01X1770570Y213517D02*
X1770571Y213504D01*
G01X1770573Y213530D02*
X1770570Y213517D01*
G01X1770574Y213543D02*
X1770573Y213530D01*
G01X1770581Y216852D02*
X1770569Y216850D01*
G01X1770592Y216857D02*
X1770581Y216852D01*
G01Y213703D02*
X1770569Y213701D01*
G01X1770592Y213708D02*
X1770581Y213703D01*
G01X1770610Y217998D02*
Y218006D01*
G01Y217994D02*
Y217998D01*
G01X1770609Y217992D02*
X1770610Y217994D01*
G01Y214849D02*
Y214856D01*
G01Y214844D02*
Y214849D01*
G01X1770609Y214843D02*
X1770610Y214844D01*
G01X1770571Y218037D02*
Y218043D01*
G01X1770570Y218033D02*
X1770571Y218037D01*
G01X1770569Y218031D02*
X1770570Y218033D01*
G01X1770571Y214887D02*
Y214893D01*
G01X1770570Y214883D02*
X1770571Y214887D01*
G01X1770569Y214882D02*
X1770570Y214883D01*
G01X1784036Y259796D02*
X1784035Y259787D01*
G01X1784037Y259802D02*
X1784036Y259796D01*
G01X1784038Y259803D02*
X1784037Y259802D01*
G01X1784036Y254796D02*
X1784035Y254787D01*
G01X1784037Y254802D02*
X1784036Y254796D01*
G01X1784038Y254803D02*
X1784037Y254802D01*
G01X1784036Y249796D02*
X1784035Y249787D01*
G01X1784037Y249802D02*
X1784036Y249796D01*
G01X1784038Y249803D02*
X1784037Y249802D01*
G01X1784036Y244796D02*
X1784035Y244787D01*
G01X1784037Y244802D02*
X1784036Y244796D01*
G01X1784038Y244803D02*
X1784037Y244802D01*
G01X1784036Y239796D02*
X1784035Y239787D01*
G01X1784037Y239802D02*
X1784036Y239796D01*
G01X1784038Y239803D02*
X1784037Y239802D01*
G01X1784036Y234796D02*
X1784035Y234787D01*
G01X1784037Y234802D02*
X1784036Y234796D01*
G01X1784038Y234803D02*
X1784037Y234802D01*
G01X1784036Y229796D02*
X1784035Y229787D01*
G01X1784037Y229802D02*
X1784036Y229796D01*
G01X1784038Y229803D02*
X1784037Y229802D01*
G01X1784036Y224796D02*
X1784035Y224787D01*
G01X1784037Y224802D02*
X1784036Y224796D01*
G01X1784038Y224803D02*
X1784037Y224802D01*
G01X1784036Y219796D02*
X1784035Y219787D01*
G01X1784037Y219802D02*
X1784036Y219796D01*
G01X1784038Y219803D02*
X1784037Y219802D01*
G01X1769626Y217998D02*
Y218006D01*
G01X1769625Y217994D02*
X1769626Y217998D01*
G01X1769624Y217992D02*
X1769625Y217994D01*
G01X1769626Y214849D02*
Y214856D01*
G01X1769625Y214844D02*
X1769626Y214849D01*
G01X1769624Y214843D02*
X1769625Y214844D01*
G01X1770608Y216864D02*
X1770610Y216876D01*
G01X1770601Y216853D02*
X1770608Y216864D01*
G01X1770591Y216844D02*
X1770601Y216853D01*
G01X1769665Y218037D02*
Y218043D01*
G01Y218033D02*
Y218037D01*
G01X1769663Y218031D02*
X1769665Y218033D01*
G01Y214887D02*
Y214893D01*
G01Y214883D02*
Y214887D01*
G01X1769663Y214882D02*
X1769665Y214883D01*
G01X1769627Y218012D02*
X1769626Y218006D01*
G01X1769628Y218019D02*
X1769627Y218012D01*
G01X1769631Y218024D02*
X1769628Y218019D01*
G01X1769635Y218030D02*
X1769631Y218024D01*
G01X1769640Y218034D02*
X1769635Y218030D01*
G01X1769645Y218038D02*
X1769640Y218034D01*
G01X1769627Y214863D02*
X1769626Y214856D01*
G01X1769628Y214869D02*
X1769627Y214863D01*
G01X1769631Y214874D02*
X1769628Y214869D01*
G01X1769635Y214880D02*
X1769631Y214874D01*
G01X1769640Y214884D02*
X1769635Y214880D01*
G01X1769645Y214888D02*
X1769640Y214884D01*
G01X1783465Y217854D02*
X1784646Y219035D01*
G01X1779528Y217854D02*
X1780709Y219035D01*
G01X1784035Y221155D02*
X1784036Y221164D01*
G01X1784035Y226155D02*
X1784036Y226164D01*
G01X1784035Y231155D02*
X1784036Y231164D01*
G01X1784035Y236155D02*
X1784036Y236164D01*
G01X1784035Y241155D02*
X1784036Y241164D01*
G01X1784035Y246155D02*
X1784036Y246164D01*
G01X1784035Y251155D02*
X1784036Y251164D01*
G01X1784035Y256155D02*
X1784036Y256164D01*
G01X1788386Y259803D02*
Y261181D01*
G01Y254803D02*
Y256181D01*
G01Y249803D02*
Y251181D01*
G01Y244803D02*
Y246181D01*
G01Y239803D02*
Y241181D01*
G01Y234803D02*
Y236181D01*
G01Y229803D02*
Y231181D01*
G01Y224803D02*
Y226181D01*
G01Y219803D02*
Y221181D01*
G01X1770610Y214845D02*
Y214856D01*
G01Y217994D02*
Y218006D01*
G01X1785217Y221181D02*
Y219803D01*
G01Y226181D02*
Y224803D01*
G01Y231181D02*
Y229803D01*
G01Y236181D02*
Y234803D01*
G01Y241181D02*
Y239803D01*
G01Y246181D02*
Y244803D01*
G01Y251181D02*
Y249803D01*
G01Y256181D02*
Y254803D01*
G01Y261181D02*
Y259803D01*
G01X1784035Y221156D02*
Y221299D01*
G01Y231156D02*
Y231299D01*
G01Y226156D02*
Y226299D01*
G01Y241156D02*
Y241299D01*
G01Y236156D02*
Y236299D01*
G01Y251156D02*
Y251299D01*
G01Y246156D02*
Y246299D01*
G01Y256156D02*
Y256299D01*
G01Y259311D02*
Y261673D01*
G01Y254311D02*
Y256673D01*
G01Y249311D02*
Y251673D01*
G01Y244311D02*
Y246673D01*
G01Y239311D02*
Y241673D01*
G01Y234311D02*
Y236673D01*
G01Y229311D02*
Y231673D01*
G01Y224311D02*
Y226673D01*
G01Y219311D02*
Y221673D01*
G01X1783051D02*
Y219311D01*
G01Y226673D02*
Y224311D01*
G01Y231673D02*
Y229311D01*
G01Y236673D02*
Y234311D01*
G01Y241673D02*
Y239311D01*
G01Y246673D02*
Y244311D01*
G01Y251673D02*
Y249311D01*
G01Y256673D02*
Y254311D01*
G01Y261673D02*
Y259311D01*
G01X1780709Y295492D02*
Y219035D01*
G01X1779528Y294311D02*
Y217854D01*
G01X1771063Y299232D02*
Y220197D01*
G01X1770610Y216693D02*
Y218189D01*
G01Y213543D02*
Y215039D01*
G01X1770571Y216839D02*
Y216693D01*
G01Y213690D02*
Y213543D01*
G01Y215040D02*
Y214893D01*
G01Y218189D02*
Y218043D01*
G01X1769665D02*
Y218190D01*
G01Y216692D02*
Y216839D01*
G01Y213543D02*
Y213690D01*
G01Y214893D02*
Y215040D01*
G01X1769626Y215039D02*
Y213543D01*
G01Y218189D02*
Y216693D01*
G01X1768445Y218031D02*
Y216850D01*
G01Y214882D02*
Y213701D01*
G01X1770610Y216876D02*
Y216887D01*
G01Y213727D02*
Y213738D01*
G01X1770569Y213701D02*
X1770573Y213690D01*
G01X1769513Y216890D02*
X1769624Y216881D01*
G01X1788386Y259803D02*
X1783053D01*
G01X1783051Y259311D02*
X1784035D01*
G01Y256673D02*
X1783051D01*
G01X1784035Y259607D02*
X1783051Y259606D01*
G01X1783053Y256181D02*
X1788386D01*
G01Y256142D02*
X1784038D01*
G01X1788386Y254803D02*
X1783053D01*
G01X1783051Y254311D02*
X1784035D01*
G01Y251673D02*
X1783051D01*
G01X1783053Y251181D02*
X1788386D01*
G01Y251142D02*
X1784038D01*
G01X1788386Y249803D02*
X1783053D01*
G01X1783051Y249311D02*
X1784035D01*
G01Y246673D02*
X1783051D01*
G01X1783053Y246181D02*
X1788386D01*
G01Y246142D02*
X1784038D01*
G01X1788386Y244803D02*
X1783053D01*
G01X1783051Y244311D02*
X1784035D01*
G01Y241673D02*
X1783051D01*
G01X1783053Y241181D02*
X1788386D01*
G01Y241142D02*
X1784038D01*
G01X1788386Y239803D02*
X1783053D01*
G01X1783051Y239311D02*
X1784035D01*
G01Y236673D02*
X1783051D01*
G01X1783053Y236181D02*
X1788386D01*
G01Y236142D02*
X1784038D01*
G01X1788386Y234803D02*
X1783053D01*
G01X1783051Y234311D02*
X1784035D01*
G01Y231673D02*
X1783051D01*
G01X1783053Y231181D02*
X1788386D01*
G01Y231142D02*
X1784038D01*
G01X1788386Y229803D02*
X1783053D01*
G01X1783051Y229311D02*
X1784035D01*
G01Y226673D02*
X1783051D01*
G01X1783053Y226181D02*
X1788386D01*
G01Y226142D02*
X1784038D01*
G01X1788386Y224803D02*
X1783053D01*
G01X1783051Y224311D02*
X1784035D01*
G01Y221673D02*
X1783051D01*
G01X1783053Y221181D02*
X1788386D01*
G01Y221142D02*
X1784038D01*
G01X1771063Y220197D02*
X1767717D01*
G01X1788386Y219803D02*
X1783053D01*
G01X1783051Y219311D02*
X1784035D01*
G01X1780709Y219035D02*
X1784646D01*
G01X1770571Y218228D02*
X1769665D01*
G01X1770610Y218189D02*
X1769626D01*
G01X1779528Y217854D02*
X1783465D01*
G01X1769626Y216693D02*
X1770610D01*
G01X1769665Y216654D02*
X1770571D01*
G01Y215079D02*
X1769665D01*
G01X1770610Y215039D02*
X1769626D01*
G01Y213543D02*
X1770610D01*
G01X1769665Y213504D02*
X1770571D01*
G01X1783051Y256377D02*
X1784006Y256378D01*
G01X1784035Y254607D02*
X1783051Y254606D01*
G01Y251377D02*
X1784006Y251378D01*
G01X1784035Y249607D02*
X1783051Y249606D01*
G01Y246377D02*
X1784006Y246378D01*
G01X1784035Y244607D02*
X1783051Y244606D01*
G01Y241377D02*
X1784006Y241378D01*
G01X1784035Y239607D02*
X1783051Y239606D01*
G01Y236377D02*
X1784006Y236378D01*
G01X1784035Y234607D02*
X1783051Y234606D01*
G01Y231377D02*
X1784006Y231378D01*
G01X1784035Y229607D02*
X1783051Y229606D01*
G01Y226377D02*
X1784006Y226378D01*
G01X1784035Y224607D02*
X1783051Y224606D01*
G01Y221377D02*
X1784006Y221378D01*
G01X1784035Y219607D02*
X1783051Y219606D01*
G01X1784023Y261173D02*
X1784034Y261157D01*
G01X1783998Y261181D02*
X1784023Y261173D01*
G01Y266173D02*
X1784034Y266157D01*
G01X1783998Y266181D02*
X1784023Y266173D01*
G01Y271173D02*
X1784034Y271157D01*
G01X1783998Y271181D02*
X1784023Y271173D01*
G01Y276173D02*
X1784034Y276157D01*
G01X1783998Y276181D02*
X1784023Y276173D01*
G01Y281173D02*
X1784034Y281157D01*
G01X1783998Y281181D02*
X1784023Y281173D01*
G01Y286173D02*
X1784034Y286157D01*
G01X1783998Y286181D02*
X1784023Y286173D01*
G01Y291173D02*
X1784034Y291157D01*
G01X1783998Y291181D02*
X1784023Y291173D01*
G01X1784036Y261148D02*
X1784035Y261156D01*
G01X1784037Y261144D02*
X1784036Y261148D01*
G01X1784038Y261142D02*
X1784037Y261144D01*
G01X1784036Y266148D02*
X1784035Y266156D01*
G01X1784037Y266144D02*
X1784036Y266148D01*
G01X1784038Y266142D02*
X1784037Y266144D01*
G01X1784036Y271148D02*
X1784035Y271156D01*
G01X1784037Y271144D02*
X1784036Y271148D01*
G01X1784038Y271142D02*
X1784037Y271144D01*
G01X1784036Y276148D02*
X1784035Y276156D01*
G01X1784037Y276144D02*
X1784036Y276148D01*
G01X1784038Y276142D02*
X1784037Y276144D01*
G01X1784036Y281148D02*
X1784035Y281156D01*
G01X1784037Y281144D02*
X1784036Y281148D01*
G01X1784038Y281142D02*
X1784037Y281144D01*
G01X1784036Y286148D02*
X1784035Y286156D01*
G01X1784037Y286144D02*
X1784036Y286148D01*
G01X1784038Y286142D02*
X1784037Y286144D01*
G01X1784036Y291148D02*
X1784035Y291156D01*
G01X1784037Y291144D02*
X1784036Y291148D01*
G01X1784038Y291142D02*
X1784037Y291144D01*
G01X1783051Y261189D02*
Y261198D01*
G01X1783052Y261183D02*
X1783051Y261189D01*
G01X1783053Y261181D02*
X1783052Y261183D01*
G01X1783051Y266189D02*
Y266198D01*
G01X1783052Y266183D02*
X1783051Y266189D01*
G01X1783053Y266181D02*
X1783052Y266183D01*
G01X1783051Y271189D02*
Y271198D01*
G01X1783052Y271183D02*
X1783051Y271189D01*
G01X1783053Y271181D02*
X1783052Y271183D01*
G01X1783051Y276189D02*
Y276198D01*
G01X1783052Y276183D02*
X1783051Y276189D01*
G01X1783053Y276181D02*
X1783052Y276183D01*
G01X1783051Y281189D02*
Y281198D01*
G01X1783052Y281183D02*
X1783051Y281189D01*
G01X1783053Y281181D02*
X1783052Y281183D01*
G01X1783051Y286189D02*
Y286198D01*
G01X1783052Y286183D02*
X1783051Y286189D01*
G01X1783053Y286181D02*
X1783052Y286183D01*
G01X1783051Y291189D02*
Y291198D01*
G01X1783052Y291183D02*
X1783051Y291189D01*
G01X1783053Y291181D02*
X1783052Y291183D01*
G01X1784028Y261325D02*
X1784035Y261299D01*
G01X1784018Y261352D02*
X1784028Y261325D01*
G01X1784006Y261378D02*
X1784018Y261352D01*
G01X1784028Y266325D02*
X1784035Y266299D01*
G01X1784018Y266352D02*
X1784028Y266325D01*
G01X1784006Y266378D02*
X1784018Y266352D01*
G01X1784028Y271325D02*
X1784035Y271299D01*
G01X1784018Y271352D02*
X1784028Y271325D01*
G01X1784006Y271378D02*
X1784018Y271352D01*
G01X1784028Y276325D02*
X1784035Y276299D01*
G01X1784018Y276352D02*
X1784028Y276325D01*
G01X1784006Y276378D02*
X1784018Y276352D01*
G01X1784028Y281325D02*
X1784035Y281299D01*
G01X1784018Y281352D02*
X1784028Y281325D01*
G01X1784006Y281378D02*
X1784018Y281352D01*
G01X1784028Y286325D02*
X1784035Y286299D01*
G01X1784018Y286352D02*
X1784028Y286325D01*
G01X1784006Y286378D02*
X1784018Y286352D01*
G01X1784028Y291325D02*
X1784035Y291299D01*
G01X1784018Y291352D02*
X1784028Y291325D01*
G01X1784006Y291378D02*
X1784018Y291352D01*
G01Y261176D02*
X1783999Y261181D01*
G01X1784033Y261162D02*
X1784018Y261176D01*
G01X1784038Y261142D02*
X1784033Y261162D01*
G01X1784018Y266176D02*
X1783999Y266181D01*
G01X1784033Y266162D02*
X1784018Y266176D01*
G01X1784038Y266142D02*
X1784033Y266162D01*
G01X1784018Y271176D02*
X1783999Y271181D01*
G01X1784033Y271162D02*
X1784018Y271176D01*
G01X1784038Y271142D02*
X1784033Y271162D01*
G01X1784018Y276176D02*
X1783999Y276181D01*
G01X1784033Y276162D02*
X1784018Y276176D01*
G01X1784038Y276142D02*
X1784033Y276162D01*
G01X1784018Y281176D02*
X1783999Y281181D01*
G01X1784033Y281162D02*
X1784018Y281176D01*
G01X1784038Y281142D02*
X1784033Y281162D01*
G01X1784018Y286176D02*
X1783999Y286181D01*
G01X1784033Y286162D02*
X1784018Y286176D01*
G01X1784038Y286142D02*
X1784033Y286162D01*
G01X1784018Y291176D02*
X1783999Y291181D01*
G01X1784033Y291162D02*
X1784018Y291176D01*
G01X1784038Y291142D02*
X1784033Y291162D01*
G01X1784002Y261279D02*
X1784006Y261378D01*
G01X1783997Y261207D02*
X1784002Y261279D01*
G01X1783999Y261181D02*
X1783997Y261207D01*
G01X1784002Y266279D02*
X1784006Y266378D01*
G01X1783997Y266207D02*
X1784002Y266279D01*
G01X1783999Y266181D02*
X1783997Y266207D01*
G01X1784002Y271279D02*
X1784006Y271378D01*
G01X1783997Y271207D02*
X1784002Y271279D01*
G01X1783999Y271181D02*
X1783997Y271207D01*
G01X1784002Y276279D02*
X1784006Y276378D01*
G01X1783997Y276207D02*
X1784002Y276279D01*
G01X1783999Y276181D02*
X1783997Y276207D01*
G01X1784002Y281279D02*
X1784006Y281378D01*
G01X1783997Y281207D02*
X1784002Y281279D01*
G01X1783999Y281181D02*
X1783997Y281207D01*
G01X1784002Y286279D02*
X1784006Y286378D01*
G01X1783997Y286207D02*
X1784002Y286279D01*
G01X1783999Y286181D02*
X1783997Y286207D01*
G01X1784002Y291279D02*
X1784006Y291378D01*
G01X1783997Y291207D02*
X1784002Y291279D01*
G01X1783999Y291181D02*
X1783997Y291207D01*
G01X1783052Y289802D02*
X1783053Y289803D01*
G01X1783051Y289796D02*
X1783052Y289802D01*
G01X1783051Y289787D02*
Y289796D01*
G01X1783052Y284802D02*
X1783053Y284803D01*
G01X1783051Y284796D02*
X1783052Y284802D01*
G01X1783051Y284787D02*
Y284796D01*
G01X1783052Y279802D02*
X1783053Y279803D01*
G01X1783051Y279796D02*
X1783052Y279802D01*
G01X1783051Y279787D02*
Y279796D01*
G01X1783052Y274802D02*
X1783053Y274803D01*
G01X1783051Y274796D02*
X1783052Y274802D01*
G01X1783051Y274787D02*
Y274796D01*
G01X1783052Y269802D02*
X1783053Y269803D01*
G01X1783051Y269796D02*
X1783052Y269802D01*
G01X1783051Y269787D02*
Y269796D01*
G01X1783052Y264802D02*
X1783053Y264803D01*
G01X1783051Y264796D02*
X1783052Y264802D01*
G01X1783051Y264787D02*
Y264796D01*
G01X1784036Y289796D02*
X1784035Y289787D01*
G01X1784037Y289802D02*
X1784036Y289796D01*
G01X1784038Y289803D02*
X1784037Y289802D01*
G01X1784036Y284796D02*
X1784035Y284787D01*
G01X1784037Y284802D02*
X1784036Y284796D01*
G01X1784038Y284803D02*
X1784037Y284802D01*
G01X1784036Y279796D02*
X1784035Y279787D01*
G01X1784037Y279802D02*
X1784036Y279796D01*
G01X1784038Y279803D02*
X1784037Y279802D01*
G01X1784036Y274796D02*
X1784035Y274787D01*
G01X1784037Y274802D02*
X1784036Y274796D01*
G01X1784038Y274803D02*
X1784037Y274802D01*
G01X1784036Y269796D02*
X1784035Y269787D01*
G01X1784037Y269802D02*
X1784036Y269796D01*
G01X1784038Y269803D02*
X1784037Y269802D01*
G01X1784036Y264796D02*
X1784035Y264787D01*
G01X1784037Y264802D02*
X1784036Y264796D01*
G01X1784038Y264803D02*
X1784037Y264802D01*
G01X1775984Y307579D02*
G03X1774803Y306398I0J-1181D01*
G01X1782283D02*
G03X1781102Y307579I-1181J0D01*
G01X1780433Y302303D02*
G03I-1890J0D01*
G01X1780906D02*
G03I-2363J0D01*
G01X1789370Y300335D02*
X1786024Y296988D01*
G01X1779528Y294311D02*
X1780709Y295492D01*
G01X1776059Y299232D02*
X1777362Y301201D01*
G01X1782035Y307123D02*
X1779724Y302894D01*
G01X1784035Y261155D02*
X1784036Y261164D01*
G01X1784035Y266155D02*
X1784036Y266164D01*
G01X1784035Y271155D02*
X1784036Y271164D01*
G01X1784035Y276155D02*
X1784036Y276164D01*
G01X1784035Y281155D02*
X1784036Y281164D01*
G01X1784035Y286155D02*
X1784036Y286164D01*
G01X1784035Y291155D02*
X1784036Y291164D01*
G01X1789370Y300335D02*
Y316083D01*
G01X1788386Y289803D02*
Y291181D01*
G01Y284803D02*
Y286181D01*
G01Y279803D02*
Y281181D01*
G01Y274803D02*
Y276181D01*
G01Y269803D02*
Y271181D01*
G01Y264803D02*
Y266181D01*
G01X1785217D02*
Y264803D01*
G01Y271181D02*
Y269803D01*
G01Y276181D02*
Y274803D01*
G01Y281181D02*
Y279803D01*
G01Y286181D02*
Y284803D01*
G01Y291181D02*
Y289803D01*
G01X1784035Y261156D02*
Y261299D01*
G01Y271156D02*
Y271299D01*
G01Y266156D02*
Y266299D01*
G01Y281156D02*
Y281299D01*
G01Y276156D02*
Y276299D01*
G01Y291156D02*
Y291299D01*
G01Y286156D02*
Y286299D01*
G01Y289311D02*
Y291673D01*
G01Y284311D02*
Y286673D01*
G01Y279311D02*
Y281673D01*
G01Y274311D02*
Y276673D01*
G01Y269311D02*
Y271673D01*
G01Y264311D02*
Y266673D01*
G01X1783051D02*
Y264311D01*
G01Y271673D02*
Y269311D01*
G01Y276673D02*
Y274311D01*
G01Y281673D02*
Y279311D01*
G01Y286673D02*
Y284311D01*
G01Y291673D02*
Y289311D01*
G01X1782283Y306398D02*
Y297854D01*
G01X1779724Y302894D02*
Y301201D01*
G01X1777362D02*
Y302894D01*
G01X1774803Y297854D02*
Y306398D01*
G01X1767717Y316083D02*
Y300335D01*
G01X1777362Y302894D02*
X1775052Y307123D01*
G01X1779724Y301201D02*
X1781028Y299232D01*
G01X1772835Y295492D02*
X1774016Y294311D01*
G01X1767717Y300335D02*
X1771063Y296988D01*
G01X1789370Y307618D02*
X1767717D01*
G01X1775984Y307579D02*
X1781102D01*
G01X1777362Y302894D02*
X1779724D01*
G01X1777362Y301201D02*
X1779724D01*
G01X1771063Y299232D02*
X1785433D01*
G01X1771063Y297854D02*
X1774803D01*
G01X1785433D02*
X1782283D01*
G01X1771063Y296988D02*
X1786024D01*
G01X1772835Y295492D02*
X1780709D01*
G01X1774016Y294311D02*
X1779528D01*
G01X1784035Y291673D02*
X1783051D01*
G01X1783053Y291181D02*
X1788386D01*
G01Y291142D02*
X1784038D01*
G01X1788386Y289803D02*
X1783053D01*
G01X1783051Y289311D02*
X1784035D01*
G01Y286673D02*
X1783051D01*
G01X1783053Y286181D02*
X1788386D01*
G01Y286142D02*
X1784038D01*
G01X1788386Y284803D02*
X1783053D01*
G01X1783051Y284311D02*
X1784035D01*
G01Y281673D02*
X1783051D01*
G01X1783053Y281181D02*
X1788386D01*
G01Y281142D02*
X1784038D01*
G01X1788386Y279803D02*
X1783053D01*
G01X1783051Y279311D02*
X1784035D01*
G01Y276673D02*
X1783051D01*
G01X1783053Y276181D02*
X1788386D01*
G01Y276142D02*
X1784038D01*
G01X1788386Y274803D02*
X1783053D01*
G01X1783051Y274311D02*
X1784035D01*
G01Y271673D02*
X1783051D01*
G01X1783053Y271181D02*
X1788386D01*
G01Y271142D02*
X1784038D01*
G01X1788386Y269803D02*
X1783053D01*
G01X1783051Y269311D02*
X1784035D01*
G01Y266673D02*
X1783051D01*
G01X1783053Y266181D02*
X1788386D01*
G01Y266142D02*
X1784038D01*
G01X1788386Y264803D02*
X1783053D01*
G01X1783051Y264311D02*
X1784035D01*
G01Y261673D02*
X1783051D01*
G01X1783053Y261181D02*
X1788386D01*
G01Y261142D02*
X1784038D01*
G01X1783051Y291377D02*
X1784006Y291378D01*
G01X1784035Y289607D02*
X1783051Y289606D01*
G01Y286377D02*
X1784006Y286378D01*
G01X1784035Y284607D02*
X1783051Y284606D01*
G01Y281377D02*
X1784006Y281378D01*
G01X1784035Y279607D02*
X1783051Y279606D01*
G01Y276377D02*
X1784006Y276378D01*
G01X1784035Y274607D02*
X1783051Y274606D01*
G01Y271377D02*
X1784006Y271378D01*
G01X1784035Y269607D02*
X1783051Y269606D01*
G01Y266377D02*
X1784006Y266378D01*
G01X1784035Y264607D02*
X1783051Y264606D01*
G01Y261377D02*
X1784006Y261378D01*
G01X1781028Y378885D02*
G03X1814838I16905J-13531D01*
G01X1782480Y316673D02*
G03X1781890Y317264I-590J1D01*
G01X1775197D02*
G03X1774606Y316673I0J-591D01*
G01X1777362Y315492D02*
G03Y313524I0J-984D01*
G01X1779724D02*
G03Y315492I0J984D01*
G01X1789370Y316083D02*
G03X1787402Y318051I-1968J0D01*
G01X1769685D02*
G03X1767717Y316083I0J-1968D01*
G01X1781028Y378885D02*
G03X1814839I16906J-13531D01*
G01X1782480Y310571D02*
Y316673D01*
G01X1774606Y310571D02*
Y316673D01*
G01X1787402Y318051D02*
X1769685D01*
G01X1781890Y317264D02*
X1775197D01*
G01X1779724Y315492D02*
X1777362D01*
G01Y313524D02*
X1779724D01*
G01X1782480Y312146D02*
X1774606D01*
G01Y310571D02*
X1782480D01*
G01X1807914Y392016D02*
G03X1814838Y378885I37663J11469D01*
G01X1807914Y392016D02*
G03X1787953I-9980J-3039D01*
G01X1781028Y378885D02*
G03X1787953Y392016I-30737J24602D01*
G01X1807913D02*
G03X1814839Y378885I37662J11473D01*
G01X1781028D02*
G03X1787953Y392016I-30737J24602D01*
G01X1807913D02*
G03X1787953I-9980J-3040D01*
G01X1774606Y592067D02*
G03X1775197Y591476I591J0D01*
G01X1781890D02*
G03X1782480Y592067I-1J591D01*
G01X1779724Y593248D02*
G03Y595217I0J985D01*
G01X1777362D02*
G03Y593248I0J-985D01*
G01X1767717Y592657D02*
G03X1769685Y590689I1968J0D01*
G01X1787402D02*
G03X1789370Y592657I-1J1969D01*
G01D02*
Y608406D01*
G01X1782480Y598169D02*
Y592067D01*
G01X1774606Y598169D02*
Y592067D01*
G01X1767717Y608406D02*
Y592657D01*
G01X1782480Y598169D02*
X1774606D01*
G01Y596594D02*
X1782480D01*
G01X1779724Y595217D02*
X1777362D01*
G01Y593248D02*
X1779724D01*
G01X1781890Y591476D02*
X1775197D01*
G01X1787402Y590689D02*
X1769685D01*
G01X1784023Y618929D02*
X1784034Y618913D01*
G01X1783998Y618937D02*
X1784023Y618929D01*
G01Y623929D02*
X1784034Y623913D01*
G01X1783998Y623937D02*
X1784023Y623929D01*
G01Y628929D02*
X1784034Y628913D01*
G01X1783998Y628937D02*
X1784023Y628929D01*
G01Y633929D02*
X1784034Y633913D01*
G01X1783998Y633937D02*
X1784023Y633929D01*
G01Y638929D02*
X1784034Y638913D01*
G01X1783998Y638937D02*
X1784023Y638929D01*
G01Y643929D02*
X1784034Y643913D01*
G01X1783998Y643937D02*
X1784023Y643929D01*
G01X1784036Y618904D02*
X1784035Y618911D01*
G01X1784037Y618900D02*
X1784036Y618904D01*
G01X1784038Y618898D02*
X1784037Y618900D01*
G01X1784036Y623904D02*
X1784035Y623911D01*
G01X1784037Y623900D02*
X1784036Y623904D01*
G01X1784038Y623898D02*
X1784037Y623900D01*
G01X1784036Y628904D02*
X1784035Y628911D01*
G01X1784037Y628900D02*
X1784036Y628904D01*
G01X1784038Y628898D02*
X1784037Y628900D01*
G01X1784036Y633904D02*
X1784035Y633911D01*
G01X1784037Y633900D02*
X1784036Y633904D01*
G01X1784038Y633898D02*
X1784037Y633900D01*
G01X1784036Y638904D02*
X1784035Y638911D01*
G01X1784037Y638900D02*
X1784036Y638904D01*
G01X1784038Y638898D02*
X1784037Y638900D01*
G01X1784036Y643904D02*
X1784035Y643911D01*
G01X1784037Y643900D02*
X1784036Y643904D01*
G01X1784038Y643898D02*
X1784037Y643900D01*
G01X1784036Y647552D02*
X1784035Y647543D01*
G01X1784037Y647557D02*
X1784036Y647552D01*
G01X1784038Y647559D02*
X1784037Y647557D01*
G01X1784036Y642552D02*
X1784035Y642543D01*
G01X1784037Y642557D02*
X1784036Y642552D01*
G01X1784038Y642559D02*
X1784037Y642557D01*
G01X1784036Y637552D02*
X1784035Y637543D01*
G01X1784037Y637557D02*
X1784036Y637552D01*
G01X1784038Y637559D02*
X1784037Y637557D01*
G01X1783051Y618944D02*
Y618954D01*
G01X1783052Y618939D02*
X1783051Y618944D01*
G01X1783053Y618937D02*
X1783052Y618939D01*
G01X1783051Y623944D02*
Y623954D01*
G01X1783052Y623939D02*
X1783051Y623944D01*
G01X1783053Y623937D02*
X1783052Y623939D01*
G01X1783051Y628944D02*
Y628954D01*
G01X1783052Y628939D02*
X1783051Y628944D01*
G01X1783053Y628937D02*
X1783052Y628939D01*
G01X1783051Y633944D02*
Y633954D01*
G01X1783052Y633939D02*
X1783051Y633944D01*
G01X1783053Y633937D02*
X1783052Y633939D01*
G01X1783051Y638944D02*
Y638954D01*
G01X1783052Y638939D02*
X1783051Y638944D01*
G01X1783053Y638937D02*
X1783052Y638939D01*
G01X1783051Y643944D02*
Y643954D01*
G01X1783052Y643939D02*
X1783051Y643944D01*
G01X1783053Y643937D02*
X1783052Y643939D01*
G01X1784028Y619081D02*
X1784035Y619055D01*
G01X1784018Y619107D02*
X1784028Y619081D01*
G01X1784006Y619134D02*
X1784018Y619107D01*
G01X1784028Y624081D02*
X1784035Y624055D01*
G01X1784018Y624107D02*
X1784028Y624081D01*
G01X1784006Y624134D02*
X1784018Y624107D01*
G01X1784028Y629081D02*
X1784035Y629055D01*
G01X1784018Y629107D02*
X1784028Y629081D01*
G01X1784006Y629134D02*
X1784018Y629107D01*
G01X1784028Y634081D02*
X1784035Y634055D01*
G01X1784018Y634107D02*
X1784028Y634081D01*
G01X1784006Y634134D02*
X1784018Y634107D01*
G01X1784028Y639081D02*
X1784035Y639055D01*
G01X1784018Y639107D02*
X1784028Y639081D01*
G01X1784006Y639134D02*
X1784018Y639107D01*
G01X1784028Y644081D02*
X1784035Y644055D01*
G01X1784018Y644107D02*
X1784028Y644081D01*
G01X1784006Y644134D02*
X1784018Y644107D01*
G01X1784002Y619035D02*
X1784006Y619134D01*
G01X1783997Y618963D02*
X1784002Y619035D01*
G01X1783999Y618937D02*
X1783997Y618963D01*
G01X1784002Y624035D02*
X1784006Y624134D01*
G01X1783997Y623963D02*
X1784002Y624035D01*
G01X1783999Y623937D02*
X1783997Y623963D01*
G01X1784002Y629035D02*
X1784006Y629134D01*
G01X1783997Y628963D02*
X1784002Y629035D01*
G01X1783999Y628937D02*
X1783997Y628963D01*
G01X1784002Y634035D02*
X1784006Y634134D01*
G01X1783997Y633963D02*
X1784002Y634035D01*
G01X1783999Y633937D02*
X1783997Y633963D01*
G01X1784002Y639035D02*
X1784006Y639134D01*
G01X1783997Y638963D02*
X1784002Y639035D01*
G01X1783999Y638937D02*
X1783997Y638963D01*
G01X1784002Y644035D02*
X1784006Y644134D01*
G01X1783997Y643963D02*
X1784002Y644035D01*
G01X1783999Y643937D02*
X1783997Y643963D01*
G01X1783052Y647557D02*
X1783053Y647559D01*
G01X1783051Y647552D02*
X1783052Y647557D01*
G01X1783051Y647543D02*
Y647552D01*
G01X1783052Y642557D02*
X1783053Y642559D01*
G01X1783051Y642552D02*
X1783052Y642557D01*
G01X1783051Y642543D02*
Y642552D01*
G01X1783052Y637557D02*
X1783053Y637559D01*
G01X1783051Y637552D02*
X1783052Y637557D01*
G01X1783051Y637543D02*
Y637552D01*
G01X1783052Y632557D02*
X1783053Y632559D01*
G01X1783051Y632552D02*
X1783052Y632557D01*
G01X1783051Y632543D02*
Y632552D01*
G01X1783052Y627557D02*
X1783053Y627559D01*
G01X1783051Y627552D02*
X1783052Y627557D01*
G01X1783051Y627543D02*
Y627552D01*
G01X1783052Y622557D02*
X1783053Y622559D01*
G01X1783051Y622552D02*
X1783052Y622557D01*
G01X1783051Y622543D02*
Y622552D01*
G01X1783052Y617557D02*
X1783053Y617559D01*
G01X1783051Y617552D02*
X1783052Y617557D01*
G01X1783051Y617543D02*
Y617552D01*
G01X1784036Y632552D02*
X1784035Y632543D01*
G01X1784037Y632557D02*
X1784036Y632552D01*
G01X1784038Y632559D02*
X1784037Y632557D01*
G01X1784036Y627552D02*
X1784035Y627543D01*
G01X1784037Y627557D02*
X1784036Y627552D01*
G01X1784038Y627559D02*
X1784037Y627557D01*
G01X1784036Y622552D02*
X1784035Y622543D01*
G01X1784037Y622557D02*
X1784036Y622552D01*
G01X1784038Y622559D02*
X1784037Y622557D01*
G01X1784036Y617552D02*
X1784035Y617543D01*
G01X1784037Y617557D02*
X1784036Y617552D01*
G01X1784038Y617559D02*
X1784037Y617557D01*
G01X1784018Y618932D02*
X1783999Y618937D01*
G01X1784033Y618918D02*
X1784018Y618932D01*
G01X1784038Y618898D02*
X1784033Y618918D01*
G01X1784018Y623932D02*
X1783999Y623937D01*
G01X1784033Y623918D02*
X1784018Y623932D01*
G01X1784038Y623898D02*
X1784033Y623918D01*
G01X1784018Y628932D02*
X1783999Y628937D01*
G01X1784033Y628918D02*
X1784018Y628932D01*
G01X1784038Y628898D02*
X1784033Y628918D01*
G01X1784018Y633932D02*
X1783999Y633937D01*
G01X1784033Y633918D02*
X1784018Y633932D01*
G01X1784038Y633898D02*
X1784033Y633918D01*
G01X1784018Y638932D02*
X1783999Y638937D01*
G01X1784033Y638918D02*
X1784018Y638932D01*
G01X1784038Y638898D02*
X1784033Y638918D01*
G01X1784018Y643932D02*
X1783999Y643937D01*
G01X1784033Y643918D02*
X1784018Y643932D01*
G01X1784038Y643898D02*
X1784033Y643918D01*
G01X1779646Y606437D02*
G03I-1103J0D01*
G01X1781102Y601161D02*
G03X1782283Y602343I0J1181D01*
G01X1774803D02*
G03X1775984Y601161I1181J-1D01*
G01X1780118Y606437D02*
G03I-1575J0D01*
G01X1784035Y618911D02*
X1784036Y618920D01*
G01X1784035Y623911D02*
X1784036Y623920D01*
G01X1784035Y628911D02*
X1784036Y628920D01*
G01X1784035Y633911D02*
X1784036Y633920D01*
G01X1784035Y638911D02*
X1784036Y638920D01*
G01X1784035Y643911D02*
X1784036Y643920D01*
G01X1788386Y647559D02*
Y648937D01*
G01Y642559D02*
Y643937D01*
G01Y637559D02*
Y638937D01*
G01Y632559D02*
Y633937D01*
G01Y627559D02*
Y628937D01*
G01Y622559D02*
Y623937D01*
G01Y617559D02*
Y618937D01*
G01X1781028Y609508D02*
X1779724Y607539D01*
G01X1775052Y601617D02*
X1777362Y605846D01*
G01X1786024Y749744D02*
Y611752D01*
G01X1785433Y751988D02*
Y609508D01*
G01X1785217Y618937D02*
Y617559D01*
G01Y623937D02*
Y622559D01*
G01Y628937D02*
Y627559D01*
G01Y633937D02*
Y632559D01*
G01Y638937D02*
Y637559D01*
G01Y643937D02*
Y642559D01*
G01Y648937D02*
Y647559D01*
G01X1784035Y647067D02*
Y649429D01*
G01Y642067D02*
Y644429D01*
G01Y637067D02*
Y639429D01*
G01Y632067D02*
Y634429D01*
G01Y627067D02*
Y629429D01*
G01Y622067D02*
Y624429D01*
G01Y617067D02*
Y619429D01*
G01X1783051D02*
Y617067D01*
G01Y624429D02*
Y622067D01*
G01Y629429D02*
Y627067D01*
G01Y634429D02*
Y632067D01*
G01Y639429D02*
Y637067D01*
G01Y644429D02*
Y642067D01*
G01Y649429D02*
Y647067D01*
G01X1782283Y610886D02*
Y602343D01*
G01X1780709Y649705D02*
Y613248D01*
G01X1779724Y607539D02*
Y605846D01*
G01X1779528Y650886D02*
Y614429D01*
G01X1777362Y605846D02*
Y607539D01*
G01X1774803Y602343D02*
Y610886D01*
G01X1774016Y614429D02*
Y747067D01*
G01X1772835Y613248D02*
Y748248D01*
G01X1771063Y648543D02*
Y609508D01*
G01X1774016Y614429D02*
X1772835Y613248D01*
G01X1771063Y611752D02*
X1767717Y608406D01*
G01X1779724Y605846D02*
X1782035Y601617D01*
G01X1777362Y607539D02*
X1776059Y609508D01*
G01X1786024Y611752D02*
X1789370Y608406D01*
G01X1779528Y614429D02*
X1780709Y613248D01*
G01X1788386Y647559D02*
X1783053D01*
G01X1783051Y647067D02*
X1784035D01*
G01Y644429D02*
X1783051D01*
G01X1783053Y643937D02*
X1788386D01*
G01Y643898D02*
X1784038D01*
G01X1788386Y642559D02*
X1783053D01*
G01X1783051Y642067D02*
X1784035D01*
G01Y639429D02*
X1783051D01*
G01X1783053Y638937D02*
X1788386D01*
G01Y638898D02*
X1784038D01*
G01X1788386Y637559D02*
X1783053D01*
G01X1783051Y637067D02*
X1784035D01*
G01Y634429D02*
X1783051D01*
G01X1783053Y633937D02*
X1788386D01*
G01Y633898D02*
X1784038D01*
G01X1788386Y632559D02*
X1783053D01*
G01X1783051Y632067D02*
X1784035D01*
G01Y629429D02*
X1783051D01*
G01X1783053Y628937D02*
X1788386D01*
G01Y628898D02*
X1784038D01*
G01X1788386Y627559D02*
X1783053D01*
G01X1783051Y627067D02*
X1784035D01*
G01Y624429D02*
X1783051D01*
G01X1783053Y623937D02*
X1788386D01*
G01Y623898D02*
X1784038D01*
G01X1788386Y622559D02*
X1783053D01*
G01X1783051Y622067D02*
X1784035D01*
G01Y619429D02*
X1783051D01*
G01X1783053Y618937D02*
X1788386D01*
G01Y618898D02*
X1784038D01*
G01X1788386Y617559D02*
X1783053D01*
G01X1783051Y617067D02*
X1784035D01*
G01Y647363D02*
X1783051Y647362D01*
G01Y644133D02*
X1784006Y644134D01*
G01X1784035Y642363D02*
X1783051Y642362D01*
G01Y639133D02*
X1784006Y639134D01*
G01X1784035Y637363D02*
X1783051Y637362D01*
G01Y634133D02*
X1784006Y634134D01*
G01X1784035Y632363D02*
X1783051Y632362D01*
G01Y629133D02*
X1784006Y629134D01*
G01X1784035Y627363D02*
X1783051Y627362D01*
G01Y624133D02*
X1784006Y624134D01*
G01X1784035Y622363D02*
X1783051Y622362D01*
G01Y619133D02*
X1784006Y619134D01*
G01X1784035Y617363D02*
X1783051Y617362D01*
G01X1779528Y614429D02*
X1774016D01*
G01X1780709Y613248D02*
X1772835D01*
G01X1786024Y611752D02*
X1771063D01*
G01X1782283Y610886D02*
X1785433D01*
G01X1774803D02*
X1771063D01*
G01Y609508D02*
X1785433D01*
G01X1779724Y607539D02*
X1777362D01*
G01X1779724Y605846D02*
X1777362D01*
G01X1781102Y601161D02*
X1775984D01*
G01X1789370Y601122D02*
X1767717D01*
G01X1769629Y651870D02*
X1769624Y651850D01*
G01X1769643Y651885D02*
X1769629Y651870D01*
G01X1769663Y651890D02*
X1769643Y651885D01*
G01X1769629Y655020D02*
X1769624Y655000D01*
G01X1769643Y655034D02*
X1769629Y655020D01*
G01X1769663Y655039D02*
X1769643Y655034D01*
G01X1769629Y658169D02*
X1769624Y658150D01*
G01X1769643Y658184D02*
X1769629Y658169D01*
G01X1769663Y658189D02*
X1769643Y658184D01*
G01X1769629Y661319D02*
X1769624Y661299D01*
G01X1769643Y661333D02*
X1769629Y661319D01*
G01X1769663Y661339D02*
X1769643Y661333D01*
G01X1769629Y664469D02*
X1769624Y664449D01*
G01X1769643Y664483D02*
X1769629Y664469D01*
G01X1769663Y664488D02*
X1769643Y664483D01*
G01X1769629Y667618D02*
X1769624Y667598D01*
G01X1769643Y667633D02*
X1769629Y667618D01*
G01X1769663Y667638D02*
X1769643Y667633D01*
G01X1769629Y670768D02*
X1769624Y670748D01*
G01X1769643Y670782D02*
X1769629Y670768D01*
G01X1769663Y670787D02*
X1769643Y670782D01*
G01X1770604Y650728D02*
X1770609Y650748D01*
G01X1770589Y650714D02*
X1770604Y650728D01*
G01X1770569Y650709D02*
X1770589Y650714D01*
G01X1770604Y653878D02*
X1770609Y653898D01*
G01X1770589Y653864D02*
X1770604Y653878D01*
G01X1770569Y653858D02*
X1770589Y653864D01*
G01X1770604Y657028D02*
X1770609Y657047D01*
G01X1770589Y657013D02*
X1770604Y657028D01*
G01X1770569Y657008D02*
X1770589Y657013D01*
G01X1770604Y660177D02*
X1770609Y660197D01*
G01X1770589Y660163D02*
X1770604Y660177D01*
G01X1770569Y660157D02*
X1770589Y660163D01*
G01X1770604Y663327D02*
X1770609Y663346D01*
G01X1770589Y663313D02*
X1770604Y663327D01*
G01X1770569Y663307D02*
X1770589Y663313D01*
G01X1770604Y666476D02*
X1770609Y666496D01*
G01X1770589Y666462D02*
X1770604Y666476D01*
G01X1770569Y666457D02*
X1770589Y666462D01*
G01X1770604Y669626D02*
X1770609Y669646D01*
G01X1770589Y669612D02*
X1770604Y669626D01*
G01X1770569Y669606D02*
X1770589Y669612D01*
G01X1770609Y666475D02*
X1770610Y666483D01*
G01X1770607Y666469D02*
X1770609Y666475D01*
G01X1770604Y666462D02*
X1770607Y666469D01*
G01X1770599Y666456D02*
X1770604Y666462D01*
G01X1770593Y666452D02*
X1770599Y666456D01*
G01X1770586Y666448D02*
X1770593Y666452D01*
G01X1770578Y666446D02*
X1770586Y666448D01*
G01X1770571Y666446D02*
X1770578D01*
G01X1770588Y650701D02*
X1770591Y650703D01*
G01X1770585Y650700D02*
X1770588Y650701D01*
G01X1770581Y650699D02*
X1770585Y650700D01*
G01X1770578Y650698D02*
X1770581Y650699D01*
G01X1770574Y650698D02*
X1770578D01*
G01X1770571D02*
X1770574D01*
G01X1769648Y651898D02*
X1769645Y651896D01*
G01X1769652Y651899D02*
X1769648Y651898D01*
G01X1769655Y651900D02*
X1769652Y651899D01*
G01X1769658Y651900D02*
X1769655D01*
G01X1769662Y651901D02*
X1769658Y651900D01*
G01X1769665Y651901D02*
X1769662D01*
G01X1770588Y653851D02*
X1770591Y653852D01*
G01X1770585Y653850D02*
X1770588Y653851D01*
G01X1770581Y653848D02*
X1770585Y653850D01*
G01X1770578Y653848D02*
X1770581D01*
G01X1770574Y653847D02*
X1770578Y653848D01*
G01X1770571Y653847D02*
X1770574D01*
G01X1769648Y655047D02*
X1769645Y655046D01*
G01X1769652Y655048D02*
X1769648Y655047D01*
G01X1769655Y655050D02*
X1769652Y655048D01*
G01X1769658Y655050D02*
X1769655D01*
G01X1769662Y655051D02*
X1769658Y655050D01*
G01X1769665Y655051D02*
X1769662D01*
G01X1770588Y657000D02*
X1770591Y657002D01*
G01X1770585Y656999D02*
X1770588Y657000D01*
G01X1770581Y656998D02*
X1770585Y656999D01*
G01X1770578Y656997D02*
X1770581Y656998D01*
G01X1770574Y656997D02*
X1770578D01*
G01X1770571D02*
X1770574D01*
G01X1769648Y658197D02*
X1769645Y658195D01*
G01X1769652Y658198D02*
X1769648Y658197D01*
G01X1769655Y658199D02*
X1769652Y658198D01*
G01X1769658Y658200D02*
X1769655Y658199D01*
G01X1769662Y658200D02*
X1769658D01*
G01X1769665D02*
X1769662D01*
G01X1770588Y660150D02*
X1770591Y660152D01*
G01X1770585Y660149D02*
X1770588Y660150D01*
G01X1770581Y660148D02*
X1770585Y660149D01*
G01X1770578Y660147D02*
X1770581Y660148D01*
G01X1770574Y660146D02*
X1770578Y660147D01*
G01X1770571Y660146D02*
X1770574D01*
G01X1769648Y661346D02*
X1769645Y661345D01*
G01X1769652Y661348D02*
X1769648Y661346D01*
G01X1769655Y661349D02*
X1769652Y661348D01*
G01X1769658Y661349D02*
X1769655D01*
G01X1769662Y661350D02*
X1769658Y661349D01*
G01X1769665Y661350D02*
X1769662D01*
G01X1770588Y663300D02*
X1770591Y663301D01*
G01X1770585Y663298D02*
X1770588Y663300D01*
G01X1770581Y663297D02*
X1770585Y663298D01*
G01X1770578Y663296D02*
X1770581Y663297D01*
G01X1770574Y663296D02*
X1770578D01*
G01X1770571D02*
X1770574D01*
G01X1769648Y664496D02*
X1769645Y664494D01*
G01X1769652Y664497D02*
X1769648Y664496D01*
G01X1769655Y664498D02*
X1769652Y664497D01*
G01X1769658Y664499D02*
X1769655Y664498D01*
G01X1769662Y664500D02*
X1769658Y664499D01*
G01X1769665Y664500D02*
X1769662D01*
G01X1769648Y667646D02*
X1769645Y667644D01*
G01X1769652Y667647D02*
X1769648Y667646D01*
G01X1769655Y667648D02*
X1769652Y667647D01*
G01X1769658Y667648D02*
X1769655D01*
G01X1769662Y667649D02*
X1769658Y667648D01*
G01X1769665Y667649D02*
X1769662D01*
G01X1770588Y669599D02*
X1770591Y669600D01*
G01X1770585Y669598D02*
X1770588Y669599D01*
G01X1770581Y669596D02*
X1770585Y669598D01*
G01X1770578Y669596D02*
X1770581D01*
G01X1770574Y669595D02*
X1770578Y669596D01*
G01X1770571Y669595D02*
X1770574D01*
G01X1769648Y670795D02*
X1769645Y670794D01*
G01X1769652Y670796D02*
X1769648Y670795D01*
G01X1769655Y670798D02*
X1769652Y670796D01*
G01X1769658Y670798D02*
X1769655D01*
G01X1769662Y670799D02*
X1769658Y670798D01*
G01X1769665Y670799D02*
X1769662D01*
G01X1770601Y651888D02*
X1770605Y651883D01*
G01X1770596Y651893D02*
X1770601Y651888D01*
G01X1770590Y651896D02*
X1770596Y651893D01*
G01X1770584Y651899D02*
X1770590Y651896D01*
G01X1770578Y651901D02*
X1770584Y651899D01*
G01X1770571Y651901D02*
X1770578D01*
G01X1770601Y655038D02*
X1770605Y655033D01*
G01X1770596Y655042D02*
X1770601Y655038D01*
G01X1770590Y655046D02*
X1770596Y655042D01*
G01X1770584Y655048D02*
X1770590Y655046D01*
G01X1770578Y655050D02*
X1770584Y655048D01*
G01X1770571Y655051D02*
X1770578Y655050D01*
G01X1770601Y658187D02*
X1770605Y658182D01*
G01X1770596Y658192D02*
X1770601Y658187D01*
G01X1770590Y658196D02*
X1770596Y658192D01*
G01X1770584Y658198D02*
X1770590Y658196D01*
G01X1770578Y658200D02*
X1770584Y658198D01*
G01X1770571Y658200D02*
X1770578D01*
G01X1770601Y661337D02*
X1770605Y661332D01*
G01X1770596Y661341D02*
X1770601Y661337D01*
G01X1770590Y661345D02*
X1770596Y661341D01*
G01X1770584Y661348D02*
X1770590Y661345D01*
G01X1770578Y661350D02*
X1770584Y661348D01*
G01X1770571Y661350D02*
X1770578D01*
G01X1770601Y664487D02*
X1770605Y664481D01*
G01X1770596Y664491D02*
X1770601Y664487D01*
G01X1770590Y664495D02*
X1770596Y664491D01*
G01X1770584Y664497D02*
X1770590Y664495D01*
G01X1770578Y664499D02*
X1770584Y664497D01*
G01X1770571Y664500D02*
X1770578Y664499D01*
G01X1770601Y667636D02*
X1770605Y667631D01*
G01X1770596Y667641D02*
X1770601Y667636D01*
G01X1770590Y667644D02*
X1770596Y667641D01*
G01X1770584Y667647D02*
X1770590Y667644D01*
G01X1770578Y667649D02*
X1770584Y667647D01*
G01X1770571Y667649D02*
X1770578D01*
G01X1770601Y670786D02*
X1770605Y670781D01*
G01X1770596Y670790D02*
X1770601Y670786D01*
G01X1770590Y670794D02*
X1770596Y670790D01*
G01X1770584Y670796D02*
X1770590Y670794D01*
G01X1770578Y670798D02*
X1770584Y670796D01*
G01X1770571Y670799D02*
X1770578Y670798D01*
G01X1769627Y650727D02*
X1769626Y650735D01*
G01X1769629Y650720D02*
X1769627Y650727D01*
G01X1769633Y650714D02*
X1769629Y650720D01*
G01X1769637Y650708D02*
X1769633Y650714D01*
G01X1769644Y650704D02*
X1769637Y650708D01*
G01X1769650Y650700D02*
X1769644Y650704D01*
G01X1769658Y650698D02*
X1769650Y650700D01*
G01X1769665Y650698D02*
X1769658D01*
G01X1769627Y653877D02*
X1769626Y653884D01*
G01X1769629Y653870D02*
X1769627Y653877D01*
G01X1769633Y653864D02*
X1769629Y653870D01*
G01X1769637Y653858D02*
X1769633Y653864D01*
G01X1769644Y653853D02*
X1769637Y653858D01*
G01X1769650Y653850D02*
X1769644Y653853D01*
G01X1769658Y653848D02*
X1769650Y653850D01*
G01X1769665Y653847D02*
X1769658Y653848D01*
G01X1769627Y657026D02*
X1769626Y657034D01*
G01X1769629Y657020D02*
X1769627Y657026D01*
G01X1769633Y657013D02*
X1769629Y657020D01*
G01X1769637Y657007D02*
X1769633Y657013D01*
G01X1769644Y657003D02*
X1769637Y657007D01*
G01X1769650Y657000D02*
X1769644Y657003D01*
G01X1769658Y656998D02*
X1769650Y657000D01*
G01X1769665Y656997D02*
X1769658Y656998D01*
G01X1769627Y660176D02*
X1769626Y660183D01*
G01X1769629Y660169D02*
X1769627Y660176D01*
G01X1769633Y660163D02*
X1769629Y660169D01*
G01X1769637Y660157D02*
X1769633Y660163D01*
G01X1769644Y660152D02*
X1769637Y660157D01*
G01X1769650Y660149D02*
X1769644Y660152D01*
G01X1769658Y660147D02*
X1769650Y660149D01*
G01X1769665Y660146D02*
X1769658Y660147D01*
G01X1769627Y663326D02*
X1769626Y663333D01*
G01X1769629Y663319D02*
X1769627Y663326D01*
G01X1769633Y663313D02*
X1769629Y663319D01*
G01X1769637Y663307D02*
X1769633Y663313D01*
G01X1769644Y663302D02*
X1769637Y663307D01*
G01X1769650Y663299D02*
X1769644Y663302D01*
G01X1769658Y663297D02*
X1769650Y663299D01*
G01X1769665Y663296D02*
X1769658Y663297D01*
G01X1769627Y666475D02*
X1769626Y666483D01*
G01X1769629Y666469D02*
X1769627Y666475D01*
G01X1769633Y666462D02*
X1769629Y666469D01*
G01X1769637Y666456D02*
X1769633Y666462D01*
G01X1769644Y666452D02*
X1769637Y666456D01*
G01X1769650Y666448D02*
X1769644Y666452D01*
G01X1769658Y666446D02*
X1769650Y666448D01*
G01X1769665Y666446D02*
X1769658D01*
G01X1769627Y669625D02*
X1769626Y669632D01*
G01X1769629Y669618D02*
X1769627Y669625D01*
G01X1769633Y669612D02*
X1769629Y669618D01*
G01X1769637Y669606D02*
X1769633Y669612D01*
G01X1769644Y669601D02*
X1769637Y669606D01*
G01X1769650Y669598D02*
X1769644Y669601D01*
G01X1769658Y669596D02*
X1769650Y669598D01*
G01X1769665Y669595D02*
X1769658Y669596D01*
G01X1770580Y651889D02*
X1770589Y651884D01*
G01X1770569Y651890D02*
X1770580Y651889D01*
G01Y655038D02*
X1770589Y655034D01*
G01X1770569Y655039D02*
X1770580Y655038D01*
G01Y658188D02*
X1770589Y658183D01*
G01X1770569Y658189D02*
X1770580Y658188D01*
G01Y661337D02*
X1770589Y661333D01*
G01X1770569Y661339D02*
X1770580Y661337D01*
G01Y664487D02*
X1770589Y664483D01*
G01X1770569Y664488D02*
X1770580Y664487D01*
G01Y667637D02*
X1770589Y667632D01*
G01X1770569Y667638D02*
X1770580Y667637D01*
G01Y670786D02*
X1770589Y670782D01*
G01X1770569Y670787D02*
X1770580Y670786D01*
G01X1769626Y653888D02*
Y653884D01*
G01X1769628Y653882D02*
X1769626Y653888D01*
G01X1769639Y653867D02*
X1769628Y653882D01*
G01X1769664Y653858D02*
X1769639Y653867D01*
G01X1769626Y657038D02*
Y657034D01*
G01X1769628Y657031D02*
X1769626Y657038D01*
G01X1769639Y657016D02*
X1769628Y657031D01*
G01X1769663Y657008D02*
X1769639Y657016D01*
G01X1769626Y663337D02*
Y663333D01*
G01X1769628Y663331D02*
X1769626Y663337D01*
G01X1769639Y663315D02*
X1769628Y663331D01*
G01X1769663Y663307D02*
X1769639Y663315D01*
G01X1769626Y666487D02*
Y666483D01*
G01X1769628Y666480D02*
X1769626Y666487D01*
G01X1769639Y666465D02*
X1769628Y666480D01*
G01X1769663Y666457D02*
X1769639Y666465D01*
G01X1769626Y650739D02*
Y650735D01*
G01X1769628Y650732D02*
X1769626Y650739D01*
G01X1769639Y650717D02*
X1769628Y650732D01*
G01X1769663Y650709D02*
X1769639Y650717D01*
G01X1769626Y669636D02*
Y669632D01*
G01X1769628Y669630D02*
X1769626Y669636D01*
G01X1769639Y669615D02*
X1769628Y669630D01*
G01X1769663Y669606D02*
X1769639Y669615D01*
G01X1784023Y648929D02*
X1784034Y648913D01*
G01X1783998Y648937D02*
X1784023Y648929D01*
G01Y673929D02*
X1784034Y673913D01*
G01X1783998Y673937D02*
X1784023Y673929D01*
G01Y678929D02*
X1784034Y678913D01*
G01X1783998Y678937D02*
X1784023Y678929D01*
G01Y683929D02*
X1784034Y683913D01*
G01X1783998Y683937D02*
X1784023Y683929D01*
G01Y688929D02*
X1784034Y688913D01*
G01X1783998Y688937D02*
X1784023Y688929D01*
G01Y693929D02*
X1784034Y693913D01*
G01X1783998Y693937D02*
X1784023Y693929D01*
G01X1769626Y660187D02*
Y660183D01*
G01X1769627Y660182D02*
X1769626Y660187D01*
G01X1769637Y660167D02*
X1769627Y660182D01*
G01X1769661Y660158D02*
X1769637Y660167D01*
G01X1770579Y658188D02*
X1770569Y658189D01*
G01X1770587Y658185D02*
X1770579Y658188D01*
G01X1770595Y658180D02*
X1770587Y658185D01*
G01X1770579Y651889D02*
X1770569Y651890D01*
G01X1770588Y651885D02*
X1770579Y651889D01*
G01X1770595Y651880D02*
X1770588Y651885D01*
G01X1770579Y655038D02*
X1770569Y655039D01*
G01X1770588Y655035D02*
X1770579Y655038D01*
G01X1770595Y655030D02*
X1770588Y655035D01*
G01X1770579Y661337D02*
X1770569Y661339D01*
G01X1770588Y661334D02*
X1770579Y661337D01*
G01X1770595Y661329D02*
X1770588Y661334D01*
G01X1770579Y664487D02*
X1770569Y664488D01*
G01X1770588Y664484D02*
X1770579Y664487D01*
G01X1770595Y664479D02*
X1770588Y664484D01*
G01X1770579Y667637D02*
X1770569Y667638D01*
G01X1770588Y667633D02*
X1770579Y667637D01*
G01X1770595Y667628D02*
X1770588Y667633D01*
G01X1770579Y670786D02*
X1770569Y670787D01*
G01X1770588Y670783D02*
X1770579Y670786D01*
G01X1770595Y670778D02*
X1770588Y670783D01*
G01X1770581Y669608D02*
X1770569Y669606D01*
G01X1770592Y669613D02*
X1770581Y669608D01*
G01Y666459D02*
X1770569Y666457D01*
G01X1770592Y666464D02*
X1770581Y666459D01*
G01X1769665Y650704D02*
Y650698D01*
G01X1769664Y650707D02*
X1769665Y650704D01*
G01X1769663Y650709D02*
X1769664Y650707D01*
G01X1769665Y653854D02*
Y653847D01*
G01X1769664Y653857D02*
X1769665Y653854D01*
G01X1769663Y653858D02*
X1769664Y653857D01*
G01X1769665Y657003D02*
Y656997D01*
G01X1769664Y657007D02*
X1769665Y657003D01*
G01X1769663Y657008D02*
X1769664Y657007D01*
G01X1769665Y660153D02*
Y660146D01*
G01X1769664Y660156D02*
X1769665Y660153D01*
G01X1769663Y660157D02*
X1769664Y660156D01*
G01X1769665Y663302D02*
Y663296D01*
G01X1769664Y663306D02*
X1769665Y663302D01*
G01X1769663Y663307D02*
X1769664Y663306D01*
G01X1769665Y666452D02*
Y666446D01*
G01X1769664Y666456D02*
X1769665Y666452D01*
G01X1769663Y666457D02*
X1769664Y666456D01*
G01X1769665Y669602D02*
Y669595D01*
G01X1769664Y669605D02*
X1769665Y669602D01*
G01X1769663Y669606D02*
X1769664Y669605D01*
G01X1769627Y670768D02*
X1769626Y670762D01*
G01X1769628Y670774D02*
X1769627Y670768D01*
G01X1769631Y670780D02*
X1769628Y670774D01*
G01X1769635Y670785D02*
X1769631Y670780D01*
G01X1769640Y670790D02*
X1769635Y670785D01*
G01X1769645Y670794D02*
X1769640Y670790D01*
G01X1769627Y667619D02*
X1769626Y667612D01*
G01X1769628Y667625D02*
X1769627Y667619D01*
G01X1769631Y667630D02*
X1769628Y667625D01*
G01X1769635Y667636D02*
X1769631Y667630D01*
G01X1769640Y667640D02*
X1769635Y667636D01*
G01X1769645Y667644D02*
X1769640Y667640D01*
G01X1769627Y664469D02*
X1769626Y664463D01*
G01X1769628Y664475D02*
X1769627Y664469D01*
G01X1769631Y664481D02*
X1769628Y664475D01*
G01X1769635Y664486D02*
X1769631Y664481D01*
G01X1769640Y664491D02*
X1769635Y664486D01*
G01X1769645Y664494D02*
X1769640Y664491D01*
G01X1770581Y663309D02*
X1770569Y663307D01*
G01X1770592Y663314D02*
X1770581Y663309D01*
G01Y660159D02*
X1770569Y660157D01*
G01X1770592Y660165D02*
X1770581Y660159D01*
G01Y657010D02*
X1770569Y657008D01*
G01X1770592Y657015D02*
X1770581Y657010D01*
G01Y653860D02*
X1770569Y653858D01*
G01X1770592Y653865D02*
X1770581Y653860D01*
G01Y650711D02*
X1770569Y650709D01*
G01X1770592Y650716D02*
X1770581Y650711D01*
G01X1770608Y669620D02*
X1770610Y669632D01*
G01X1770601Y669609D02*
X1770608Y669620D01*
G01X1770591Y669600D02*
X1770601Y669609D01*
G01X1770608Y663320D02*
X1770610Y663333D01*
G01X1770601Y663309D02*
X1770608Y663320D01*
G01X1770591Y663301D02*
X1770601Y663309D01*
G01X1770608Y660171D02*
X1770610Y660183D01*
G01X1770601Y660160D02*
X1770608Y660171D01*
G01X1770591Y660152D02*
X1770601Y660160D01*
G01X1770608Y657021D02*
X1770610Y657034D01*
G01X1770601Y657010D02*
X1770608Y657021D01*
G01X1770591Y657002D02*
X1770601Y657010D01*
G01X1770608Y653872D02*
X1770610Y653884D01*
G01X1770601Y653861D02*
X1770608Y653872D01*
G01X1770591Y653852D02*
X1770601Y653861D01*
G01X1770608Y650722D02*
X1770610Y650735D01*
G01X1770601Y650711D02*
X1770608Y650722D01*
G01X1770591Y650703D02*
X1770601Y650711D01*
G01X1769665Y670793D02*
Y670799D01*
G01Y670789D02*
Y670793D01*
G01X1769663Y670787D02*
X1769665Y670789D01*
G01Y667643D02*
Y667649D01*
G01Y667639D02*
Y667643D01*
G01X1769663Y667638D02*
X1769665Y667639D01*
G01Y664493D02*
Y664500D01*
G01Y664489D02*
Y664493D01*
G01X1769663Y664488D02*
X1769665Y664489D01*
G01Y661344D02*
Y661350D01*
G01Y661340D02*
Y661344D01*
G01X1769663Y661339D02*
X1769665Y661340D01*
G01Y658194D02*
Y658200D01*
G01Y658190D02*
Y658194D01*
G01X1769663Y658189D02*
X1769665Y658190D01*
G01Y655044D02*
Y655051D01*
G01Y655041D02*
Y655044D01*
G01X1769663Y655039D02*
X1769665Y655041D01*
G01Y651895D02*
Y651901D01*
G01Y651891D02*
Y651895D01*
G01X1769663Y651890D02*
X1769665Y651891D01*
G01X1769627Y661319D02*
X1769626Y661313D01*
G01X1769628Y661326D02*
X1769627Y661319D01*
G01X1769631Y661331D02*
X1769628Y661326D01*
G01X1769635Y661337D02*
X1769631Y661331D01*
G01X1769640Y661341D02*
X1769635Y661337D01*
G01X1769645Y661345D02*
X1769640Y661341D01*
G01X1769627Y658170D02*
X1769626Y658163D01*
G01X1769628Y658176D02*
X1769627Y658170D01*
G01X1769631Y658181D02*
X1769628Y658176D01*
G01X1769635Y658187D02*
X1769631Y658181D01*
G01X1769640Y658191D02*
X1769635Y658187D01*
G01X1769645Y658195D02*
X1769640Y658191D01*
G01X1769627Y655020D02*
X1769626Y655014D01*
G01X1769628Y655026D02*
X1769627Y655020D01*
G01X1769631Y655032D02*
X1769628Y655026D01*
G01X1769635Y655037D02*
X1769631Y655032D01*
G01X1769640Y655042D02*
X1769635Y655037D01*
G01X1769645Y655046D02*
X1769640Y655042D01*
G01X1769627Y651870D02*
X1769626Y651864D01*
G01X1769628Y651877D02*
X1769627Y651870D01*
G01X1769631Y651882D02*
X1769628Y651877D01*
G01X1769635Y651888D02*
X1769631Y651882D01*
G01X1769640Y651892D02*
X1769635Y651888D01*
G01X1769645Y651896D02*
X1769640Y651892D01*
G01X1784036Y648904D02*
X1784035Y648911D01*
G01X1784037Y648900D02*
X1784036Y648904D01*
G01X1784038Y648898D02*
X1784037Y648900D01*
G01X1784036Y673904D02*
X1784035Y673911D01*
G01X1784037Y673900D02*
X1784036Y673904D01*
G01X1784038Y673898D02*
X1784037Y673900D01*
G01X1784036Y678904D02*
X1784035Y678911D01*
G01X1784037Y678900D02*
X1784036Y678904D01*
G01X1784038Y678898D02*
X1784037Y678900D01*
G01X1784036Y683904D02*
X1784035Y683911D01*
G01X1784037Y683900D02*
X1784036Y683904D01*
G01X1784038Y683898D02*
X1784037Y683900D01*
G01X1784036Y688904D02*
X1784035Y688911D01*
G01X1784037Y688900D02*
X1784036Y688904D01*
G01X1784038Y688898D02*
X1784037Y688900D01*
G01X1784036Y693904D02*
X1784035Y693911D01*
G01X1784037Y693900D02*
X1784036Y693904D01*
G01X1784038Y693898D02*
X1784037Y693900D01*
G01X1769649Y653861D02*
X1769663Y653858D01*
G01X1769637Y653868D02*
X1769649Y653861D01*
G01X1769625Y653887D02*
X1769637Y653868D01*
G01X1769649Y663310D02*
X1769663Y663307D01*
G01X1769637Y663317D02*
X1769649Y663310D01*
G01X1769625Y663335D02*
X1769637Y663317D01*
G01X1769648Y657011D02*
X1769663Y657008D01*
G01X1769636Y657019D02*
X1769648Y657011D01*
G01X1769624Y657039D02*
X1769636Y657019D01*
G01X1769648Y666459D02*
X1769663Y666457D01*
G01X1769636Y666467D02*
X1769648Y666459D01*
G01X1769624Y666487D02*
X1769636Y666467D01*
G01X1770610Y650742D02*
Y650735D01*
G01X1770609Y650747D02*
X1770610Y650742D01*
G01X1770609Y650748D02*
Y650747D01*
G01X1770610Y653892D02*
Y653884D01*
G01X1770609Y653896D02*
X1770610Y653892D01*
G01X1770609Y653898D02*
Y653896D01*
G01X1770610Y657041D02*
Y657034D01*
G01X1770609Y657046D02*
X1770610Y657041D01*
G01X1770609Y657047D02*
Y657046D01*
G01X1770610Y660191D02*
Y660183D01*
G01X1770609Y660196D02*
X1770610Y660191D01*
G01X1770609Y660197D02*
Y660196D01*
G01X1770610Y663341D02*
Y663333D01*
G01X1770609Y663345D02*
X1770610Y663341D01*
G01X1770609Y663346D02*
Y663345D01*
G01X1770610Y666490D02*
Y666483D01*
G01X1770609Y666495D02*
X1770610Y666490D01*
G01X1770609Y666496D02*
Y666495D01*
G01X1784036Y692552D02*
X1784035Y692543D01*
G01X1784037Y692557D02*
X1784036Y692552D01*
G01X1784038Y692559D02*
X1784037Y692557D01*
G01X1784036Y687552D02*
X1784035Y687543D01*
G01X1784037Y687557D02*
X1784036Y687552D01*
G01X1784038Y687559D02*
X1784037Y687557D01*
G01X1784036Y682552D02*
X1784035Y682543D01*
G01X1784037Y682557D02*
X1784036Y682552D01*
G01X1784038Y682559D02*
X1784037Y682557D01*
G01X1784036Y677552D02*
X1784035Y677543D01*
G01X1784037Y677557D02*
X1784036Y677552D01*
G01X1784038Y677559D02*
X1784037Y677557D01*
G01X1784036Y672552D02*
X1784035Y672543D01*
G01X1784037Y672557D02*
X1784036Y672552D01*
G01X1784038Y672559D02*
X1784037Y672557D01*
G01X1769626Y670754D02*
Y670762D01*
G01X1769625Y670750D02*
X1769626Y670754D01*
G01X1769624Y670748D02*
X1769625Y670750D01*
G01X1769626Y667605D02*
Y667612D01*
G01X1769625Y667600D02*
X1769626Y667605D01*
G01X1769624Y667598D02*
X1769625Y667600D01*
G01X1769626Y664455D02*
Y664463D01*
G01X1769625Y664450D02*
X1769626Y664455D01*
G01X1769624Y664449D02*
X1769625Y664450D01*
G01X1769626Y661306D02*
Y661313D01*
G01X1769625Y661301D02*
X1769626Y661306D01*
G01X1769624Y661299D02*
X1769625Y661301D01*
G01X1769626Y658156D02*
Y658163D01*
G01X1769625Y658151D02*
X1769626Y658156D01*
G01X1769624Y658150D02*
X1769625Y658151D01*
G01X1769626Y655006D02*
Y655014D01*
G01X1769625Y655002D02*
X1769626Y655006D01*
G01X1769624Y655000D02*
X1769625Y655002D01*
G01X1769626Y651857D02*
Y651864D01*
G01X1769625Y651852D02*
X1769626Y651857D01*
G01X1769624Y651850D02*
X1769625Y651852D01*
G01X1770610Y669640D02*
Y669632D01*
G01X1770609Y669644D02*
X1770610Y669640D01*
G01X1770609Y669646D02*
Y669644D01*
G01X1769648Y669609D02*
X1769663Y669606D01*
G01X1769636Y669617D02*
X1769648Y669609D01*
G01X1769624Y669637D02*
X1769636Y669617D01*
G01X1769648Y650712D02*
X1769663Y650709D01*
G01X1769635Y650720D02*
X1769648Y650712D01*
G01X1769624Y650741D02*
X1769635Y650720D01*
G01X1770609Y651871D02*
X1770610Y651864D01*
G01X1770608Y651877D02*
X1770609Y651871D01*
G01X1770605Y651883D02*
X1770608Y651877D01*
G01X1770609Y655020D02*
X1770610Y655014D01*
G01X1770608Y655027D02*
X1770609Y655020D01*
G01X1770605Y655033D02*
X1770608Y655027D01*
G01X1770609Y658170D02*
X1770610Y658163D01*
G01X1770608Y658176D02*
X1770609Y658170D01*
G01X1770605Y658182D02*
X1770608Y658176D01*
G01X1770609Y661320D02*
X1770610Y661313D01*
G01X1770608Y661326D02*
X1770609Y661320D01*
G01X1770605Y661332D02*
X1770608Y661326D01*
G01X1770609Y664469D02*
X1770610Y664463D01*
G01X1770608Y664476D02*
X1770609Y664469D01*
G01X1770605Y664481D02*
X1770608Y664476D01*
G01X1770609Y667619D02*
X1770610Y667612D01*
G01X1770608Y667625D02*
X1770609Y667619D01*
G01X1770605Y667631D02*
X1770608Y667625D01*
G01X1770609Y670769D02*
X1770610Y670762D01*
G01X1770608Y670775D02*
X1770609Y670769D01*
G01X1770605Y670781D02*
X1770608Y670775D01*
G01X1770571Y650704D02*
X1770572Y650698D01*
G01X1770570Y650707D02*
X1770571Y650704D01*
G01X1770569Y650709D02*
X1770570Y650707D01*
G01X1770571Y653853D02*
X1770572Y653847D01*
G01X1770570Y653857D02*
X1770571Y653853D01*
G01X1770569Y653858D02*
X1770570Y653857D01*
G01X1770571Y657003D02*
X1770572Y656997D01*
G01X1770570Y657007D02*
X1770571Y657003D01*
G01X1770569Y657008D02*
X1770570Y657007D01*
G01X1770571Y660152D02*
X1770572Y660146D01*
G01X1770570Y660156D02*
X1770571Y660152D01*
G01X1770569Y660157D02*
X1770570Y660156D01*
G01X1770571Y663302D02*
X1770572Y663296D01*
G01X1770570Y663306D02*
X1770571Y663302D01*
G01X1770569Y663307D02*
X1770570Y663306D01*
G01X1770571Y669601D02*
X1770572Y669595D01*
G01X1770570Y669605D02*
X1770571Y669601D01*
G01X1770569Y669606D02*
X1770570Y669605D01*
G01X1783051Y648944D02*
Y648954D01*
G01X1783052Y648939D02*
X1783051Y648944D01*
G01X1783053Y648937D02*
X1783052Y648939D01*
G01X1783051Y673944D02*
Y673954D01*
G01X1783052Y673939D02*
X1783051Y673944D01*
G01X1783053Y673937D02*
X1783052Y673939D01*
G01X1783051Y678944D02*
Y678954D01*
G01X1783052Y678939D02*
X1783051Y678944D01*
G01X1783053Y678937D02*
X1783052Y678939D01*
G01X1783051Y683944D02*
Y683954D01*
G01X1783052Y683939D02*
X1783051Y683944D01*
G01X1783053Y683937D02*
X1783052Y683939D01*
G01X1783051Y688944D02*
Y688954D01*
G01X1783052Y688939D02*
X1783051Y688944D01*
G01X1783053Y688937D02*
X1783052Y688939D01*
G01X1783051Y693944D02*
Y693954D01*
G01X1783052Y693939D02*
X1783051Y693944D01*
G01X1783053Y693937D02*
X1783052Y693939D01*
G01X1784028Y649081D02*
X1784035Y649055D01*
G01X1784018Y649107D02*
X1784028Y649081D01*
G01X1784006Y649134D02*
X1784018Y649107D01*
G01X1784028Y674081D02*
X1784035Y674055D01*
G01X1784018Y674107D02*
X1784028Y674081D01*
G01X1784006Y674134D02*
X1784018Y674107D01*
G01X1784028Y679081D02*
X1784035Y679055D01*
G01X1784018Y679107D02*
X1784028Y679081D01*
G01X1784006Y679134D02*
X1784018Y679107D01*
G01X1784028Y684081D02*
X1784035Y684055D01*
G01X1784018Y684107D02*
X1784028Y684081D01*
G01X1784006Y684134D02*
X1784018Y684107D01*
G01X1784028Y689081D02*
X1784035Y689055D01*
G01X1784018Y689107D02*
X1784028Y689081D01*
G01X1784006Y689134D02*
X1784018Y689107D01*
G01X1784028Y694081D02*
X1784035Y694055D01*
G01X1784018Y694107D02*
X1784028Y694081D01*
G01X1784006Y694134D02*
X1784018Y694107D01*
G01X1769644Y660163D02*
X1769663Y660157D01*
G01X1769630Y660175D02*
X1769644Y660163D01*
G01X1769624Y660193D02*
X1769630Y660175D01*
G01X1784002Y649035D02*
X1784006Y649134D01*
G01X1783997Y648963D02*
X1784002Y649035D01*
G01X1783999Y648937D02*
X1783997Y648963D01*
G01X1784002Y674035D02*
X1784006Y674134D01*
G01X1783997Y673963D02*
X1784002Y674035D01*
G01X1783999Y673937D02*
X1783997Y673963D01*
G01X1784002Y679035D02*
X1784006Y679134D01*
G01X1783997Y678963D02*
X1784002Y679035D01*
G01X1783999Y678937D02*
X1783997Y678963D01*
G01X1784002Y684035D02*
X1784006Y684134D01*
G01X1783997Y683963D02*
X1784002Y684035D01*
G01X1783999Y683937D02*
X1783997Y683963D01*
G01X1784002Y689035D02*
X1784006Y689134D01*
G01X1783997Y688963D02*
X1784002Y689035D01*
G01X1783999Y688937D02*
X1783997Y688963D01*
G01X1784002Y694035D02*
X1784006Y694134D01*
G01X1783997Y693963D02*
X1784002Y694035D01*
G01X1783999Y693937D02*
X1783997Y693963D01*
G01X1769626Y663341D02*
Y663333D01*
G01X1769625Y663345D02*
X1769626Y663341D01*
G01X1769625Y663336D02*
Y663345D01*
G01X1769666Y670972D02*
X1769665Y670984D01*
G01X1769663Y670959D02*
X1769666Y670972D01*
G01X1769663Y670945D02*
Y670959D01*
G01X1769666Y667822D02*
X1769665Y667835D01*
G01X1769663Y667809D02*
X1769666Y667822D01*
G01X1769663Y667796D02*
Y667809D01*
G01X1769666Y664673D02*
X1769665Y664685D01*
G01X1769663Y664660D02*
X1769666Y664673D01*
G01X1769663Y664646D02*
Y664660D01*
G01X1769666Y661523D02*
X1769665Y661535D01*
G01X1769663Y661510D02*
X1769666Y661523D01*
G01X1769663Y661496D02*
Y661510D01*
G01X1769666Y658374D02*
X1769665Y658386D01*
G01X1769663Y658361D02*
X1769666Y658374D01*
G01X1769663Y658347D02*
Y658361D01*
G01X1769666Y655224D02*
X1769665Y655236D01*
G01X1769663Y655211D02*
X1769666Y655224D01*
G01X1769663Y655197D02*
Y655211D01*
G01X1769666Y652074D02*
X1769665Y652087D01*
G01X1769663Y652061D02*
X1769666Y652074D01*
G01X1769663Y652048D02*
Y652061D01*
G01X1783052Y692557D02*
X1783053Y692559D01*
G01X1783051Y692552D02*
X1783052Y692557D01*
G01X1783051Y692543D02*
Y692552D01*
G01X1783052Y687557D02*
X1783053Y687559D01*
G01X1783051Y687552D02*
X1783052Y687557D01*
G01X1783051Y687543D02*
Y687552D01*
G01X1783052Y682557D02*
X1783053Y682559D01*
G01X1783051Y682552D02*
X1783052Y682557D01*
G01X1783051Y682543D02*
Y682552D01*
G01X1783052Y677557D02*
X1783053Y677559D01*
G01X1783051Y677552D02*
X1783052Y677557D01*
G01X1783051Y677543D02*
Y677552D01*
G01X1783052Y672557D02*
X1783053Y672559D01*
G01X1783051Y672552D02*
X1783052Y672557D01*
G01X1783051Y672543D02*
Y672552D01*
G01X1769626Y669640D02*
Y669632D01*
G01X1769625Y669644D02*
X1769626Y669640D01*
G01X1769625Y669637D02*
Y669644D01*
G01X1769663Y669435D02*
X1769662Y669448D01*
G01X1769666Y669422D02*
X1769663Y669435D01*
G01X1769665Y669409D02*
X1769666Y669422D01*
G01X1769663Y666285D02*
X1769662Y666299D01*
G01X1769666Y666272D02*
X1769663Y666285D01*
G01X1769665Y666260D02*
X1769666Y666272D01*
G01X1769663Y663136D02*
X1769662Y663149D01*
G01X1769666Y663123D02*
X1769663Y663136D01*
G01X1769665Y663110D02*
X1769666Y663123D01*
G01X1769663Y659986D02*
X1769662Y660000D01*
G01X1769666Y659973D02*
X1769663Y659986D01*
G01X1769665Y659961D02*
X1769666Y659973D01*
G01X1769663Y656837D02*
X1769662Y656850D01*
G01X1769666Y656824D02*
X1769663Y656837D01*
G01X1769665Y656811D02*
X1769666Y656824D01*
G01X1769663Y653687D02*
X1769662Y653700D01*
G01X1769666Y653674D02*
X1769663Y653687D01*
G01X1769665Y653661D02*
X1769666Y653674D01*
G01X1769663Y650537D02*
X1769662Y650551D01*
G01X1769666Y650524D02*
X1769663Y650537D01*
G01X1769665Y650512D02*
X1769666Y650524D01*
G01X1770573Y670959D02*
X1770574Y670945D01*
G01X1770570Y670972D02*
X1770573Y670959D01*
G01X1770571Y670984D02*
X1770570Y670972D01*
G01X1770573Y667809D02*
X1770574Y667796D01*
G01X1770570Y667822D02*
X1770573Y667809D01*
G01X1770571Y667835D02*
X1770570Y667822D01*
G01X1770573Y664659D02*
X1770574Y664646D01*
G01X1770570Y664672D02*
X1770573Y664659D01*
G01X1770571Y664685D02*
X1770570Y664672D01*
G01X1770573Y661510D02*
X1770574Y661496D01*
G01X1770570Y661523D02*
X1770573Y661510D01*
G01X1770571Y661535D02*
X1770570Y661523D01*
G01X1770573Y658360D02*
X1770574Y658347D01*
G01X1770570Y658373D02*
X1770573Y658360D01*
G01X1770571Y658386D02*
X1770570Y658373D01*
G01X1770573Y655211D02*
X1770574Y655197D01*
G01X1770570Y655224D02*
X1770573Y655211D01*
G01X1770571Y655236D02*
X1770570Y655224D01*
G01X1770573Y652061D02*
X1770574Y652048D01*
G01X1770570Y652074D02*
X1770573Y652061D01*
G01X1770571Y652087D02*
X1770570Y652074D01*
G01X1769626Y657041D02*
Y657034D01*
G01X1769625Y657046D02*
X1769626Y657041D01*
G01X1769624Y657039D02*
X1769625Y657046D01*
G01X1769626Y666490D02*
Y666483D01*
G01X1769625Y666495D02*
X1769626Y666490D01*
G01X1769624Y666488D02*
X1769625Y666495D01*
G01X1770570Y669422D02*
X1770571Y669409D01*
G01X1770573Y669435D02*
X1770570Y669422D01*
G01X1770574Y669448D02*
X1770573Y669435D01*
G01X1770570Y666272D02*
X1770571Y666260D01*
G01X1770573Y666285D02*
X1770570Y666272D01*
G01X1770574Y666299D02*
X1770573Y666285D01*
G01X1770570Y663123D02*
X1770571Y663110D01*
G01X1770573Y663136D02*
X1770570Y663123D01*
G01X1770574Y663149D02*
X1770573Y663136D01*
G01X1770570Y659973D02*
X1770571Y659961D01*
G01X1770573Y659986D02*
X1770570Y659973D01*
G01X1770574Y660000D02*
X1770573Y659986D01*
G01X1770570Y656824D02*
X1770571Y656811D01*
G01X1770573Y656837D02*
X1770570Y656824D01*
G01X1770574Y656850D02*
X1770573Y656837D01*
G01X1770570Y653674D02*
X1770571Y653661D01*
G01X1770573Y653687D02*
X1770570Y653674D01*
G01X1770574Y653700D02*
X1770573Y653687D01*
G01X1770570Y650524D02*
X1770571Y650512D01*
G01X1770573Y650537D02*
X1770570Y650524D01*
G01X1770574Y650551D02*
X1770573Y650537D01*
G01X1769626Y650743D02*
Y650735D01*
G01X1769625Y650747D02*
X1769626Y650743D01*
G01X1769624Y650741D02*
X1769625Y650747D01*
G01X1769639Y670779D02*
X1769663Y670787D01*
G01X1769628Y670765D02*
X1769639Y670779D01*
G01X1769626Y670758D02*
X1769628Y670765D01*
G01X1769639Y667630D02*
X1769663Y667638D01*
G01X1769628Y667615D02*
X1769639Y667630D01*
G01X1769626Y667608D02*
X1769628Y667615D01*
G01X1769639Y664480D02*
X1769663Y664488D01*
G01X1769628Y664465D02*
X1769639Y664480D01*
G01X1769626Y664459D02*
X1769628Y664465D01*
G01X1769639Y661330D02*
X1769663Y661339D01*
G01X1769628Y661316D02*
X1769639Y661330D01*
G01X1769626Y661309D02*
X1769628Y661316D01*
G01X1769639Y658181D02*
X1769663Y658189D01*
G01X1769628Y658166D02*
X1769639Y658181D01*
G01X1769626Y658159D02*
X1769628Y658166D01*
G01X1769639Y655031D02*
X1769663Y655039D01*
G01X1769628Y655017D02*
X1769639Y655031D01*
G01X1769626Y655010D02*
X1769628Y655017D01*
G01X1769639Y651881D02*
X1769663Y651890D01*
G01X1769628Y651867D02*
X1769639Y651881D01*
G01X1769626Y651860D02*
X1769628Y651867D01*
G01X1770610Y670754D02*
Y670761D01*
G01Y670750D02*
Y670754D01*
G01X1770609Y670748D02*
X1770610Y670750D01*
G01Y667605D02*
Y667612D01*
G01Y667600D02*
Y667605D01*
G01X1770609Y667598D02*
X1770610Y667600D01*
G01Y664455D02*
Y664462D01*
G01Y664451D02*
Y664455D01*
G01X1770609Y664449D02*
X1770610Y664451D01*
G01Y661306D02*
Y661313D01*
G01Y661301D02*
Y661306D01*
G01X1770609Y661299D02*
X1770610Y661301D01*
G01Y658156D02*
Y658163D01*
G01Y658152D02*
Y658156D01*
G01X1770609Y658150D02*
X1770610Y658152D01*
G01Y655006D02*
Y655013D01*
G01Y655002D02*
Y655006D01*
G01X1770609Y655000D02*
X1770610Y655002D01*
G01Y651857D02*
Y651864D01*
G01Y651852D02*
Y651857D01*
G01X1770609Y651850D02*
X1770610Y651852D01*
G01X1769626Y660191D02*
Y660183D01*
G01X1769625Y660196D02*
X1769626Y660191D01*
G01X1769624Y660193D02*
X1769625Y660196D01*
G01X1769626Y653892D02*
Y653884D01*
G01X1769625Y653896D02*
X1769626Y653892D01*
G01X1769624Y653894D02*
X1769625Y653896D01*
G01X1770571Y670793D02*
Y670799D01*
G01X1770570Y670789D02*
X1770571Y670793D01*
G01X1770569Y670787D02*
X1770570Y670789D01*
G01X1770571Y667643D02*
Y667649D01*
G01X1770570Y667639D02*
X1770571Y667643D01*
G01X1770569Y667638D02*
X1770570Y667639D01*
G01X1770571Y664493D02*
Y664500D01*
G01X1770570Y664490D02*
X1770571Y664493D01*
G01X1770569Y664488D02*
X1770570Y664490D01*
G01X1770571Y661344D02*
Y661350D01*
G01X1770570Y661340D02*
X1770571Y661344D01*
G01X1770569Y661339D02*
X1770570Y661340D01*
G01X1770571Y658194D02*
Y658200D01*
G01X1770570Y658191D02*
X1770571Y658194D01*
G01X1770569Y658189D02*
X1770570Y658191D01*
G01X1770571Y655044D02*
Y655051D01*
G01X1770570Y655041D02*
X1770571Y655044D01*
G01X1770569Y655039D02*
X1770570Y655041D01*
G01X1770571Y651895D02*
Y651901D01*
G01X1770570Y651891D02*
X1770571Y651895D01*
G01X1770569Y651890D02*
X1770570Y651891D01*
G01X1784018Y648932D02*
X1783999Y648937D01*
G01X1784033Y648918D02*
X1784018Y648932D01*
G01X1784038Y648898D02*
X1784033Y648918D01*
G01X1784018Y673932D02*
X1783999Y673937D01*
G01X1784033Y673918D02*
X1784018Y673932D01*
G01X1784038Y673898D02*
X1784033Y673918D01*
G01X1784018Y678932D02*
X1783999Y678937D01*
G01X1784033Y678918D02*
X1784018Y678932D01*
G01X1784038Y678898D02*
X1784033Y678918D01*
G01X1784018Y683932D02*
X1783999Y683937D01*
G01X1784033Y683918D02*
X1784018Y683932D01*
G01X1784038Y683898D02*
X1784033Y683918D01*
G01X1784018Y688932D02*
X1783999Y688937D01*
G01X1784033Y688918D02*
X1784018Y688932D01*
G01X1784038Y688898D02*
X1784033Y688918D01*
G01X1784018Y693932D02*
X1783999Y693937D01*
G01X1784033Y693918D02*
X1784018Y693932D01*
G01X1784038Y693898D02*
X1784033Y693918D01*
G01X1770603Y658171D02*
X1770595Y658180D01*
G01X1770607Y658161D02*
X1770603Y658171D01*
G01X1770609Y658150D02*
X1770607Y658161D01*
G01X1770603Y651872D02*
X1770595Y651880D01*
G01X1770607Y651861D02*
X1770603Y651872D01*
G01X1770609Y651850D02*
X1770607Y651861D01*
G01X1770603Y655021D02*
X1770595Y655030D01*
G01X1770607Y655011D02*
X1770603Y655021D01*
G01X1770609Y655000D02*
X1770607Y655011D01*
G01X1770603Y661320D02*
X1770595Y661329D01*
G01X1770607Y661310D02*
X1770603Y661320D01*
G01X1770609Y661299D02*
X1770607Y661310D01*
G01X1770603Y664470D02*
X1770595Y664479D01*
G01X1770607Y664460D02*
X1770603Y664470D01*
G01X1770609Y664449D02*
X1770607Y664460D01*
G01X1770603Y667620D02*
X1770595Y667628D01*
G01X1770607Y667609D02*
X1770603Y667620D01*
G01X1770609Y667598D02*
X1770607Y667609D01*
G01X1770603Y670769D02*
X1770595Y670778D01*
G01X1770607Y670759D02*
X1770603Y670769D01*
G01X1770609Y670748D02*
X1770607Y670759D01*
G01X1784035Y648911D02*
X1784036Y648920D01*
G01X1788386Y692559D02*
Y693937D01*
G01Y687559D02*
Y688937D01*
G01Y682559D02*
Y683937D01*
G01Y677559D02*
Y678937D01*
G01Y672559D02*
Y673937D01*
G01X1770569Y666457D02*
X1770573Y666446D01*
G01X1770610Y651853D02*
Y651864D01*
G01Y655002D02*
Y655013D01*
G01Y658152D02*
Y658163D01*
G01Y661302D02*
Y661313D01*
G01Y664451D02*
Y664462D01*
G01Y667601D02*
Y667612D01*
G01Y670750D02*
Y670761D01*
G01X1784035Y673911D02*
X1784036Y673920D01*
G01X1784035Y678911D02*
X1784036Y678920D01*
G01X1784035Y683911D02*
X1784036Y683920D01*
G01X1784035Y688911D02*
X1784036Y688920D01*
G01X1784035Y693911D02*
X1784036Y693920D01*
G01X1785217Y673937D02*
Y672559D01*
G01Y678937D02*
Y677559D01*
G01Y683937D02*
Y682559D01*
G01Y688937D02*
Y687559D01*
G01Y693937D02*
Y692559D01*
G01X1784646Y671791D02*
Y649705D01*
G01X1784035Y692067D02*
Y694429D01*
G01Y687067D02*
Y689429D01*
G01Y682067D02*
Y684429D01*
G01Y677067D02*
Y679429D01*
G01Y672067D02*
Y674429D01*
G01X1783465Y670610D02*
Y650886D01*
G01X1783051Y674429D02*
Y672067D01*
G01Y679429D02*
Y677067D01*
G01Y684429D02*
Y682067D01*
G01Y689429D02*
Y687067D01*
G01Y694429D02*
Y692067D01*
G01X1780709Y748248D02*
Y671791D01*
G01X1779528Y747067D02*
Y670610D01*
G01X1771063Y751988D02*
Y672953D01*
G01X1770610Y669449D02*
Y670945D01*
G01Y666299D02*
Y667795D01*
G01Y663150D02*
Y664646D01*
G01Y660000D02*
Y661496D01*
G01Y656850D02*
Y658346D01*
G01Y653701D02*
Y655197D01*
G01Y650551D02*
Y652047D01*
G01X1770571Y650698D02*
Y650551D01*
G01Y652048D02*
Y651901D01*
G01Y656997D02*
Y656850D01*
G01Y653847D02*
Y653700D01*
G01Y655197D02*
Y655051D01*
G01Y660146D02*
Y660000D01*
G01Y661496D02*
Y661350D01*
G01Y658347D02*
Y658200D01*
G01Y666446D02*
Y666299D01*
G01Y663296D02*
Y663149D01*
G01Y664646D02*
Y664500D01*
G01Y669595D02*
Y669448D01*
G01Y670945D02*
Y670799D01*
G01Y667796D02*
Y667649D01*
G01X1769665Y669448D02*
Y669595D01*
G01Y670799D02*
Y670946D01*
G01Y667649D02*
Y667796D01*
G01Y666298D02*
Y666446D01*
G01Y663149D02*
Y663296D01*
G01Y664500D02*
Y664646D01*
G01Y659999D02*
Y660146D01*
G01Y661350D02*
Y661497D01*
G01Y658200D02*
Y658347D01*
G01Y656850D02*
Y656997D01*
G01Y653700D02*
Y653847D01*
G01Y655051D02*
Y655198D01*
G01Y650550D02*
Y650698D01*
G01Y651901D02*
Y652048D01*
G01X1769626Y652047D02*
Y650551D01*
G01Y655197D02*
Y653701D01*
G01Y661496D02*
Y660000D01*
G01Y658346D02*
Y656850D01*
G01Y664646D02*
Y663150D01*
G01Y670945D02*
Y669449D01*
G01Y667795D02*
Y666299D01*
G01X1768445Y651890D02*
Y650709D01*
G01Y658189D02*
Y657008D01*
G01Y655039D02*
Y653858D01*
G01Y661339D02*
Y660157D01*
G01Y667638D02*
Y666457D01*
G01Y664488D02*
Y663307D01*
G01Y670787D02*
Y669606D01*
G01X1768110Y672953D02*
Y648543D01*
G01X1767717D02*
Y672953D01*
G01X1770610Y669632D02*
Y669643D01*
G01Y666483D02*
Y666494D01*
G01Y663333D02*
Y663344D01*
G01Y660183D02*
Y660194D01*
G01Y657034D02*
Y657045D01*
G01Y653884D02*
Y653895D01*
G01Y650735D02*
Y650746D01*
G01X1783465Y670610D02*
X1784646Y671791D01*
G01X1779528Y670610D02*
X1780709Y671791D01*
G01X1783465Y650886D02*
X1784646Y649705D01*
G01X1779528Y650886D02*
X1780709Y649705D01*
G01X1769513Y669646D02*
X1769624Y669637D01*
G01Y660193D02*
X1769513Y660197D01*
G01X1769624Y653894D02*
X1769513Y653898D01*
G01X1769624Y663343D02*
X1769513Y663346D01*
G01X1784035Y694429D02*
X1783051D01*
G01X1783053Y693937D02*
X1788386D01*
G01Y693898D02*
X1784038D01*
G01X1788386Y692559D02*
X1783053D01*
G01X1783051Y692067D02*
X1784035D01*
G01Y689429D02*
X1783051D01*
G01X1783053Y688937D02*
X1788386D01*
G01Y688898D02*
X1784038D01*
G01X1788386Y687559D02*
X1783053D01*
G01X1783051Y687067D02*
X1784035D01*
G01Y684429D02*
X1783051D01*
G01X1783053Y683937D02*
X1788386D01*
G01Y683898D02*
X1784038D01*
G01X1788386Y682559D02*
X1783053D01*
G01X1783051Y682067D02*
X1784035D01*
G01Y679429D02*
X1783051D01*
G01X1783053Y678937D02*
X1788386D01*
G01Y678898D02*
X1784038D01*
G01X1788386Y677559D02*
X1783053D01*
G01X1783051Y677067D02*
X1784035D01*
G01Y674429D02*
X1783051D01*
G01X1783053Y673937D02*
X1788386D01*
G01Y673898D02*
X1784038D01*
G01X1771063Y672953D02*
X1767717D01*
G01X1788386Y672559D02*
X1783053D01*
G01X1783051Y672067D02*
X1784035D01*
G01X1780709Y671791D02*
X1784646D01*
G01X1770571Y670984D02*
X1769665D01*
G01X1770610Y670945D02*
X1769626D01*
G01X1779528Y670610D02*
X1783465D01*
G01X1769626Y669449D02*
X1770610D01*
G01X1769665Y669409D02*
X1770571D01*
G01Y667835D02*
X1769665D01*
G01X1770610Y667795D02*
X1769626D01*
G01Y666299D02*
X1770610D01*
G01X1769665Y666260D02*
X1770571D01*
G01Y664685D02*
X1769665D01*
G01X1770610Y664646D02*
X1769626D01*
G01X1768879Y663346D02*
X1768445D01*
G01X1769626Y663150D02*
X1770610D01*
G01X1769665Y663110D02*
X1770571D01*
G01Y661535D02*
X1769665D01*
G01X1770610Y661496D02*
X1769626D01*
G01X1768879Y660197D02*
X1768445D01*
G01X1769626Y660000D02*
X1770610D01*
G01X1769665Y659961D02*
X1770571D01*
G01Y658386D02*
X1769665D01*
G01X1770610Y658346D02*
X1769626D01*
G01Y656850D02*
X1770610D01*
G01X1769665Y656811D02*
X1770571D01*
G01Y655236D02*
X1769665D01*
G01X1770610Y655197D02*
X1769626D01*
G01X1768879Y653898D02*
X1768445D01*
G01X1769626Y653701D02*
X1770610D01*
G01X1769665Y653661D02*
X1770571D01*
G01Y652087D02*
X1769665D01*
G01X1770610Y652047D02*
X1769626D01*
G01X1783465Y650886D02*
X1779528D01*
G01X1769626Y650551D02*
X1770610D01*
G01X1769665Y650512D02*
X1770571D01*
G01X1784646Y649705D02*
X1780709D01*
G01X1784035Y649429D02*
X1783051D01*
G01X1783053Y648937D02*
X1788386D01*
G01Y648898D02*
X1784038D01*
G01X1771063Y648543D02*
X1767717D01*
G01X1783051Y694133D02*
X1784006Y694134D01*
G01X1784035Y692363D02*
X1783051Y692362D01*
G01Y689133D02*
X1784006Y689134D01*
G01X1784035Y687363D02*
X1783051Y687362D01*
G01Y684133D02*
X1784006Y684134D01*
G01X1784035Y682363D02*
X1783051Y682362D01*
G01Y679133D02*
X1784006Y679134D01*
G01X1784035Y677363D02*
X1783051Y677362D01*
G01Y674133D02*
X1784006Y674134D01*
G01X1784035Y672363D02*
X1783051Y672362D01*
G01Y649133D02*
X1784006Y649134D01*
G01X1784023Y698929D02*
X1784034Y698913D01*
G01X1783998Y698937D02*
X1784023Y698929D01*
G01Y703929D02*
X1784034Y703913D01*
G01X1783998Y703937D02*
X1784023Y703929D01*
G01Y708929D02*
X1784034Y708913D01*
G01X1783998Y708937D02*
X1784023Y708929D01*
G01Y713929D02*
X1784034Y713913D01*
G01X1783998Y713937D02*
X1784023Y713929D01*
G01Y718929D02*
X1784034Y718913D01*
G01X1783998Y718937D02*
X1784023Y718929D01*
G01Y723929D02*
X1784034Y723913D01*
G01X1783998Y723937D02*
X1784023Y723929D01*
G01Y728929D02*
X1784034Y728913D01*
G01X1783998Y728937D02*
X1784023Y728929D01*
G01Y733929D02*
X1784034Y733913D01*
G01X1783998Y733937D02*
X1784023Y733929D01*
G01Y738929D02*
X1784034Y738913D01*
G01X1783998Y738937D02*
X1784023Y738929D01*
G01Y743929D02*
X1784034Y743913D01*
G01X1783998Y743937D02*
X1784023Y743929D01*
G01X1784036Y698904D02*
X1784035Y698911D01*
G01X1784037Y698900D02*
X1784036Y698904D01*
G01X1784038Y698898D02*
X1784037Y698900D01*
G01X1784036Y703904D02*
X1784035Y703911D01*
G01X1784037Y703900D02*
X1784036Y703904D01*
G01X1784038Y703898D02*
X1784037Y703900D01*
G01X1784036Y708904D02*
X1784035Y708911D01*
G01X1784037Y708900D02*
X1784036Y708904D01*
G01X1784038Y708898D02*
X1784037Y708900D01*
G01X1784036Y713904D02*
X1784035Y713911D01*
G01X1784037Y713900D02*
X1784036Y713904D01*
G01X1784038Y713898D02*
X1784037Y713900D01*
G01X1784036Y718904D02*
X1784035Y718911D01*
G01X1784037Y718900D02*
X1784036Y718904D01*
G01X1784038Y718898D02*
X1784037Y718900D01*
G01X1784036Y723904D02*
X1784035Y723911D01*
G01X1784037Y723900D02*
X1784036Y723904D01*
G01X1784038Y723898D02*
X1784037Y723900D01*
G01X1784036Y728904D02*
X1784035Y728911D01*
G01X1784037Y728900D02*
X1784036Y728904D01*
G01X1784038Y728898D02*
X1784037Y728900D01*
G01X1784036Y733904D02*
X1784035Y733911D01*
G01X1784037Y733900D02*
X1784036Y733904D01*
G01X1784038Y733898D02*
X1784037Y733900D01*
G01X1784036Y738904D02*
X1784035Y738911D01*
G01X1784037Y738900D02*
X1784036Y738904D01*
G01X1784038Y738898D02*
X1784037Y738900D01*
G01X1784036Y743904D02*
X1784035Y743911D01*
G01X1784037Y743900D02*
X1784036Y743904D01*
G01X1784038Y743898D02*
X1784037Y743900D01*
G01X1784036Y742552D02*
X1784035Y742543D01*
G01X1784037Y742557D02*
X1784036Y742552D01*
G01X1784038Y742559D02*
X1784037Y742557D01*
G01X1784036Y737552D02*
X1784035Y737543D01*
G01X1784037Y737557D02*
X1784036Y737552D01*
G01X1784038Y737559D02*
X1784037Y737557D01*
G01X1784036Y732552D02*
X1784035Y732543D01*
G01X1784037Y732557D02*
X1784036Y732552D01*
G01X1784038Y732559D02*
X1784037Y732557D01*
G01X1784036Y727552D02*
X1784035Y727543D01*
G01X1784037Y727557D02*
X1784036Y727552D01*
G01X1784038Y727559D02*
X1784037Y727557D01*
G01X1784036Y722552D02*
X1784035Y722543D01*
G01X1784037Y722557D02*
X1784036Y722552D01*
G01X1784038Y722559D02*
X1784037Y722557D01*
G01X1784036Y717552D02*
X1784035Y717543D01*
G01X1784037Y717557D02*
X1784036Y717552D01*
G01X1784038Y717559D02*
X1784037Y717557D01*
G01X1784036Y712552D02*
X1784035Y712543D01*
G01X1784037Y712557D02*
X1784036Y712552D01*
G01X1784038Y712559D02*
X1784037Y712557D01*
G01X1784036Y707552D02*
X1784035Y707543D01*
G01X1784037Y707557D02*
X1784036Y707552D01*
G01X1784038Y707559D02*
X1784037Y707557D01*
G01X1784036Y702552D02*
X1784035Y702543D01*
G01X1784037Y702557D02*
X1784036Y702552D01*
G01X1784038Y702559D02*
X1784037Y702557D01*
G01X1784036Y697552D02*
X1784035Y697543D01*
G01X1784037Y697557D02*
X1784036Y697552D01*
G01X1784038Y697559D02*
X1784037Y697557D01*
G01X1783051Y698944D02*
Y698954D01*
G01X1783052Y698939D02*
X1783051Y698944D01*
G01X1783053Y698937D02*
X1783052Y698939D01*
G01X1783051Y703944D02*
Y703954D01*
G01X1783052Y703939D02*
X1783051Y703944D01*
G01X1783053Y703937D02*
X1783052Y703939D01*
G01X1783051Y708944D02*
Y708954D01*
G01X1783052Y708939D02*
X1783051Y708944D01*
G01X1783053Y708937D02*
X1783052Y708939D01*
G01X1783051Y713944D02*
Y713954D01*
G01X1783052Y713939D02*
X1783051Y713944D01*
G01X1783053Y713937D02*
X1783052Y713939D01*
G01X1783051Y718944D02*
Y718954D01*
G01X1783052Y718939D02*
X1783051Y718944D01*
G01X1783053Y718937D02*
X1783052Y718939D01*
G01X1783051Y723944D02*
Y723954D01*
G01X1783052Y723939D02*
X1783051Y723944D01*
G01X1783053Y723937D02*
X1783052Y723939D01*
G01X1783051Y728944D02*
Y728954D01*
G01X1783052Y728939D02*
X1783051Y728944D01*
G01X1783053Y728937D02*
X1783052Y728939D01*
G01X1783051Y733944D02*
Y733954D01*
G01X1783052Y733939D02*
X1783051Y733944D01*
G01X1783053Y733937D02*
X1783052Y733939D01*
G01X1783051Y738944D02*
Y738954D01*
G01X1783052Y738939D02*
X1783051Y738944D01*
G01X1783053Y738937D02*
X1783052Y738939D01*
G01X1784028Y699081D02*
X1784035Y699055D01*
G01X1784018Y699107D02*
X1784028Y699081D01*
G01X1784006Y699134D02*
X1784018Y699107D01*
G01X1784028Y704081D02*
X1784035Y704055D01*
G01X1784018Y704107D02*
X1784028Y704081D01*
G01X1784006Y704134D02*
X1784018Y704107D01*
G01X1784028Y709081D02*
X1784035Y709055D01*
G01X1784018Y709107D02*
X1784028Y709081D01*
G01X1784006Y709134D02*
X1784018Y709107D01*
G01X1784028Y714081D02*
X1784035Y714055D01*
G01X1784018Y714107D02*
X1784028Y714081D01*
G01X1784006Y714134D02*
X1784018Y714107D01*
G01X1784028Y719081D02*
X1784035Y719055D01*
G01X1784018Y719107D02*
X1784028Y719081D01*
G01X1784006Y719134D02*
X1784018Y719107D01*
G01X1784028Y724081D02*
X1784035Y724055D01*
G01X1784018Y724107D02*
X1784028Y724081D01*
G01X1784006Y724134D02*
X1784018Y724107D01*
G01X1784028Y729081D02*
X1784035Y729055D01*
G01X1784018Y729107D02*
X1784028Y729081D01*
G01X1784006Y729134D02*
X1784018Y729107D01*
G01X1784002Y699035D02*
X1784006Y699134D01*
G01X1783997Y698963D02*
X1784002Y699035D01*
G01X1783999Y698937D02*
X1783997Y698963D01*
G01X1784002Y704035D02*
X1784006Y704134D01*
G01X1783997Y703963D02*
X1784002Y704035D01*
G01X1783999Y703937D02*
X1783997Y703963D01*
G01X1784002Y709035D02*
X1784006Y709134D01*
G01X1783997Y708963D02*
X1784002Y709035D01*
G01X1783999Y708937D02*
X1783997Y708963D01*
G01X1784002Y714035D02*
X1784006Y714134D01*
G01X1783997Y713963D02*
X1784002Y714035D01*
G01X1783999Y713937D02*
X1783997Y713963D01*
G01X1784002Y719035D02*
X1784006Y719134D01*
G01X1783997Y718963D02*
X1784002Y719035D01*
G01X1783999Y718937D02*
X1783997Y718963D01*
G01X1784002Y724035D02*
X1784006Y724134D01*
G01X1783997Y723963D02*
X1784002Y724035D01*
G01X1783999Y723937D02*
X1783997Y723963D01*
G01X1784002Y729035D02*
X1784006Y729134D01*
G01X1783997Y728963D02*
X1784002Y729035D01*
G01X1783999Y728937D02*
X1783997Y728963D01*
G01X1784002Y734035D02*
X1784006Y734134D01*
G01X1783997Y733963D02*
X1784002Y734035D01*
G01X1783999Y733937D02*
X1783997Y733963D01*
G01X1784002Y739035D02*
X1784006Y739134D01*
G01X1783997Y738963D02*
X1784002Y739035D01*
G01X1783999Y738937D02*
X1783997Y738963D01*
G01X1784002Y744035D02*
X1784006Y744134D01*
G01X1783997Y743963D02*
X1784002Y744035D01*
G01X1783999Y743937D02*
X1783997Y743963D01*
G01X1783052Y742557D02*
X1783053Y742559D01*
G01X1783051Y742552D02*
X1783052Y742557D01*
G01X1783051Y742543D02*
Y742552D01*
G01X1783052Y737557D02*
X1783053Y737559D01*
G01X1783051Y737552D02*
X1783052Y737557D01*
G01X1783051Y737543D02*
Y737552D01*
G01X1783052Y732557D02*
X1783053Y732559D01*
G01X1783051Y732552D02*
X1783052Y732557D01*
G01X1783051Y732543D02*
Y732552D01*
G01X1783052Y727557D02*
X1783053Y727559D01*
G01X1783051Y727552D02*
X1783052Y727557D01*
G01X1783051Y727543D02*
Y727552D01*
G01X1783052Y722557D02*
X1783053Y722559D01*
G01X1783051Y722552D02*
X1783052Y722557D01*
G01X1783051Y722543D02*
Y722552D01*
G01X1783052Y717557D02*
X1783053Y717559D01*
G01X1783051Y717552D02*
X1783052Y717557D01*
G01X1783051Y717543D02*
Y717552D01*
G01X1783052Y712557D02*
X1783053Y712559D01*
G01X1783051Y712552D02*
X1783052Y712557D01*
G01X1783051Y712543D02*
Y712552D01*
G01X1783052Y707557D02*
X1783053Y707559D01*
G01X1783051Y707552D02*
X1783052Y707557D01*
G01X1783051Y707543D02*
Y707552D01*
G01X1783052Y702557D02*
X1783053Y702559D01*
G01X1783051Y702552D02*
X1783052Y702557D01*
G01X1783051Y702543D02*
Y702552D01*
G01X1783052Y697557D02*
X1783053Y697559D01*
G01X1783051Y697552D02*
X1783052Y697557D01*
G01X1783051Y697543D02*
Y697552D01*
G01Y743944D02*
Y743954D01*
G01X1783052Y743939D02*
X1783051Y743944D01*
G01X1783053Y743937D02*
X1783052Y743939D01*
G01X1784028Y734081D02*
X1784035Y734055D01*
G01X1784018Y734107D02*
X1784028Y734081D01*
G01X1784006Y734134D02*
X1784018Y734107D01*
G01X1784028Y739081D02*
X1784035Y739055D01*
G01X1784018Y739107D02*
X1784028Y739081D01*
G01X1784006Y739134D02*
X1784018Y739107D01*
G01X1784028Y744081D02*
X1784035Y744055D01*
G01X1784018Y744107D02*
X1784028Y744081D01*
G01X1784006Y744134D02*
X1784018Y744107D01*
G01Y698932D02*
X1783999Y698937D01*
G01X1784033Y698918D02*
X1784018Y698932D01*
G01X1784038Y698898D02*
X1784033Y698918D01*
G01X1784018Y703932D02*
X1783999Y703937D01*
G01X1784033Y703918D02*
X1784018Y703932D01*
G01X1784038Y703898D02*
X1784033Y703918D01*
G01X1784018Y708932D02*
X1783999Y708937D01*
G01X1784033Y708918D02*
X1784018Y708932D01*
G01X1784038Y708898D02*
X1784033Y708918D01*
G01X1784018Y713932D02*
X1783999Y713937D01*
G01X1784033Y713918D02*
X1784018Y713932D01*
G01X1784038Y713898D02*
X1784033Y713918D01*
G01X1784018Y718932D02*
X1783999Y718937D01*
G01X1784033Y718918D02*
X1784018Y718932D01*
G01X1784038Y718898D02*
X1784033Y718918D01*
G01X1784018Y723932D02*
X1783999Y723937D01*
G01X1784033Y723918D02*
X1784018Y723932D01*
G01X1784038Y723898D02*
X1784033Y723918D01*
G01X1784018Y728932D02*
X1783999Y728937D01*
G01X1784033Y728918D02*
X1784018Y728932D01*
G01X1784038Y728898D02*
X1784033Y728918D01*
G01X1784018Y733932D02*
X1783999Y733937D01*
G01X1784033Y733918D02*
X1784018Y733932D01*
G01X1784038Y733898D02*
X1784033Y733918D01*
G01X1784018Y738932D02*
X1783999Y738937D01*
G01X1784033Y738918D02*
X1784018Y738932D01*
G01X1784038Y738898D02*
X1784033Y738918D01*
G01X1784018Y743932D02*
X1783999Y743937D01*
G01X1784033Y743918D02*
X1784018Y743932D01*
G01X1784038Y743898D02*
X1784033Y743918D01*
G01X1788386Y742559D02*
Y743937D01*
G01Y737559D02*
Y738937D01*
G01Y732559D02*
Y733937D01*
G01Y727559D02*
Y728937D01*
G01Y722559D02*
Y723937D01*
G01Y717559D02*
Y718937D01*
G01Y712559D02*
Y713937D01*
G01Y707559D02*
Y708937D01*
G01Y702559D02*
Y703937D01*
G01Y697559D02*
Y698937D01*
G01X1784035Y698911D02*
X1784036Y698920D01*
G01X1784035Y703911D02*
X1784036Y703920D01*
G01X1784035Y708911D02*
X1784036Y708920D01*
G01X1784035Y713911D02*
X1784036Y713920D01*
G01X1784035Y718911D02*
X1784036Y718920D01*
G01X1784035Y723911D02*
X1784036Y723920D01*
G01X1784035Y728911D02*
X1784036Y728920D01*
G01X1784035Y733911D02*
X1784036Y733920D01*
G01X1784035Y738911D02*
X1784036Y738920D01*
G01X1784035Y743911D02*
X1784036Y743920D01*
G01X1785217Y698937D02*
Y697559D01*
G01Y703937D02*
Y702559D01*
G01Y708937D02*
Y707559D01*
G01Y713937D02*
Y712559D01*
G01Y718937D02*
Y717559D01*
G01Y723937D02*
Y722559D01*
G01Y728937D02*
Y727559D01*
G01Y733937D02*
Y732559D01*
G01Y738937D02*
Y737559D01*
G01Y743937D02*
Y742559D01*
G01X1784035Y742067D02*
Y744429D01*
G01Y737067D02*
Y739429D01*
G01Y732067D02*
Y734429D01*
G01Y727067D02*
Y729429D01*
G01Y722067D02*
Y724429D01*
G01Y717067D02*
Y719429D01*
G01Y712067D02*
Y714429D01*
G01Y707067D02*
Y709429D01*
G01Y702067D02*
Y704429D01*
G01Y697067D02*
Y699429D01*
G01X1783051D02*
Y697067D01*
G01Y704429D02*
Y702067D01*
G01Y709429D02*
Y707067D01*
G01Y714429D02*
Y712067D01*
G01Y719429D02*
Y717067D01*
G01Y724429D02*
Y722067D01*
G01Y729429D02*
Y727067D01*
G01Y734429D02*
Y732067D01*
G01Y739429D02*
Y737067D01*
G01Y744429D02*
Y742067D01*
G01X1784035Y744429D02*
X1783051D01*
G01X1783053Y743937D02*
X1788386D01*
G01Y743898D02*
X1784038D01*
G01X1788386Y742559D02*
X1783053D01*
G01X1783051Y742067D02*
X1784035D01*
G01Y739429D02*
X1783051D01*
G01X1783053Y738937D02*
X1788386D01*
G01Y738898D02*
X1784038D01*
G01X1788386Y737559D02*
X1783053D01*
G01X1783051Y737067D02*
X1784035D01*
G01Y734429D02*
X1783051D01*
G01X1783053Y733937D02*
X1788386D01*
G01Y733898D02*
X1784038D01*
G01X1788386Y732559D02*
X1783053D01*
G01X1783051Y732067D02*
X1784035D01*
G01Y729429D02*
X1783051D01*
G01X1783053Y728937D02*
X1788386D01*
G01Y728898D02*
X1784038D01*
G01X1788386Y727559D02*
X1783053D01*
G01X1783051Y727067D02*
X1784035D01*
G01Y724429D02*
X1783051D01*
G01X1783053Y723937D02*
X1788386D01*
G01Y723898D02*
X1784038D01*
G01X1788386Y722559D02*
X1783053D01*
G01X1783051Y722067D02*
X1784035D01*
G01Y719429D02*
X1783051D01*
G01X1783053Y718937D02*
X1788386D01*
G01Y718898D02*
X1784038D01*
G01X1788386Y717559D02*
X1783053D01*
G01X1783051Y717067D02*
X1784035D01*
G01Y714429D02*
X1783051D01*
G01X1783053Y713937D02*
X1788386D01*
G01Y713898D02*
X1784038D01*
G01X1788386Y712559D02*
X1783053D01*
G01X1783051Y712067D02*
X1784035D01*
G01Y709429D02*
X1783051D01*
G01X1783053Y708937D02*
X1788386D01*
G01Y708898D02*
X1784038D01*
G01X1788386Y707559D02*
X1783053D01*
G01X1783051Y707067D02*
X1784035D01*
G01X1783051Y744133D02*
X1784006Y744134D01*
G01X1784035Y742363D02*
X1783051Y742362D01*
G01Y739133D02*
X1784006Y739134D01*
G01X1784035Y737363D02*
X1783051Y737362D01*
G01Y734133D02*
X1784006Y734134D01*
G01X1784035Y732363D02*
X1783051Y732362D01*
G01Y729133D02*
X1784006Y729134D01*
G01X1784035Y727363D02*
X1783051Y727362D01*
G01Y724133D02*
X1784006Y724134D01*
G01X1784035Y722363D02*
X1783051Y722362D01*
G01Y719133D02*
X1784006Y719134D01*
G01X1784035Y717363D02*
X1783051Y717362D01*
G01Y714133D02*
X1784006Y714134D01*
G01X1784035Y712363D02*
X1783051Y712362D01*
G01Y709133D02*
X1784006Y709134D01*
G01X1784035Y707363D02*
X1783051Y707362D01*
G01X1784035Y704429D02*
X1783051D01*
G01X1783053Y703937D02*
X1788386D01*
G01Y703898D02*
X1784038D01*
G01X1788386Y702559D02*
X1783053D01*
G01X1783051Y702067D02*
X1784035D01*
G01Y699429D02*
X1783051D01*
G01X1783053Y698937D02*
X1788386D01*
G01Y698898D02*
X1784038D01*
G01X1788386Y697559D02*
X1783053D01*
G01X1783051Y697067D02*
X1784035D01*
G01X1783051Y704133D02*
X1784006Y704134D01*
G01X1784035Y702363D02*
X1783051Y702362D01*
G01Y699133D02*
X1784006Y699134D01*
G01X1784035Y697363D02*
X1783051Y697362D01*
G01X1782480Y769429D02*
G03X1781890Y770020I-591J0D01*
G01X1775197D02*
G03X1774606Y769429I0J-591D01*
G01X1777362Y768248D02*
G03Y766280I0J-984D01*
G01X1779724D02*
G03Y768248I0J984D01*
G01X1789370Y768839D02*
G03X1787402Y770807I-1968J0D01*
G01X1769685D02*
G03X1767717Y768839I0J-1968D01*
G01X1775984Y760335D02*
G03X1774803Y759154I0J-1181D01*
G01X1782283D02*
G03X1781102Y760335I-1181J0D01*
G01X1780433Y755059D02*
G03I-1890J0D01*
G01X1780906D02*
G03I-2363J0D01*
G01X1789370Y753091D02*
Y768839D01*
G01X1782480Y763327D02*
Y769429D01*
G01X1782283Y759154D02*
Y750610D01*
G01X1779724Y755650D02*
Y753957D01*
G01X1777362D02*
Y755650D01*
G01X1774803Y750610D02*
Y759154D01*
G01X1774606Y763327D02*
Y769429D01*
G01X1767717Y768839D02*
Y753091D01*
G01X1777362Y755650D02*
X1775052Y759879D01*
G01X1779724Y753957D02*
X1781028Y751988D01*
G01X1776059D02*
X1777362Y753957D01*
G01X1782035Y759879D02*
X1779724Y755650D01*
G01X1789370Y753091D02*
X1786024Y749744D01*
G01X1779528Y747067D02*
X1780709Y748248D01*
G01X1772835D02*
X1774016Y747067D01*
G01X1767717Y753091D02*
X1771063Y749744D01*
G01X1787402Y770807D02*
X1769685D01*
G01X1781890Y770020D02*
X1775197D01*
G01X1779724Y768248D02*
X1777362D01*
G01Y766280D02*
X1779724D01*
G01X1782480Y764902D02*
X1774606D01*
G01Y763327D02*
X1782480D01*
G01X1789370Y760374D02*
X1767717D01*
G01X1775984Y760335D02*
X1781102D01*
G01X1777362Y755650D02*
X1779724D01*
G01X1777362Y753957D02*
X1779724D01*
G01X1771063Y751988D02*
X1785433D01*
G01X1771063Y750610D02*
X1774803D01*
G01X1785433D02*
X1782283D01*
G01X1771063Y749744D02*
X1786024D01*
G01X1772835Y748248D02*
X1780709D01*
G01X1774016Y747067D02*
X1779528D01*
G01X1781028Y831641D02*
G03X1814838I16905J-13531D01*
G01X1807914Y844772D02*
G03X1814838Y831641I37663J11469D01*
G01X1781028D02*
G03X1787953Y844772I-30737J24602D01*
G01X1807913D02*
G03X1814839Y831641I37662J11473D01*
G01X1781028D02*
G03X1814839I16906J-13531D01*
G01X1781028D02*
G03X1787953Y844772I-30737J24602D01*
G01X1807914D02*
G03X1787953I-9980J-3039D01*
G01X1807913D02*
G03X1787953I-9980J-3040D01*
G01X1784036Y1080308D02*
X1784035Y1080299D01*
G01X1784037Y1080313D02*
X1784036Y1080308D01*
G01X1784038Y1080315D02*
X1784037Y1080313D01*
G01X1784036Y1075308D02*
X1784035Y1075299D01*
G01X1784037Y1075313D02*
X1784036Y1075308D01*
G01X1784038Y1075315D02*
X1784037Y1075313D01*
G01X1784036Y1070308D02*
X1784035Y1070299D01*
G01X1784037Y1070313D02*
X1784036Y1070308D01*
G01X1784038Y1070315D02*
X1784037Y1070313D01*
G01X1784023Y1071685D02*
X1784034Y1071669D01*
G01X1783998Y1071693D02*
X1784023Y1071685D01*
G01Y1076685D02*
X1784034Y1076669D01*
G01X1783998Y1076693D02*
X1784023Y1076685D01*
G01Y1081685D02*
X1784034Y1081669D01*
G01X1783998Y1081693D02*
X1784023Y1081685D01*
G01X1783052Y1080313D02*
X1783053Y1080315D01*
G01X1783051Y1080308D02*
X1783052Y1080313D01*
G01X1783051Y1080299D02*
Y1080308D01*
G01X1783052Y1075313D02*
X1783053Y1075315D01*
G01X1783051Y1075308D02*
X1783052Y1075313D01*
G01X1783051Y1075299D02*
Y1075308D01*
G01X1783052Y1070313D02*
X1783053Y1070315D01*
G01X1783051Y1070308D02*
X1783052Y1070313D01*
G01X1783051Y1070299D02*
Y1070308D01*
G01X1784002Y1071791D02*
X1784006Y1071890D01*
G01X1783997Y1071719D02*
X1784002Y1071791D01*
G01X1783999Y1071693D02*
X1783997Y1071719D01*
G01X1784002Y1076791D02*
X1784006Y1076890D01*
G01X1783997Y1076719D02*
X1784002Y1076791D01*
G01X1783999Y1076693D02*
X1783997Y1076719D01*
G01X1784002Y1081791D02*
X1784006Y1081890D01*
G01X1783997Y1081719D02*
X1784002Y1081791D01*
G01X1783999Y1081693D02*
X1783997Y1081719D01*
G01X1784036Y1071660D02*
X1784035Y1071667D01*
G01X1784037Y1071656D02*
X1784036Y1071660D01*
G01X1784038Y1071654D02*
X1784037Y1071656D01*
G01X1784036Y1076660D02*
X1784035Y1076667D01*
G01X1784037Y1076656D02*
X1784036Y1076660D01*
G01X1784038Y1076654D02*
X1784037Y1076656D01*
G01X1784036Y1081660D02*
X1784035Y1081667D01*
G01X1784037Y1081656D02*
X1784036Y1081660D01*
G01X1784038Y1081654D02*
X1784037Y1081656D01*
G01X1783051Y1071700D02*
Y1071709D01*
G01X1783052Y1071695D02*
X1783051Y1071700D01*
G01X1783053Y1071693D02*
X1783052Y1071695D01*
G01X1783051Y1076700D02*
Y1076709D01*
G01X1783052Y1076695D02*
X1783051Y1076700D01*
G01X1783053Y1076693D02*
X1783052Y1076695D01*
G01X1783051Y1081700D02*
Y1081709D01*
G01X1783052Y1081695D02*
X1783051Y1081700D01*
G01X1783053Y1081693D02*
X1783052Y1081695D01*
G01X1784028Y1071837D02*
X1784035Y1071811D01*
G01X1784018Y1071863D02*
X1784028Y1071837D01*
G01X1784006Y1071890D02*
X1784018Y1071863D01*
G01X1784028Y1076837D02*
X1784035Y1076811D01*
G01X1784018Y1076863D02*
X1784028Y1076837D01*
G01X1784006Y1076890D02*
X1784018Y1076863D01*
G01X1784028Y1081837D02*
X1784035Y1081811D01*
G01X1784018Y1081863D02*
X1784028Y1081837D01*
G01X1784006Y1081890D02*
X1784018Y1081863D01*
G01Y1071688D02*
X1783999Y1071693D01*
G01X1784033Y1071674D02*
X1784018Y1071688D01*
G01X1784038Y1071654D02*
X1784033Y1071674D01*
G01X1784018Y1076688D02*
X1783999Y1076693D01*
G01X1784033Y1076674D02*
X1784018Y1076688D01*
G01X1784038Y1076654D02*
X1784033Y1076674D01*
G01X1784018Y1081688D02*
X1783999Y1081693D01*
G01X1784033Y1081674D02*
X1784018Y1081688D01*
G01X1784038Y1081654D02*
X1784033Y1081674D01*
G01X1774606Y1044823D02*
G03X1775197Y1044232I591J0D01*
G01X1781890D02*
G03X1782480Y1044823I-1J591D01*
G01X1779724Y1046004D02*
G03Y1047972I0J984D01*
G01X1777362D02*
G03Y1046004I0J-984D01*
G01X1779646Y1059193D02*
G03I-1103J0D01*
G01X1781102Y1053917D02*
G03X1782283Y1055098I0J1181D01*
G01X1774803D02*
G03X1775984Y1053917I1181J0D01*
G01X1780118Y1059193D02*
G03I-1575J0D01*
G01X1767717Y1045413D02*
G03X1769685Y1043445I1968J0D01*
G01X1787402D02*
G03X1789370Y1045413I0J1968D01*
G01X1779724Y1058602D02*
X1782035Y1054373D01*
G01X1777362Y1060295D02*
X1776059Y1062264D01*
G01X1789370Y1045413D02*
Y1061161D01*
G01X1788386Y1080315D02*
Y1081693D01*
G01Y1075315D02*
Y1076693D01*
G01Y1070315D02*
Y1071693D01*
G01X1786024Y1064508D02*
X1789370Y1061161D01*
G01X1779528Y1067185D02*
X1780709Y1066004D01*
G01X1784035Y1071667D02*
X1784036Y1071676D01*
G01X1784035Y1076667D02*
X1784036Y1076676D01*
G01X1784035Y1081667D02*
X1784036Y1081676D01*
G01X1786024Y1202500D02*
Y1064508D01*
G01X1785433Y1204744D02*
Y1062264D01*
G01X1785217Y1071693D02*
Y1070315D01*
G01Y1076693D02*
Y1075315D01*
G01Y1081693D02*
Y1080315D01*
G01X1784035Y1079823D02*
Y1082185D01*
G01Y1074823D02*
Y1077185D01*
G01Y1069823D02*
Y1072185D01*
G01Y1076667D02*
Y1076811D01*
G01Y1071667D02*
Y1071811D01*
G01Y1081667D02*
Y1081811D01*
G01X1783051Y1072185D02*
Y1069823D01*
G01Y1077185D02*
Y1074823D01*
G01Y1082185D02*
Y1079823D01*
G01X1782480Y1050925D02*
Y1044823D01*
G01X1782283Y1063642D02*
Y1055098D01*
G01X1780709Y1102461D02*
Y1066004D01*
G01X1779724Y1060295D02*
Y1058602D01*
G01X1779528Y1103642D02*
Y1067185D01*
G01X1777362Y1058602D02*
Y1060295D01*
G01X1774803Y1055098D02*
Y1063642D01*
G01X1774606Y1050925D02*
Y1044823D01*
G01X1774016Y1067185D02*
Y1199823D01*
G01X1772835Y1066004D02*
Y1201004D01*
G01X1771063Y1101299D02*
Y1062264D01*
G01X1767717Y1061161D02*
Y1045413D01*
G01X1775052Y1054373D02*
X1777362Y1058602D01*
G01X1781028Y1062264D02*
X1779724Y1060295D01*
G01X1784035Y1082185D02*
X1783051D01*
G01X1783053Y1081693D02*
X1788386D01*
G01Y1081654D02*
X1784038D01*
G01X1788386Y1080315D02*
X1783053D01*
G01X1783051Y1079823D02*
X1784035D01*
G01Y1077185D02*
X1783051D01*
G01X1783053Y1076693D02*
X1788386D01*
G01Y1076654D02*
X1784038D01*
G01X1788386Y1075315D02*
X1783053D01*
G01X1783051Y1074823D02*
X1784035D01*
G01Y1072185D02*
X1783051D01*
G01X1783053Y1071693D02*
X1788386D01*
G01Y1071654D02*
X1784038D01*
G01X1788386Y1070315D02*
X1783053D01*
G01X1783051Y1069823D02*
X1784035D01*
G01X1779528Y1067185D02*
X1774016D01*
G01X1780709Y1066004D02*
X1772835D01*
G01X1786024Y1064508D02*
X1771063D01*
G01X1783051Y1081889D02*
X1784006Y1081890D01*
G01X1784035Y1080119D02*
X1783051Y1080118D01*
G01Y1076889D02*
X1784006Y1076890D01*
G01X1784035Y1075119D02*
X1783051Y1075118D01*
G01Y1071889D02*
X1784006Y1071890D01*
G01X1784035Y1070119D02*
X1783051Y1070118D01*
G01X1774016Y1067185D02*
X1772835Y1066004D01*
G01X1771063Y1064508D02*
X1767717Y1061161D01*
G01X1782283Y1063642D02*
X1785433D01*
G01X1774803D02*
X1771063D01*
G01Y1062264D02*
X1785433D01*
G01X1779724Y1060295D02*
X1777362D01*
G01X1779724Y1058602D02*
X1777362D01*
G01X1781102Y1053917D02*
X1775984D01*
G01X1789370Y1053878D02*
X1767717D01*
G01X1782480Y1050925D02*
X1774606D01*
G01Y1049350D02*
X1782480D01*
G01X1779724Y1047972D02*
X1777362D01*
G01Y1046004D02*
X1779724D01*
G01X1781890Y1044232D02*
X1775197D01*
G01X1787402Y1043445D02*
X1769685D01*
G01X1770581Y1122364D02*
X1770569Y1122362D01*
G01X1770592Y1122369D02*
X1770581Y1122364D01*
G01Y1119215D02*
X1770569Y1119213D01*
G01X1770592Y1119220D02*
X1770581Y1119215D01*
G01Y1116065D02*
X1770569Y1116063D01*
G01X1770592Y1116070D02*
X1770581Y1116065D01*
G01Y1112915D02*
X1770569Y1112913D01*
G01X1770592Y1112920D02*
X1770581Y1112915D01*
G01Y1109766D02*
X1770569Y1109764D01*
G01X1770592Y1109771D02*
X1770581Y1109766D01*
G01Y1106616D02*
X1770569Y1106614D01*
G01X1770592Y1106621D02*
X1770581Y1106616D01*
G01Y1103467D02*
X1770569Y1103465D01*
G01X1770592Y1103472D02*
X1770581Y1103467D01*
G01X1770604Y1103484D02*
X1770609Y1103504D01*
G01X1770589Y1103470D02*
X1770604Y1103484D01*
G01X1770569Y1103465D02*
X1770589Y1103470D01*
G01X1769665Y1123548D02*
Y1123555D01*
G01Y1123544D02*
Y1123548D01*
G01X1769663Y1123543D02*
X1769665Y1123544D01*
G01Y1120399D02*
Y1120405D01*
G01Y1120395D02*
Y1120399D01*
G01X1769663Y1120394D02*
X1769665Y1120395D01*
G01Y1117249D02*
Y1117256D01*
G01Y1117245D02*
Y1117249D01*
G01X1769663Y1117244D02*
X1769665Y1117245D01*
G01X1769627Y1123524D02*
X1769626Y1123518D01*
G01X1769628Y1123530D02*
X1769627Y1123524D01*
G01X1769631Y1123536D02*
X1769628Y1123530D01*
G01X1769635Y1123541D02*
X1769631Y1123536D01*
G01X1769640Y1123546D02*
X1769635Y1123541D01*
G01X1769645Y1123550D02*
X1769640Y1123546D01*
G01X1769627Y1120374D02*
X1769626Y1120368D01*
G01X1769628Y1120381D02*
X1769627Y1120374D01*
G01X1769631Y1120386D02*
X1769628Y1120381D01*
G01X1769635Y1120392D02*
X1769631Y1120386D01*
G01X1769640Y1120396D02*
X1769635Y1120392D01*
G01X1769645Y1120400D02*
X1769640Y1120396D01*
G01X1769627Y1117225D02*
X1769626Y1117219D01*
G01X1769628Y1117231D02*
X1769627Y1117225D01*
G01X1769631Y1117237D02*
X1769628Y1117231D01*
G01X1769635Y1117242D02*
X1769631Y1117237D01*
G01X1769640Y1117246D02*
X1769635Y1117242D01*
G01X1769645Y1117250D02*
X1769640Y1117246D01*
G01X1769627Y1114075D02*
X1769626Y1114069D01*
G01X1769628Y1114081D02*
X1769627Y1114075D01*
G01X1769631Y1114087D02*
X1769628Y1114081D01*
G01X1769635Y1114093D02*
X1769631Y1114087D01*
G01X1769640Y1114097D02*
X1769635Y1114093D01*
G01X1769645Y1114101D02*
X1769640Y1114097D01*
G01X1769627Y1110926D02*
X1769626Y1110919D01*
G01X1769628Y1110932D02*
X1769627Y1110926D01*
G01X1769631Y1110937D02*
X1769628Y1110932D01*
G01X1769635Y1110943D02*
X1769631Y1110937D01*
G01X1769640Y1110947D02*
X1769635Y1110943D01*
G01X1769645Y1110951D02*
X1769640Y1110947D01*
G01X1769627Y1107776D02*
X1769626Y1107770D01*
G01X1769628Y1107782D02*
X1769627Y1107776D01*
G01X1769631Y1107788D02*
X1769628Y1107782D01*
G01X1769635Y1107793D02*
X1769631Y1107788D01*
G01X1769640Y1107798D02*
X1769635Y1107793D01*
G01X1769645Y1107802D02*
X1769640Y1107798D01*
G01X1769627Y1104626D02*
X1769626Y1104620D01*
G01X1769628Y1104633D02*
X1769627Y1104626D01*
G01X1769631Y1104638D02*
X1769628Y1104633D01*
G01X1769635Y1104644D02*
X1769631Y1104638D01*
G01X1769640Y1104648D02*
X1769635Y1104644D01*
G01X1769645Y1104652D02*
X1769640Y1104648D01*
G01X1769629Y1104626D02*
X1769624Y1104606D01*
G01X1769643Y1104641D02*
X1769629Y1104626D01*
G01X1769663Y1104646D02*
X1769643Y1104641D01*
G01X1769629Y1107776D02*
X1769624Y1107756D01*
G01X1769643Y1107790D02*
X1769629Y1107776D01*
G01X1769663Y1107795D02*
X1769643Y1107790D01*
G01X1769629Y1110925D02*
X1769624Y1110906D01*
G01X1769643Y1110940D02*
X1769629Y1110925D01*
G01X1769663Y1110945D02*
X1769643Y1110940D01*
G01X1769629Y1114075D02*
X1769624Y1114055D01*
G01X1769643Y1114089D02*
X1769629Y1114075D01*
G01X1769663Y1114094D02*
X1769643Y1114089D01*
G01X1769629Y1117224D02*
X1769624Y1117205D01*
G01X1769643Y1117239D02*
X1769629Y1117224D01*
G01X1769663Y1117244D02*
X1769643Y1117239D01*
G01X1769629Y1120374D02*
X1769624Y1120354D01*
G01X1769643Y1120389D02*
X1769629Y1120374D01*
G01X1769663Y1120394D02*
X1769643Y1120389D01*
G01X1769629Y1123524D02*
X1769624Y1123504D01*
G01X1769643Y1123538D02*
X1769629Y1123524D01*
G01X1769663Y1123543D02*
X1769643Y1123538D01*
G01X1770604Y1106634D02*
X1770609Y1106654D01*
G01X1770589Y1106620D02*
X1770604Y1106634D01*
G01X1770569Y1106614D02*
X1770589Y1106620D01*
G01X1770604Y1109783D02*
X1770609Y1109803D01*
G01X1770589Y1109769D02*
X1770604Y1109783D01*
G01X1770569Y1109764D02*
X1770589Y1109769D01*
G01X1770604Y1112933D02*
X1770609Y1112953D01*
G01X1770589Y1112919D02*
X1770604Y1112933D01*
G01X1770569Y1112913D02*
X1770589Y1112919D01*
G01X1770604Y1116083D02*
X1770609Y1116102D01*
G01X1770589Y1116069D02*
X1770604Y1116083D01*
G01X1770569Y1116063D02*
X1770589Y1116069D01*
G01X1770604Y1119232D02*
X1770609Y1119252D01*
G01X1770589Y1119218D02*
X1770604Y1119232D01*
G01X1770569Y1119213D02*
X1770589Y1119218D01*
G01X1770604Y1122382D02*
X1770609Y1122402D01*
G01X1770589Y1122368D02*
X1770604Y1122382D01*
G01X1770569Y1122362D02*
X1770589Y1122368D01*
G01X1770608Y1122376D02*
X1770610Y1122388D01*
G01X1770601Y1122365D02*
X1770608Y1122376D01*
G01X1770591Y1122356D02*
X1770601Y1122365D01*
G01X1770608Y1116076D02*
X1770610Y1116089D01*
G01X1770601Y1116065D02*
X1770608Y1116076D01*
G01X1770591Y1116057D02*
X1770601Y1116065D01*
G01X1770608Y1112927D02*
X1770610Y1112939D01*
G01X1770601Y1112916D02*
X1770608Y1112927D01*
G01X1770591Y1112907D02*
X1770601Y1112916D01*
G01X1770608Y1109777D02*
X1770610Y1109790D01*
G01X1770601Y1109766D02*
X1770608Y1109777D01*
G01X1770591Y1109758D02*
X1770601Y1109766D01*
G01X1770608Y1106628D02*
X1770610Y1106640D01*
G01X1770601Y1106617D02*
X1770608Y1106628D01*
G01X1770591Y1106608D02*
X1770601Y1106617D01*
G01X1770608Y1103478D02*
X1770610Y1103491D01*
G01X1770601Y1103467D02*
X1770608Y1103478D01*
G01X1770591Y1103459D02*
X1770601Y1103467D01*
G01X1769665Y1114100D02*
Y1114106D01*
G01Y1114096D02*
Y1114100D01*
G01X1769663Y1114094D02*
X1769665Y1114096D01*
G01Y1110950D02*
Y1110956D01*
G01Y1110946D02*
Y1110950D01*
G01X1769663Y1110945D02*
X1769665Y1110946D01*
G01Y1107800D02*
Y1107807D01*
G01Y1107796D02*
Y1107800D01*
G01X1769663Y1107795D02*
X1769665Y1107796D01*
G01Y1104651D02*
Y1104657D01*
G01Y1104647D02*
Y1104651D01*
G01X1769663Y1104646D02*
X1769665Y1104647D01*
G01X1770609Y1119231D02*
X1770610Y1119239D01*
G01X1770607Y1119224D02*
X1770609Y1119231D01*
G01X1770604Y1119218D02*
X1770607Y1119224D01*
G01X1770599Y1119212D02*
X1770604Y1119218D01*
G01X1770593Y1119207D02*
X1770599Y1119212D01*
G01X1770586Y1119204D02*
X1770593Y1119207D01*
G01X1770578Y1119202D02*
X1770586Y1119204D01*
G01X1770571Y1119202D02*
X1770578D01*
G01X1769626Y1123510D02*
Y1123518D01*
G01X1769625Y1123506D02*
X1769626Y1123510D01*
G01X1769624Y1123504D02*
X1769625Y1123506D01*
G01X1769626Y1120361D02*
Y1120368D01*
G01X1769625Y1120356D02*
X1769626Y1120361D01*
G01X1769624Y1120354D02*
X1769625Y1120356D01*
G01X1769626Y1117211D02*
Y1117219D01*
G01X1769625Y1117206D02*
X1769626Y1117211D01*
G01X1769624Y1117205D02*
X1769625Y1117206D01*
G01X1769626Y1114061D02*
Y1114069D01*
G01X1769625Y1114057D02*
X1769626Y1114061D01*
G01X1769624Y1114055D02*
X1769625Y1114057D01*
G01X1769626Y1110912D02*
Y1110919D01*
G01X1769625Y1110907D02*
X1769626Y1110912D01*
G01X1769624Y1110906D02*
X1769625Y1110907D01*
G01X1770588Y1103457D02*
X1770591Y1103459D01*
G01X1770585Y1103456D02*
X1770588Y1103457D01*
G01X1770581Y1103455D02*
X1770585Y1103456D01*
G01X1770578Y1103454D02*
X1770581Y1103455D01*
G01X1770574Y1103454D02*
X1770578D01*
G01X1770571D02*
X1770574D01*
G01X1769648Y1104654D02*
X1769645Y1104652D01*
G01X1769652Y1104655D02*
X1769648Y1104654D01*
G01X1769655Y1104656D02*
X1769652Y1104655D01*
G01X1769658Y1104656D02*
X1769655D01*
G01X1769662Y1104657D02*
X1769658Y1104656D01*
G01X1769665Y1104657D02*
X1769662D01*
G01X1770588Y1106607D02*
X1770591Y1106608D01*
G01X1770585Y1106606D02*
X1770588Y1106607D01*
G01X1770581Y1106604D02*
X1770585Y1106606D01*
G01X1770578Y1106604D02*
X1770581D01*
G01X1770574Y1106603D02*
X1770578Y1106604D01*
G01X1770571Y1106603D02*
X1770574D01*
G01X1769648Y1107803D02*
X1769645Y1107802D01*
G01X1769652Y1107804D02*
X1769648Y1107803D01*
G01X1769655Y1107806D02*
X1769652Y1107804D01*
G01X1769658Y1107806D02*
X1769655D01*
G01X1769662Y1107807D02*
X1769658Y1107806D01*
G01X1769665Y1107807D02*
X1769662D01*
G01X1770588Y1109756D02*
X1770591Y1109758D01*
G01X1770585Y1109755D02*
X1770588Y1109756D01*
G01X1770581Y1109754D02*
X1770585Y1109755D01*
G01X1770578Y1109753D02*
X1770581Y1109754D01*
G01X1770574Y1109753D02*
X1770578D01*
G01X1770571D02*
X1770574D01*
G01X1769648Y1110953D02*
X1769645Y1110951D01*
G01X1769652Y1110954D02*
X1769648Y1110953D01*
G01X1769655Y1110955D02*
X1769652Y1110954D01*
G01X1769658Y1110956D02*
X1769655Y1110955D01*
G01X1769662Y1110956D02*
X1769658D01*
G01X1769665D02*
X1769662D01*
G01X1770588Y1112906D02*
X1770591Y1112907D01*
G01X1770585Y1112905D02*
X1770588Y1112906D01*
G01X1770581Y1112904D02*
X1770585Y1112905D01*
G01X1770578Y1112903D02*
X1770581Y1112904D01*
G01X1770574Y1112902D02*
X1770578Y1112903D01*
G01X1770571Y1112902D02*
X1770574D01*
G01X1769648Y1114102D02*
X1769645Y1114101D01*
G01X1769652Y1114104D02*
X1769648Y1114102D01*
G01X1769655Y1114105D02*
X1769652Y1114104D01*
G01X1769658Y1114105D02*
X1769655D01*
G01X1769662Y1114106D02*
X1769658Y1114105D01*
G01X1769665Y1114106D02*
X1769662D01*
G01X1770588Y1116056D02*
X1770591Y1116057D01*
G01X1770585Y1116054D02*
X1770588Y1116056D01*
G01X1770581Y1116053D02*
X1770585Y1116054D01*
G01X1770578Y1116052D02*
X1770581Y1116053D01*
G01X1770574Y1116052D02*
X1770578D01*
G01X1770571D02*
X1770574D01*
G01X1769648Y1117252D02*
X1769645Y1117250D01*
G01X1769652Y1117253D02*
X1769648Y1117252D01*
G01X1769655Y1117254D02*
X1769652Y1117253D01*
G01X1769658Y1117255D02*
X1769655Y1117254D01*
G01X1769662Y1117256D02*
X1769658Y1117255D01*
G01X1769665Y1117256D02*
X1769662D01*
G01X1769648Y1120402D02*
X1769645Y1120400D01*
G01X1769652Y1120403D02*
X1769648Y1120402D01*
G01X1769655Y1120404D02*
X1769652Y1120403D01*
G01X1769658Y1120404D02*
X1769655D01*
G01X1769662Y1120405D02*
X1769658Y1120404D01*
G01X1769665Y1120405D02*
X1769662D01*
G01X1770588Y1122355D02*
X1770591Y1122356D01*
G01X1770585Y1122354D02*
X1770588Y1122355D01*
G01X1770581Y1122352D02*
X1770585Y1122354D01*
G01X1770578Y1122352D02*
X1770581D01*
G01X1770574Y1122351D02*
X1770578Y1122352D01*
G01X1770571Y1122351D02*
X1770574D01*
G01X1769648Y1123551D02*
X1769645Y1123550D01*
G01X1769652Y1123552D02*
X1769648Y1123551D01*
G01X1769655Y1123554D02*
X1769652Y1123552D01*
G01X1769658Y1123554D02*
X1769655D01*
G01X1769662Y1123555D02*
X1769658Y1123554D01*
G01X1769665Y1123555D02*
X1769662D01*
G01X1784036Y1130308D02*
X1784035Y1130299D01*
G01X1784037Y1130313D02*
X1784036Y1130308D01*
G01X1784038Y1130315D02*
X1784037Y1130313D01*
G01X1784036Y1125308D02*
X1784035Y1125299D01*
G01X1784037Y1125313D02*
X1784036Y1125308D01*
G01X1784038Y1125315D02*
X1784037Y1125313D01*
G01X1784036Y1100308D02*
X1784035Y1100299D01*
G01X1784037Y1100313D02*
X1784036Y1100308D01*
G01X1784038Y1100315D02*
X1784037Y1100313D01*
G01X1784036Y1095308D02*
X1784035Y1095299D01*
G01X1784037Y1095313D02*
X1784036Y1095308D01*
G01X1784038Y1095315D02*
X1784037Y1095313D01*
G01X1784036Y1090308D02*
X1784035Y1090299D01*
G01X1784037Y1090313D02*
X1784036Y1090308D01*
G01X1784038Y1090315D02*
X1784037Y1090313D01*
G01X1784036Y1085308D02*
X1784035Y1085299D01*
G01X1784037Y1085313D02*
X1784036Y1085308D01*
G01X1784038Y1085315D02*
X1784037Y1085313D01*
G01X1769626Y1107762D02*
Y1107770D01*
G01X1769625Y1107757D02*
X1769626Y1107762D01*
G01X1769624Y1107756D02*
X1769625Y1107757D01*
G01X1769626Y1104613D02*
Y1104620D01*
G01X1769625Y1104608D02*
X1769626Y1104613D01*
G01X1769624Y1104606D02*
X1769625Y1104608D01*
G01X1770601Y1104644D02*
X1770605Y1104639D01*
G01X1770596Y1104648D02*
X1770601Y1104644D01*
G01X1770590Y1104652D02*
X1770596Y1104648D01*
G01X1770584Y1104655D02*
X1770590Y1104652D01*
G01X1770578Y1104657D02*
X1770584Y1104655D01*
G01X1770571Y1104657D02*
X1770578D01*
G01X1770601Y1107794D02*
X1770605Y1107789D01*
G01X1770596Y1107798D02*
X1770601Y1107794D01*
G01X1770590Y1107802D02*
X1770596Y1107798D01*
G01X1770584Y1107804D02*
X1770590Y1107802D01*
G01X1770578Y1107806D02*
X1770584Y1107804D01*
G01X1770571Y1107807D02*
X1770578Y1107806D01*
G01X1770601Y1110943D02*
X1770605Y1110938D01*
G01X1770596Y1110948D02*
X1770601Y1110943D01*
G01X1770590Y1110952D02*
X1770596Y1110948D01*
G01X1770584Y1110954D02*
X1770590Y1110952D01*
G01X1770578Y1110956D02*
X1770584Y1110954D01*
G01X1770571Y1110956D02*
X1770578D01*
G01X1770601Y1114093D02*
X1770605Y1114088D01*
G01X1770596Y1114097D02*
X1770601Y1114093D01*
G01X1770590Y1114101D02*
X1770596Y1114097D01*
G01X1770584Y1114104D02*
X1770590Y1114101D01*
G01X1770578Y1114106D02*
X1770584Y1114104D01*
G01X1770571Y1114106D02*
X1770578D01*
G01X1770601Y1117243D02*
X1770605Y1117237D01*
G01X1770596Y1117247D02*
X1770601Y1117243D01*
G01X1770590Y1117251D02*
X1770596Y1117247D01*
G01X1770584Y1117253D02*
X1770590Y1117251D01*
G01X1770578Y1117255D02*
X1770584Y1117253D01*
G01X1770571Y1117256D02*
X1770578Y1117255D01*
G01X1770601Y1120392D02*
X1770605Y1120387D01*
G01X1770596Y1120396D02*
X1770601Y1120392D01*
G01X1770590Y1120400D02*
X1770596Y1120396D01*
G01X1770584Y1120403D02*
X1770590Y1120400D01*
G01X1770578Y1120405D02*
X1770584Y1120403D01*
G01X1770571Y1120405D02*
X1770578D01*
G01X1770601Y1123542D02*
X1770605Y1123537D01*
G01X1770596Y1123546D02*
X1770601Y1123542D01*
G01X1770590Y1123550D02*
X1770596Y1123546D01*
G01X1770584Y1123552D02*
X1770590Y1123550D01*
G01X1770578Y1123554D02*
X1770584Y1123552D01*
G01X1770571Y1123555D02*
X1770578Y1123554D01*
G01X1769627Y1103483D02*
X1769626Y1103491D01*
G01X1769629Y1103476D02*
X1769627Y1103483D01*
G01X1769633Y1103470D02*
X1769629Y1103476D01*
G01X1769637Y1103464D02*
X1769633Y1103470D01*
G01X1769644Y1103459D02*
X1769637Y1103464D01*
G01X1769650Y1103456D02*
X1769644Y1103459D01*
G01X1769658Y1103454D02*
X1769650Y1103456D01*
G01X1769665Y1103454D02*
X1769658D01*
G01X1769627Y1106633D02*
X1769626Y1106640D01*
G01X1769629Y1106626D02*
X1769627Y1106633D01*
G01X1769633Y1106620D02*
X1769629Y1106626D01*
G01X1769637Y1106614D02*
X1769633Y1106620D01*
G01X1769644Y1106609D02*
X1769637Y1106614D01*
G01X1769650Y1106606D02*
X1769644Y1106609D01*
G01X1769658Y1106604D02*
X1769650Y1106606D01*
G01X1769665Y1106603D02*
X1769658Y1106604D01*
G01X1769627Y1109782D02*
X1769626Y1109790D01*
G01X1769629Y1109776D02*
X1769627Y1109782D01*
G01X1769633Y1109769D02*
X1769629Y1109776D01*
G01X1769637Y1109763D02*
X1769633Y1109769D01*
G01X1769644Y1109759D02*
X1769637Y1109763D01*
G01X1769650Y1109756D02*
X1769644Y1109759D01*
G01X1769658Y1109754D02*
X1769650Y1109756D01*
G01X1769665Y1109753D02*
X1769658Y1109754D01*
G01X1769627Y1112932D02*
X1769626Y1112939D01*
G01X1769629Y1112925D02*
X1769627Y1112932D01*
G01X1769633Y1112919D02*
X1769629Y1112925D01*
G01X1769637Y1112913D02*
X1769633Y1112919D01*
G01X1769644Y1112908D02*
X1769637Y1112913D01*
G01X1769650Y1112905D02*
X1769644Y1112908D01*
G01X1769658Y1112903D02*
X1769650Y1112905D01*
G01X1769665Y1112902D02*
X1769658Y1112903D01*
G01X1769627Y1116081D02*
X1769626Y1116089D01*
G01X1769629Y1116075D02*
X1769627Y1116081D01*
G01X1769633Y1116069D02*
X1769629Y1116075D01*
G01X1769637Y1116063D02*
X1769633Y1116069D01*
G01X1769644Y1116058D02*
X1769637Y1116063D01*
G01X1769650Y1116055D02*
X1769644Y1116058D01*
G01X1769658Y1116053D02*
X1769650Y1116055D01*
G01X1769665Y1116052D02*
X1769658Y1116053D01*
G01X1769627Y1119231D02*
X1769626Y1119239D01*
G01X1769629Y1119224D02*
X1769627Y1119231D01*
G01X1769633Y1119218D02*
X1769629Y1119224D01*
G01X1769637Y1119212D02*
X1769633Y1119218D01*
G01X1769644Y1119207D02*
X1769637Y1119212D01*
G01X1769650Y1119204D02*
X1769644Y1119207D01*
G01X1769658Y1119202D02*
X1769650Y1119204D01*
G01X1769665Y1119202D02*
X1769658D01*
G01X1769627Y1122381D02*
X1769626Y1122388D01*
G01X1769629Y1122374D02*
X1769627Y1122381D01*
G01X1769633Y1122368D02*
X1769629Y1122374D01*
G01X1769637Y1122362D02*
X1769633Y1122368D01*
G01X1769644Y1122357D02*
X1769637Y1122362D01*
G01X1769650Y1122354D02*
X1769644Y1122357D01*
G01X1769658Y1122352D02*
X1769650Y1122354D01*
G01X1769665Y1122351D02*
X1769658Y1122352D01*
G01X1770580Y1104644D02*
X1770589Y1104640D01*
G01X1770569Y1104646D02*
X1770580Y1104644D01*
G01Y1107794D02*
X1770589Y1107790D01*
G01X1770569Y1107795D02*
X1770580Y1107794D01*
G01Y1110944D02*
X1770589Y1110939D01*
G01X1770569Y1110945D02*
X1770580Y1110944D01*
G01Y1114093D02*
X1770589Y1114089D01*
G01X1770569Y1114094D02*
X1770580Y1114093D01*
G01Y1117243D02*
X1770589Y1117239D01*
G01X1770569Y1117244D02*
X1770580Y1117243D01*
G01Y1120393D02*
X1770589Y1120388D01*
G01X1770569Y1120394D02*
X1770580Y1120393D01*
G01Y1123542D02*
X1770589Y1123538D01*
G01X1770569Y1123543D02*
X1770580Y1123542D01*
G01X1769626Y1106648D02*
Y1106640D01*
G01X1769625Y1106652D02*
X1769626Y1106648D01*
G01X1769624Y1106650D02*
X1769625Y1106652D01*
G01X1770571Y1123548D02*
Y1123555D01*
G01X1770570Y1123545D02*
X1770571Y1123548D01*
G01X1770569Y1123543D02*
X1770570Y1123545D01*
G01X1770571Y1120399D02*
Y1120405D01*
G01X1770570Y1120395D02*
X1770571Y1120399D01*
G01X1770569Y1120394D02*
X1770570Y1120395D01*
G01X1770571Y1117249D02*
Y1117256D01*
G01X1770570Y1117246D02*
X1770571Y1117249D01*
G01X1770569Y1117244D02*
X1770570Y1117246D01*
G01X1770571Y1114100D02*
Y1114106D01*
G01X1770570Y1114096D02*
X1770571Y1114100D01*
G01X1770569Y1114094D02*
X1770570Y1114096D01*
G01X1770571Y1110950D02*
Y1110956D01*
G01X1770570Y1110946D02*
X1770571Y1110950D01*
G01X1770569Y1110945D02*
X1770570Y1110946D01*
G01X1770571Y1107800D02*
Y1107807D01*
G01X1770570Y1107797D02*
X1770571Y1107800D01*
G01X1770569Y1107795D02*
X1770570Y1107797D01*
G01X1770571Y1104651D02*
Y1104657D01*
G01X1770570Y1104647D02*
X1770571Y1104651D01*
G01X1770569Y1104646D02*
X1770570Y1104647D01*
G01X1770610Y1123510D02*
Y1123517D01*
G01Y1123506D02*
Y1123510D01*
G01X1770609Y1123504D02*
X1770610Y1123506D01*
G01Y1120361D02*
Y1120368D01*
G01Y1120356D02*
Y1120361D01*
G01X1770609Y1120354D02*
X1770610Y1120356D01*
G01Y1117211D02*
Y1117218D01*
G01Y1117207D02*
Y1117211D01*
G01X1770609Y1117205D02*
X1770610Y1117207D01*
G01Y1114061D02*
Y1114069D01*
G01Y1114057D02*
Y1114061D01*
G01X1770609Y1114055D02*
X1770610Y1114057D01*
G01Y1110912D02*
Y1110919D01*
G01Y1110907D02*
Y1110912D01*
G01X1770609Y1110906D02*
X1770610Y1110907D01*
G01Y1107762D02*
Y1107769D01*
G01Y1107758D02*
Y1107762D01*
G01X1770609Y1107756D02*
X1770610Y1107758D01*
G01Y1104613D02*
Y1104620D01*
G01Y1104608D02*
Y1104613D01*
G01X1770609Y1104606D02*
X1770610Y1104608D01*
G01X1769626Y1112947D02*
Y1112939D01*
G01X1769625Y1112952D02*
X1769626Y1112947D01*
G01X1769624Y1112949D02*
X1769625Y1112952D01*
G01X1769626Y1106644D02*
Y1106640D01*
G01X1769628Y1106638D02*
X1769626Y1106644D01*
G01X1769639Y1106622D02*
X1769628Y1106638D01*
G01X1769664Y1106614D02*
X1769639Y1106622D01*
G01X1769626Y1109794D02*
Y1109790D01*
G01X1769628Y1109787D02*
X1769626Y1109794D01*
G01X1769639Y1109772D02*
X1769628Y1109787D01*
G01X1769663Y1109764D02*
X1769639Y1109772D01*
G01X1769626Y1116093D02*
Y1116089D01*
G01X1769628Y1116087D02*
X1769626Y1116093D01*
G01X1769639Y1116071D02*
X1769628Y1116087D01*
G01X1769663Y1116063D02*
X1769639Y1116071D01*
G01X1769626Y1119243D02*
Y1119239D01*
G01X1769628Y1119236D02*
X1769626Y1119243D01*
G01X1769639Y1119221D02*
X1769628Y1119236D01*
G01X1769663Y1119213D02*
X1769639Y1119221D01*
G01X1769626Y1103494D02*
Y1103491D01*
G01X1769628Y1103488D02*
X1769626Y1103494D01*
G01X1769639Y1103473D02*
X1769628Y1103488D01*
G01X1769663Y1103465D02*
X1769639Y1103473D01*
G01X1769626Y1122392D02*
Y1122388D01*
G01X1769628Y1122386D02*
X1769626Y1122392D01*
G01X1769639Y1122370D02*
X1769628Y1122386D01*
G01X1769663Y1122362D02*
X1769639Y1122370D01*
G01X1784023Y1086685D02*
X1784034Y1086669D01*
G01X1783998Y1086693D02*
X1784023Y1086685D01*
G01Y1091685D02*
X1784034Y1091669D01*
G01X1783998Y1091693D02*
X1784023Y1091685D01*
G01Y1096685D02*
X1784034Y1096669D01*
G01X1783998Y1096693D02*
X1784023Y1096685D01*
G01Y1101685D02*
X1784034Y1101669D01*
G01X1783998Y1101693D02*
X1784023Y1101685D01*
G01Y1126685D02*
X1784034Y1126669D01*
G01X1783998Y1126693D02*
X1784023Y1126685D01*
G01X1769626Y1112943D02*
Y1112939D01*
G01X1769627Y1112938D02*
X1769626Y1112943D01*
G01X1769637Y1112923D02*
X1769627Y1112938D01*
G01X1769661Y1112914D02*
X1769637Y1112923D01*
G01X1769639Y1123535D02*
X1769663Y1123543D01*
G01X1769628Y1123520D02*
X1769639Y1123535D01*
G01X1769626Y1123514D02*
X1769628Y1123520D01*
G01X1769639Y1120385D02*
X1769663Y1120394D01*
G01X1769628Y1120371D02*
X1769639Y1120385D01*
G01X1769626Y1120364D02*
X1769628Y1120371D01*
G01X1769639Y1117236D02*
X1769663Y1117244D01*
G01X1769628Y1117221D02*
X1769639Y1117236D01*
G01X1769626Y1117215D02*
X1769628Y1117221D01*
G01X1769639Y1114086D02*
X1769663Y1114094D01*
G01X1769628Y1114072D02*
X1769639Y1114086D01*
G01X1769626Y1114065D02*
X1769628Y1114072D01*
G01X1769639Y1110937D02*
X1769663Y1110945D01*
G01X1769628Y1110922D02*
X1769639Y1110937D01*
G01X1769626Y1110915D02*
X1769628Y1110922D01*
G01X1769639Y1107787D02*
X1769663Y1107795D01*
G01X1769628Y1107772D02*
X1769639Y1107787D01*
G01X1769626Y1107766D02*
X1769628Y1107772D01*
G01X1769639Y1104637D02*
X1769663Y1104646D01*
G01X1769628Y1104623D02*
X1769639Y1104637D01*
G01X1769626Y1104616D02*
X1769628Y1104623D01*
G01X1770579Y1110944D02*
X1770569Y1110945D01*
G01X1770587Y1110941D02*
X1770579Y1110944D01*
G01X1770595Y1110935D02*
X1770587Y1110941D01*
G01X1770579Y1104644D02*
X1770569Y1104646D01*
G01X1770588Y1104641D02*
X1770579Y1104644D01*
G01X1770595Y1104636D02*
X1770588Y1104641D01*
G01X1770579Y1107794D02*
X1770569Y1107795D01*
G01X1770588Y1107791D02*
X1770579Y1107794D01*
G01X1770595Y1107786D02*
X1770588Y1107791D01*
G01X1770579Y1114093D02*
X1770569Y1114094D01*
G01X1770588Y1114090D02*
X1770579Y1114093D01*
G01X1770595Y1114085D02*
X1770588Y1114090D01*
G01X1770579Y1117243D02*
X1770569Y1117244D01*
G01X1770588Y1117240D02*
X1770579Y1117243D01*
G01X1770595Y1117235D02*
X1770588Y1117240D01*
G01X1769626Y1116096D02*
Y1116089D01*
G01X1769625Y1116101D02*
X1769626Y1116096D01*
G01X1769625Y1116092D02*
Y1116101D01*
G01X1769666Y1123728D02*
X1769665Y1123740D01*
G01X1769663Y1123715D02*
X1769666Y1123728D01*
G01X1769663Y1123701D02*
Y1123715D01*
G01X1769666Y1120578D02*
X1769665Y1120591D01*
G01X1769663Y1120565D02*
X1769666Y1120578D01*
G01X1769663Y1120552D02*
Y1120565D01*
G01X1769666Y1117429D02*
X1769665Y1117441D01*
G01X1769663Y1117416D02*
X1769666Y1117429D01*
G01X1769663Y1117402D02*
Y1117416D01*
G01X1769666Y1114279D02*
X1769665Y1114291D01*
G01X1769663Y1114266D02*
X1769666Y1114279D01*
G01X1769663Y1114252D02*
Y1114266D01*
G01X1769666Y1111130D02*
X1769665Y1111142D01*
G01X1769663Y1111117D02*
X1769666Y1111130D01*
G01X1769663Y1111103D02*
Y1111117D01*
G01X1769666Y1107980D02*
X1769665Y1107992D01*
G01X1769663Y1107967D02*
X1769666Y1107980D01*
G01X1769663Y1107953D02*
Y1107967D01*
G01X1769666Y1104830D02*
X1769665Y1104843D01*
G01X1769663Y1104817D02*
X1769666Y1104830D01*
G01X1769663Y1104804D02*
Y1104817D01*
G01X1783052Y1130313D02*
X1783053Y1130315D01*
G01X1783051Y1130308D02*
X1783052Y1130313D01*
G01X1783051Y1130299D02*
Y1130308D01*
G01X1783052Y1125313D02*
X1783053Y1125315D01*
G01X1783051Y1125308D02*
X1783052Y1125313D01*
G01X1783051Y1125299D02*
Y1125308D01*
G01X1783052Y1100313D02*
X1783053Y1100315D01*
G01X1783051Y1100308D02*
X1783052Y1100313D01*
G01X1783051Y1100299D02*
Y1100308D01*
G01X1783052Y1095313D02*
X1783053Y1095315D01*
G01X1783051Y1095308D02*
X1783052Y1095313D01*
G01X1783051Y1095299D02*
Y1095308D01*
G01X1783052Y1090313D02*
X1783053Y1090315D01*
G01X1783051Y1090308D02*
X1783052Y1090313D01*
G01X1783051Y1090299D02*
Y1090308D01*
G01X1783052Y1085313D02*
X1783053Y1085315D01*
G01X1783051Y1085308D02*
X1783052Y1085313D01*
G01X1783051Y1085299D02*
Y1085308D01*
G01X1769626Y1122396D02*
Y1122388D01*
G01X1769625Y1122400D02*
X1769626Y1122396D01*
G01X1769625Y1122393D02*
Y1122400D01*
G01X1769663Y1122191D02*
X1769662Y1122204D01*
G01X1769666Y1122178D02*
X1769663Y1122191D01*
G01X1769665Y1122165D02*
X1769666Y1122178D01*
G01X1769663Y1119041D02*
X1769662Y1119055D01*
G01X1769666Y1119028D02*
X1769663Y1119041D01*
G01X1769665Y1119016D02*
X1769666Y1119028D01*
G01X1769663Y1115892D02*
X1769662Y1115905D01*
G01X1769666Y1115879D02*
X1769663Y1115892D01*
G01X1769665Y1115866D02*
X1769666Y1115879D01*
G01X1769663Y1112742D02*
X1769662Y1112756D01*
G01X1769666Y1112729D02*
X1769663Y1112742D01*
G01X1769665Y1112717D02*
X1769666Y1112729D01*
G01X1769663Y1109593D02*
X1769662Y1109606D01*
G01X1769666Y1109580D02*
X1769663Y1109593D01*
G01X1769665Y1109567D02*
X1769666Y1109580D01*
G01X1769663Y1106443D02*
X1769662Y1106456D01*
G01X1769666Y1106430D02*
X1769663Y1106443D01*
G01X1769665Y1106417D02*
X1769666Y1106430D01*
G01X1769663Y1103293D02*
X1769662Y1103307D01*
G01X1769666Y1103280D02*
X1769663Y1103293D01*
G01X1769665Y1103268D02*
X1769666Y1103280D01*
G01X1770573Y1123715D02*
X1770574Y1123701D01*
G01X1770570Y1123728D02*
X1770573Y1123715D01*
G01X1770571Y1123740D02*
X1770570Y1123728D01*
G01X1770573Y1120565D02*
X1770574Y1120552D01*
G01X1770570Y1120578D02*
X1770573Y1120565D01*
G01X1770571Y1120591D02*
X1770570Y1120578D01*
G01X1770573Y1117415D02*
X1770574Y1117402D01*
G01X1770570Y1117428D02*
X1770573Y1117415D01*
G01X1770571Y1117441D02*
X1770570Y1117428D01*
G01X1770573Y1114266D02*
X1770574Y1114252D01*
G01X1770570Y1114279D02*
X1770573Y1114266D01*
G01X1770571Y1114291D02*
X1770570Y1114279D01*
G01X1770573Y1111116D02*
X1770574Y1111103D01*
G01X1770570Y1111129D02*
X1770573Y1111116D01*
G01X1770571Y1111142D02*
X1770570Y1111129D01*
G01X1770573Y1107967D02*
X1770574Y1107953D01*
G01X1770570Y1107980D02*
X1770573Y1107967D01*
G01X1770571Y1107992D02*
X1770570Y1107980D01*
G01X1770573Y1104817D02*
X1770574Y1104804D01*
G01X1770570Y1104830D02*
X1770573Y1104817D01*
G01X1770571Y1104843D02*
X1770570Y1104830D01*
G01X1769626Y1109797D02*
Y1109790D01*
G01X1769625Y1109802D02*
X1769626Y1109797D01*
G01X1769624Y1109795D02*
X1769625Y1109802D01*
G01X1769626Y1119246D02*
Y1119239D01*
G01X1769625Y1119251D02*
X1769626Y1119246D01*
G01X1769624Y1119244D02*
X1769625Y1119251D01*
G01X1770570Y1122178D02*
X1770571Y1122165D01*
G01X1770573Y1122191D02*
X1770570Y1122178D01*
G01X1770574Y1122204D02*
X1770573Y1122191D01*
G01X1770570Y1119028D02*
X1770571Y1119016D01*
G01X1770573Y1119041D02*
X1770570Y1119028D01*
G01X1770574Y1119055D02*
X1770573Y1119041D01*
G01X1770570Y1115879D02*
X1770571Y1115866D01*
G01X1770573Y1115892D02*
X1770570Y1115879D01*
G01X1770574Y1115905D02*
X1770573Y1115892D01*
G01X1770570Y1112729D02*
X1770571Y1112717D01*
G01X1770573Y1112742D02*
X1770570Y1112729D01*
G01X1770574Y1112756D02*
X1770573Y1112742D01*
G01X1770570Y1109580D02*
X1770571Y1109567D01*
G01X1770573Y1109593D02*
X1770570Y1109580D01*
G01X1770574Y1109606D02*
X1770573Y1109593D01*
G01X1770570Y1106430D02*
X1770571Y1106417D01*
G01X1770573Y1106443D02*
X1770570Y1106430D01*
G01X1770574Y1106456D02*
X1770573Y1106443D01*
G01X1770570Y1103280D02*
X1770571Y1103268D01*
G01X1770573Y1103293D02*
X1770570Y1103280D01*
G01X1770574Y1103307D02*
X1770573Y1103293D01*
G01X1769626Y1103498D02*
Y1103491D01*
G01X1769625Y1103503D02*
X1769626Y1103498D01*
G01X1769624Y1103496D02*
X1769625Y1103503D01*
G01X1770579Y1120393D02*
X1770569Y1120394D01*
G01X1770588Y1120389D02*
X1770579Y1120393D01*
G01X1770595Y1120384D02*
X1770588Y1120389D01*
G01X1770579Y1123542D02*
X1770569Y1123543D01*
G01X1770588Y1123539D02*
X1770579Y1123542D01*
G01X1770595Y1123534D02*
X1770588Y1123539D01*
G01X1769665Y1103460D02*
Y1103454D01*
G01X1769664Y1103463D02*
X1769665Y1103460D01*
G01X1769663Y1103465D02*
X1769664Y1103463D01*
G01X1769665Y1106609D02*
Y1106603D01*
G01X1769664Y1106613D02*
X1769665Y1106609D01*
G01X1769663Y1106614D02*
X1769664Y1106613D01*
G01X1769665Y1109759D02*
Y1109753D01*
G01X1769664Y1109763D02*
X1769665Y1109759D01*
G01X1769663Y1109764D02*
X1769664Y1109763D01*
G01X1769665Y1112909D02*
Y1112902D01*
G01X1769664Y1112912D02*
X1769665Y1112909D01*
G01X1769663Y1112913D02*
X1769664Y1112912D01*
G01X1769665Y1116058D02*
Y1116052D01*
G01X1769664Y1116062D02*
X1769665Y1116058D01*
G01X1769663Y1116063D02*
X1769664Y1116062D01*
G01X1769665Y1119208D02*
Y1119202D01*
G01X1769664Y1119211D02*
X1769665Y1119208D01*
G01X1769663Y1119213D02*
X1769664Y1119211D01*
G01X1769665Y1122357D02*
Y1122351D01*
G01X1769664Y1122361D02*
X1769665Y1122357D01*
G01X1769663Y1122362D02*
X1769664Y1122361D01*
G01X1784002Y1086791D02*
X1784006Y1086890D01*
G01X1783997Y1086719D02*
X1784002Y1086791D01*
G01X1783999Y1086693D02*
X1783997Y1086719D01*
G01X1784002Y1091791D02*
X1784006Y1091890D01*
G01X1783997Y1091719D02*
X1784002Y1091791D01*
G01X1783999Y1091693D02*
X1783997Y1091719D01*
G01X1784002Y1096791D02*
X1784006Y1096890D01*
G01X1783997Y1096719D02*
X1784002Y1096791D01*
G01X1783999Y1096693D02*
X1783997Y1096719D01*
G01X1784002Y1101791D02*
X1784006Y1101890D01*
G01X1783997Y1101719D02*
X1784002Y1101791D01*
G01X1783999Y1101693D02*
X1783997Y1101719D01*
G01X1784002Y1126791D02*
X1784006Y1126890D01*
G01X1783997Y1126719D02*
X1784002Y1126791D01*
G01X1783999Y1126693D02*
X1783997Y1126719D01*
G01X1784036Y1086660D02*
X1784035Y1086667D01*
G01X1784037Y1086656D02*
X1784036Y1086660D01*
G01X1784038Y1086654D02*
X1784037Y1086656D01*
G01X1784036Y1091660D02*
X1784035Y1091667D01*
G01X1784037Y1091656D02*
X1784036Y1091660D01*
G01X1784038Y1091654D02*
X1784037Y1091656D01*
G01X1784036Y1096660D02*
X1784035Y1096667D01*
G01X1784037Y1096656D02*
X1784036Y1096660D01*
G01X1784038Y1096654D02*
X1784037Y1096656D01*
G01X1784036Y1101660D02*
X1784035Y1101667D01*
G01X1784037Y1101656D02*
X1784036Y1101660D01*
G01X1784038Y1101654D02*
X1784037Y1101656D01*
G01X1784036Y1126660D02*
X1784035Y1126667D01*
G01X1784037Y1126656D02*
X1784036Y1126660D01*
G01X1784038Y1126654D02*
X1784037Y1126656D01*
G01X1769649Y1106617D02*
X1769663Y1106614D01*
G01X1769637Y1106624D02*
X1769649Y1106617D01*
G01X1769625Y1106643D02*
X1769637Y1106624D01*
G01X1769649Y1116066D02*
X1769663Y1116063D01*
G01X1769637Y1116073D02*
X1769649Y1116066D01*
G01X1769625Y1116091D02*
X1769637Y1116073D01*
G01X1769648Y1109767D02*
X1769663Y1109764D01*
G01X1769636Y1109774D02*
X1769648Y1109767D01*
G01X1769624Y1109794D02*
X1769636Y1109774D01*
G01X1769648Y1119215D02*
X1769663Y1119213D01*
G01X1769636Y1119223D02*
X1769648Y1119215D01*
G01X1769624Y1119243D02*
X1769636Y1119223D01*
G01X1770610Y1103498D02*
Y1103491D01*
G01X1770609Y1103503D02*
X1770610Y1103498D01*
G01X1770609Y1103504D02*
Y1103503D01*
G01X1770610Y1106648D02*
Y1106640D01*
G01X1770609Y1106652D02*
X1770610Y1106648D01*
G01X1770609Y1106654D02*
Y1106652D01*
G01X1770610Y1109797D02*
Y1109790D01*
G01X1770609Y1109802D02*
X1770610Y1109797D01*
G01X1770609Y1109803D02*
Y1109802D01*
G01X1770610Y1112947D02*
Y1112939D01*
G01X1770609Y1112952D02*
X1770610Y1112947D01*
G01X1770609Y1112953D02*
Y1112952D01*
G01X1770610Y1116096D02*
Y1116089D01*
G01X1770609Y1116101D02*
X1770610Y1116096D01*
G01X1770609Y1116102D02*
Y1116101D01*
G01X1770610Y1119246D02*
Y1119239D01*
G01X1770609Y1119251D02*
X1770610Y1119246D01*
G01X1770609Y1119252D02*
Y1119251D01*
G01X1770610Y1122396D02*
Y1122388D01*
G01X1770609Y1122400D02*
X1770610Y1122396D01*
G01X1770609Y1122402D02*
Y1122400D01*
G01X1769648Y1122365D02*
X1769663Y1122362D01*
G01X1769636Y1122373D02*
X1769648Y1122365D01*
G01X1769624Y1122393D02*
X1769636Y1122373D01*
G01X1769648Y1103468D02*
X1769663Y1103465D01*
G01X1769635Y1103476D02*
X1769648Y1103468D01*
G01X1769624Y1103496D02*
X1769635Y1103476D01*
G01X1770609Y1104627D02*
X1770610Y1104620D01*
G01X1770608Y1104633D02*
X1770609Y1104627D01*
G01X1770605Y1104639D02*
X1770608Y1104633D01*
G01X1770609Y1107776D02*
X1770610Y1107770D01*
G01X1770608Y1107783D02*
X1770609Y1107776D01*
G01X1770605Y1107789D02*
X1770608Y1107783D01*
G01X1770609Y1110926D02*
X1770610Y1110919D01*
G01X1770608Y1110932D02*
X1770609Y1110926D01*
G01X1770605Y1110938D02*
X1770608Y1110932D01*
G01X1770609Y1114076D02*
X1770610Y1114069D01*
G01X1770608Y1114082D02*
X1770609Y1114076D01*
G01X1770605Y1114088D02*
X1770608Y1114082D01*
G01X1770609Y1117225D02*
X1770610Y1117219D01*
G01X1770608Y1117231D02*
X1770609Y1117225D01*
G01X1770605Y1117237D02*
X1770608Y1117231D01*
G01X1770609Y1120375D02*
X1770610Y1120368D01*
G01X1770608Y1120381D02*
X1770609Y1120375D01*
G01X1770605Y1120387D02*
X1770608Y1120381D01*
G01X1770609Y1123524D02*
X1770610Y1123518D01*
G01X1770608Y1123531D02*
X1770609Y1123524D01*
G01X1770605Y1123537D02*
X1770608Y1123531D01*
G01X1770571Y1103459D02*
X1770572Y1103454D01*
G01X1770570Y1103463D02*
X1770571Y1103459D01*
G01X1770569Y1103465D02*
X1770570Y1103463D01*
G01X1770571Y1106609D02*
X1770572Y1106603D01*
G01X1770570Y1106613D02*
X1770571Y1106609D01*
G01X1770569Y1106614D02*
X1770570Y1106613D01*
G01X1770571Y1109759D02*
X1770572Y1109753D01*
G01X1770570Y1109763D02*
X1770571Y1109759D01*
G01X1770569Y1109764D02*
X1770570Y1109763D01*
G01X1770571Y1112908D02*
X1770572Y1112902D01*
G01X1770570Y1112912D02*
X1770571Y1112908D01*
G01X1770569Y1112913D02*
X1770570Y1112912D01*
G01X1770571Y1116058D02*
X1770572Y1116052D01*
G01X1770570Y1116062D02*
X1770571Y1116058D01*
G01X1770569Y1116063D02*
X1770570Y1116062D01*
G01X1770571Y1122357D02*
X1770572Y1122351D01*
G01X1770570Y1122361D02*
X1770571Y1122357D01*
G01X1770569Y1122362D02*
X1770570Y1122361D01*
G01X1783051Y1086700D02*
Y1086709D01*
G01X1783052Y1086695D02*
X1783051Y1086700D01*
G01X1783053Y1086693D02*
X1783052Y1086695D01*
G01X1783051Y1091700D02*
Y1091709D01*
G01X1783052Y1091695D02*
X1783051Y1091700D01*
G01X1783053Y1091693D02*
X1783052Y1091695D01*
G01X1783051Y1096700D02*
Y1096709D01*
G01X1783052Y1096695D02*
X1783051Y1096700D01*
G01X1783053Y1096693D02*
X1783052Y1096695D01*
G01X1783051Y1101700D02*
Y1101709D01*
G01X1783052Y1101695D02*
X1783051Y1101700D01*
G01X1783053Y1101693D02*
X1783052Y1101695D01*
G01X1783051Y1126700D02*
Y1126709D01*
G01X1783052Y1126695D02*
X1783051Y1126700D01*
G01X1783053Y1126693D02*
X1783052Y1126695D01*
G01X1784028Y1086837D02*
X1784035Y1086811D01*
G01X1784018Y1086863D02*
X1784028Y1086837D01*
G01X1784006Y1086890D02*
X1784018Y1086863D01*
G01X1784028Y1091837D02*
X1784035Y1091811D01*
G01X1784018Y1091863D02*
X1784028Y1091837D01*
G01X1784006Y1091890D02*
X1784018Y1091863D01*
G01X1784028Y1096837D02*
X1784035Y1096811D01*
G01X1784018Y1096863D02*
X1784028Y1096837D01*
G01X1784006Y1096890D02*
X1784018Y1096863D01*
G01X1784028Y1101837D02*
X1784035Y1101811D01*
G01X1784018Y1101863D02*
X1784028Y1101837D01*
G01X1784006Y1101890D02*
X1784018Y1101863D01*
G01X1784028Y1126837D02*
X1784035Y1126811D01*
G01X1784018Y1126863D02*
X1784028Y1126837D01*
G01X1784006Y1126890D02*
X1784018Y1126863D01*
G01X1769644Y1112919D02*
X1769663Y1112913D01*
G01X1769630Y1112931D02*
X1769644Y1112919D01*
G01X1769624Y1112949D02*
X1769630Y1112931D01*
G01X1784018Y1086688D02*
X1783999Y1086693D01*
G01X1784033Y1086674D02*
X1784018Y1086688D01*
G01X1784038Y1086654D02*
X1784033Y1086674D01*
G01X1784018Y1091688D02*
X1783999Y1091693D01*
G01X1784033Y1091674D02*
X1784018Y1091688D01*
G01X1784038Y1091654D02*
X1784033Y1091674D01*
G01X1784018Y1096688D02*
X1783999Y1096693D01*
G01X1784033Y1096674D02*
X1784018Y1096688D01*
G01X1784038Y1096654D02*
X1784033Y1096674D01*
G01X1784018Y1101688D02*
X1783999Y1101693D01*
G01X1784033Y1101674D02*
X1784018Y1101688D01*
G01X1784038Y1101654D02*
X1784033Y1101674D01*
G01X1784018Y1126688D02*
X1783999Y1126693D01*
G01X1784033Y1126674D02*
X1784018Y1126688D01*
G01X1784038Y1126654D02*
X1784033Y1126674D01*
G01X1770603Y1110927D02*
X1770595Y1110935D01*
G01X1770607Y1110917D02*
X1770603Y1110927D01*
G01X1770609Y1110906D02*
X1770607Y1110917D01*
G01X1770603Y1104628D02*
X1770595Y1104636D01*
G01X1770607Y1104617D02*
X1770603Y1104628D01*
G01X1770609Y1104606D02*
X1770607Y1104617D01*
G01X1770603Y1107777D02*
X1770595Y1107786D01*
G01X1770607Y1107767D02*
X1770603Y1107777D01*
G01X1770609Y1107756D02*
X1770607Y1107767D01*
G01X1770603Y1114076D02*
X1770595Y1114085D01*
G01X1770607Y1114066D02*
X1770603Y1114076D01*
G01X1770609Y1114055D02*
X1770607Y1114066D01*
G01X1770603Y1117226D02*
X1770595Y1117235D01*
G01X1770607Y1117216D02*
X1770603Y1117226D01*
G01X1770609Y1117205D02*
X1770607Y1117216D01*
G01X1770603Y1120376D02*
X1770595Y1120384D01*
G01X1770607Y1120365D02*
X1770603Y1120376D01*
G01X1770609Y1120354D02*
X1770607Y1120365D01*
G01X1770603Y1123525D02*
X1770595Y1123534D01*
G01X1770607Y1123515D02*
X1770603Y1123525D01*
G01X1770609Y1123504D02*
X1770607Y1123515D01*
G01X1770569Y1119213D02*
X1770573Y1119202D01*
G01X1788386Y1130315D02*
Y1131693D01*
G01Y1125315D02*
Y1126693D01*
G01Y1100315D02*
Y1101693D01*
G01Y1095315D02*
Y1096693D01*
G01Y1090315D02*
Y1091693D01*
G01Y1085315D02*
Y1086693D01*
G01X1783465Y1103642D02*
X1784646Y1102461D01*
G01X1779528Y1103642D02*
X1780709Y1102461D01*
G01X1770610Y1104609D02*
Y1104620D01*
G01Y1107758D02*
Y1107769D01*
G01Y1110908D02*
Y1110919D01*
G01Y1114057D02*
Y1114069D01*
G01Y1117207D02*
Y1117218D01*
G01Y1120357D02*
Y1120368D01*
G01Y1123506D02*
Y1123517D01*
G01X1784035Y1086667D02*
X1784036Y1086676D01*
G01X1784035Y1091667D02*
X1784036Y1091676D01*
G01X1784035Y1096667D02*
X1784036Y1096676D01*
G01X1784035Y1101667D02*
X1784036Y1101676D01*
G01X1784035Y1126667D02*
X1784036Y1126676D01*
G01X1785217Y1086693D02*
Y1085315D01*
G01Y1091693D02*
Y1090315D01*
G01Y1096693D02*
Y1095315D01*
G01Y1101693D02*
Y1100315D01*
G01Y1126693D02*
Y1125315D01*
G01Y1131693D02*
Y1130315D01*
G01X1784646Y1124547D02*
Y1102461D01*
G01X1784035Y1129823D02*
Y1132185D01*
G01Y1124823D02*
Y1127185D01*
G01Y1099823D02*
Y1102185D01*
G01Y1094823D02*
Y1097185D01*
G01Y1089823D02*
Y1092185D01*
G01Y1084823D02*
Y1087185D01*
G01Y1086667D02*
Y1086811D01*
G01Y1096667D02*
Y1096811D01*
G01Y1091667D02*
Y1091811D01*
G01Y1101667D02*
Y1101811D01*
G01Y1126667D02*
Y1126811D01*
G01X1783465Y1123366D02*
Y1103642D01*
G01X1783051Y1087185D02*
Y1084823D01*
G01Y1092185D02*
Y1089823D01*
G01Y1097185D02*
Y1094823D01*
G01Y1102185D02*
Y1099823D01*
G01Y1127185D02*
Y1124823D01*
G01Y1132185D02*
Y1129823D01*
G01X1780709Y1201004D02*
Y1124547D01*
G01X1779528Y1199823D02*
Y1123366D01*
G01X1771063Y1204744D02*
Y1125709D01*
G01X1770610Y1122205D02*
Y1123701D01*
G01Y1119055D02*
Y1120551D01*
G01Y1115906D02*
Y1117402D01*
G01Y1112756D02*
Y1114252D01*
G01Y1109606D02*
Y1111102D01*
G01Y1106457D02*
Y1107953D01*
G01Y1103307D02*
Y1104803D01*
G01X1770571Y1106603D02*
Y1106456D01*
G01Y1103454D02*
Y1103307D01*
G01Y1104804D02*
Y1104657D01*
G01Y1109753D02*
Y1109606D01*
G01Y1111103D02*
Y1110956D01*
G01Y1107953D02*
Y1107807D01*
G01Y1116052D02*
Y1115905D01*
G01Y1112902D02*
Y1112756D01*
G01Y1114252D02*
Y1114106D01*
G01Y1119202D02*
Y1119055D01*
G01Y1120552D02*
Y1120405D01*
G01Y1117402D02*
Y1117256D01*
G01Y1122351D02*
Y1122204D01*
G01Y1123701D02*
Y1123555D01*
G01X1769665Y1122204D02*
Y1122351D01*
G01Y1123555D02*
Y1123702D01*
G01Y1119054D02*
Y1119202D01*
G01Y1120405D02*
Y1120552D01*
G01Y1117256D02*
Y1117402D01*
G01Y1115905D02*
Y1116052D01*
G01Y1112755D02*
Y1112902D01*
G01Y1114106D02*
Y1114253D01*
G01Y1109606D02*
Y1109753D01*
G01Y1110956D02*
Y1111103D01*
G01Y1107807D02*
Y1107954D01*
G01Y1106456D02*
Y1106603D01*
G01Y1103306D02*
Y1103454D01*
G01Y1104657D02*
Y1104804D01*
G01X1769626Y1104803D02*
Y1103307D01*
G01Y1111102D02*
Y1109606D01*
G01Y1107953D02*
Y1106457D01*
G01Y1114252D02*
Y1112756D01*
G01Y1120551D02*
Y1119055D01*
G01Y1117402D02*
Y1115906D01*
G01Y1123701D02*
Y1122205D01*
G01X1768445Y1107795D02*
Y1106614D01*
G01Y1104646D02*
Y1103465D01*
G01Y1110945D02*
Y1109764D01*
G01Y1117244D02*
Y1116063D01*
G01Y1114094D02*
Y1112913D01*
G01Y1120394D02*
Y1119213D01*
G01Y1123543D02*
Y1122362D01*
G01X1768110Y1125709D02*
Y1101299D01*
G01X1767717D02*
Y1125709D01*
G01X1770610Y1122388D02*
Y1122399D01*
G01Y1119239D02*
Y1119250D01*
G01Y1116089D02*
Y1116100D01*
G01Y1112939D02*
Y1112950D01*
G01Y1109790D02*
Y1109801D01*
G01Y1106640D02*
Y1106651D01*
G01Y1103491D02*
Y1103502D01*
G01X1769513Y1122402D02*
X1769624Y1122393D01*
G01Y1112949D02*
X1769513Y1112953D01*
G01X1769624Y1106650D02*
X1769513Y1106654D01*
G01X1769624Y1116099D02*
X1769513Y1116102D01*
G01X1788386Y1130315D02*
X1783053D01*
G01X1783051Y1129823D02*
X1784035D01*
G01Y1127185D02*
X1783051D01*
G01X1783053Y1126693D02*
X1788386D01*
G01Y1126654D02*
X1784038D01*
G01X1771063Y1125709D02*
X1767717D01*
G01X1788386Y1125315D02*
X1783053D01*
G01X1783051Y1124823D02*
X1784035D01*
G01X1780709Y1124547D02*
X1784646D01*
G01X1770571Y1123740D02*
X1769665D01*
G01X1770610Y1123701D02*
X1769626D01*
G01X1779528Y1123366D02*
X1783465D01*
G01X1769626Y1122205D02*
X1770610D01*
G01X1769665Y1122165D02*
X1770571D01*
G01Y1120591D02*
X1769665D01*
G01X1770610Y1120551D02*
X1769626D01*
G01Y1119055D02*
X1770610D01*
G01X1769665Y1119016D02*
X1770571D01*
G01Y1117441D02*
X1769665D01*
G01X1770610Y1117402D02*
X1769626D01*
G01X1768879Y1116102D02*
X1768445D01*
G01X1769626Y1115906D02*
X1770610D01*
G01X1769665Y1115866D02*
X1770571D01*
G01Y1114291D02*
X1769665D01*
G01X1770610Y1114252D02*
X1769626D01*
G01X1768879Y1112953D02*
X1768445D01*
G01X1769626Y1112756D02*
X1770610D01*
G01X1769665Y1112717D02*
X1770571D01*
G01Y1111142D02*
X1769665D01*
G01X1770610Y1111102D02*
X1769626D01*
G01Y1109606D02*
X1770610D01*
G01X1769665Y1109567D02*
X1770571D01*
G01Y1107992D02*
X1769665D01*
G01X1770610Y1107953D02*
X1769626D01*
G01X1768879Y1106654D02*
X1768445D01*
G01X1769626Y1106457D02*
X1770610D01*
G01X1769665Y1106417D02*
X1770571D01*
G01Y1104843D02*
X1769665D01*
G01X1770610Y1104803D02*
X1769626D01*
G01X1783465Y1103642D02*
X1779528D01*
G01X1769626Y1103307D02*
X1770610D01*
G01X1769665Y1103268D02*
X1770571D01*
G01X1784646Y1102461D02*
X1780709D01*
G01X1784035Y1102185D02*
X1783051D01*
G01X1783053Y1101693D02*
X1788386D01*
G01Y1101654D02*
X1784038D01*
G01X1771063Y1101299D02*
X1767717D01*
G01X1788386Y1100315D02*
X1783053D01*
G01X1783051Y1099823D02*
X1784035D01*
G01Y1097185D02*
X1783051D01*
G01X1783053Y1096693D02*
X1788386D01*
G01Y1096654D02*
X1784038D01*
G01X1788386Y1095315D02*
X1783053D01*
G01X1783051Y1094823D02*
X1784035D01*
G01Y1092185D02*
X1783051D01*
G01X1783053Y1091693D02*
X1788386D01*
G01Y1091654D02*
X1784038D01*
G01X1788386Y1090315D02*
X1783053D01*
G01X1783051Y1089823D02*
X1784035D01*
G01Y1087185D02*
X1783051D01*
G01X1783053Y1086693D02*
X1788386D01*
G01Y1086654D02*
X1784038D01*
G01X1788386Y1085315D02*
X1783053D01*
G01X1783051Y1084823D02*
X1784035D01*
G01Y1130119D02*
X1783051Y1130118D01*
G01Y1126889D02*
X1784006Y1126890D01*
G01X1784035Y1125119D02*
X1783051Y1125118D01*
G01Y1101889D02*
X1784006Y1101890D01*
G01X1784035Y1100119D02*
X1783051Y1100118D01*
G01Y1096889D02*
X1784006Y1096890D01*
G01X1784035Y1095119D02*
X1783051Y1095118D01*
G01Y1091889D02*
X1784006Y1091890D01*
G01X1784035Y1090119D02*
X1783051Y1090118D01*
G01Y1086889D02*
X1784006Y1086890D01*
G01X1784035Y1085119D02*
X1783051Y1085118D01*
G01X1783465Y1123366D02*
X1784646Y1124547D01*
G01X1779528Y1123366D02*
X1780709Y1124547D01*
G01X1784036Y1175308D02*
X1784035Y1175299D01*
G01X1784037Y1175313D02*
X1784036Y1175308D01*
G01X1784038Y1175315D02*
X1784037Y1175313D01*
G01X1784036Y1170308D02*
X1784035Y1170299D01*
G01X1784037Y1170313D02*
X1784036Y1170308D01*
G01X1784038Y1170315D02*
X1784037Y1170313D01*
G01X1784036Y1165308D02*
X1784035Y1165299D01*
G01X1784037Y1165313D02*
X1784036Y1165308D01*
G01X1784038Y1165315D02*
X1784037Y1165313D01*
G01X1784036Y1160308D02*
X1784035Y1160299D01*
G01X1784037Y1160313D02*
X1784036Y1160308D01*
G01X1784038Y1160315D02*
X1784037Y1160313D01*
G01X1784036Y1155308D02*
X1784035Y1155299D01*
G01X1784037Y1155313D02*
X1784036Y1155308D01*
G01X1784038Y1155315D02*
X1784037Y1155313D01*
G01X1784036Y1150308D02*
X1784035Y1150299D01*
G01X1784037Y1150313D02*
X1784036Y1150308D01*
G01X1784038Y1150315D02*
X1784037Y1150313D01*
G01X1784036Y1145308D02*
X1784035Y1145299D01*
G01X1784037Y1145313D02*
X1784036Y1145308D01*
G01X1784038Y1145315D02*
X1784037Y1145313D01*
G01X1784036Y1140308D02*
X1784035Y1140299D01*
G01X1784037Y1140313D02*
X1784036Y1140308D01*
G01X1784038Y1140315D02*
X1784037Y1140313D01*
G01X1784036Y1135308D02*
X1784035Y1135299D01*
G01X1784037Y1135313D02*
X1784036Y1135308D01*
G01X1784038Y1135315D02*
X1784037Y1135313D01*
G01X1784023Y1131685D02*
X1784034Y1131669D01*
G01X1783998Y1131693D02*
X1784023Y1131685D01*
G01Y1136685D02*
X1784034Y1136669D01*
G01X1783998Y1136693D02*
X1784023Y1136685D01*
G01Y1141685D02*
X1784034Y1141669D01*
G01X1783998Y1141693D02*
X1784023Y1141685D01*
G01Y1146685D02*
X1784034Y1146669D01*
G01X1783998Y1146693D02*
X1784023Y1146685D01*
G01Y1151685D02*
X1784034Y1151669D01*
G01X1783998Y1151693D02*
X1784023Y1151685D01*
G01Y1156685D02*
X1784034Y1156669D01*
G01X1783998Y1156693D02*
X1784023Y1156685D01*
G01Y1161685D02*
X1784034Y1161669D01*
G01X1783998Y1161693D02*
X1784023Y1161685D01*
G01Y1166685D02*
X1784034Y1166669D01*
G01X1783998Y1166693D02*
X1784023Y1166685D01*
G01Y1171685D02*
X1784034Y1171669D01*
G01X1783998Y1171693D02*
X1784023Y1171685D01*
G01Y1176685D02*
X1784034Y1176669D01*
G01X1783998Y1176693D02*
X1784023Y1176685D01*
G01X1783052Y1175313D02*
X1783053Y1175315D01*
G01X1783051Y1175308D02*
X1783052Y1175313D01*
G01X1783051Y1175299D02*
Y1175308D01*
G01X1783052Y1170313D02*
X1783053Y1170315D01*
G01X1783051Y1170308D02*
X1783052Y1170313D01*
G01X1783051Y1170299D02*
Y1170308D01*
G01X1783052Y1165313D02*
X1783053Y1165315D01*
G01X1783051Y1165308D02*
X1783052Y1165313D01*
G01X1783051Y1165299D02*
Y1165308D01*
G01X1783052Y1160313D02*
X1783053Y1160315D01*
G01X1783051Y1160308D02*
X1783052Y1160313D01*
G01X1783051Y1160299D02*
Y1160308D01*
G01X1783052Y1155313D02*
X1783053Y1155315D01*
G01X1783051Y1155308D02*
X1783052Y1155313D01*
G01X1783051Y1155299D02*
Y1155308D01*
G01X1783052Y1150313D02*
X1783053Y1150315D01*
G01X1783051Y1150308D02*
X1783052Y1150313D01*
G01X1783051Y1150299D02*
Y1150308D01*
G01X1783052Y1145313D02*
X1783053Y1145315D01*
G01X1783051Y1145308D02*
X1783052Y1145313D01*
G01X1783051Y1145299D02*
Y1145308D01*
G01X1783052Y1140313D02*
X1783053Y1140315D01*
G01X1783051Y1140308D02*
X1783052Y1140313D01*
G01X1783051Y1140299D02*
Y1140308D01*
G01X1783052Y1135313D02*
X1783053Y1135315D01*
G01X1783051Y1135308D02*
X1783052Y1135313D01*
G01X1783051Y1135299D02*
Y1135308D01*
G01X1784002Y1131791D02*
X1784006Y1131890D01*
G01X1783997Y1131719D02*
X1784002Y1131791D01*
G01X1783999Y1131693D02*
X1783997Y1131719D01*
G01X1784002Y1136791D02*
X1784006Y1136890D01*
G01X1783997Y1136719D02*
X1784002Y1136791D01*
G01X1783999Y1136693D02*
X1783997Y1136719D01*
G01X1784002Y1141791D02*
X1784006Y1141890D01*
G01X1783997Y1141719D02*
X1784002Y1141791D01*
G01X1783999Y1141693D02*
X1783997Y1141719D01*
G01X1784002Y1146791D02*
X1784006Y1146890D01*
G01X1783997Y1146719D02*
X1784002Y1146791D01*
G01X1783999Y1146693D02*
X1783997Y1146719D01*
G01X1784002Y1151791D02*
X1784006Y1151890D01*
G01X1783997Y1151719D02*
X1784002Y1151791D01*
G01X1783999Y1151693D02*
X1783997Y1151719D01*
G01X1784002Y1156791D02*
X1784006Y1156890D01*
G01X1783997Y1156719D02*
X1784002Y1156791D01*
G01X1783999Y1156693D02*
X1783997Y1156719D01*
G01X1784002Y1161791D02*
X1784006Y1161890D01*
G01X1783997Y1161719D02*
X1784002Y1161791D01*
G01X1783999Y1161693D02*
X1783997Y1161719D01*
G01X1784002Y1166791D02*
X1784006Y1166890D01*
G01X1783997Y1166719D02*
X1784002Y1166791D01*
G01X1783999Y1166693D02*
X1783997Y1166719D01*
G01X1784002Y1171791D02*
X1784006Y1171890D01*
G01X1783997Y1171719D02*
X1784002Y1171791D01*
G01X1783999Y1171693D02*
X1783997Y1171719D01*
G01X1784002Y1176791D02*
X1784006Y1176890D01*
G01X1783997Y1176719D02*
X1784002Y1176791D01*
G01X1783999Y1176693D02*
X1783997Y1176719D01*
G01X1784036Y1131660D02*
X1784035Y1131667D01*
G01X1784037Y1131656D02*
X1784036Y1131660D01*
G01X1784038Y1131654D02*
X1784037Y1131656D01*
G01X1784036Y1136660D02*
X1784035Y1136667D01*
G01X1784037Y1136656D02*
X1784036Y1136660D01*
G01X1784038Y1136654D02*
X1784037Y1136656D01*
G01X1784036Y1141660D02*
X1784035Y1141667D01*
G01X1784037Y1141656D02*
X1784036Y1141660D01*
G01X1784038Y1141654D02*
X1784037Y1141656D01*
G01X1784036Y1146660D02*
X1784035Y1146667D01*
G01X1784037Y1146656D02*
X1784036Y1146660D01*
G01X1784038Y1146654D02*
X1784037Y1146656D01*
G01X1784036Y1151660D02*
X1784035Y1151667D01*
G01X1784037Y1151656D02*
X1784036Y1151660D01*
G01X1784038Y1151654D02*
X1784037Y1151656D01*
G01X1784036Y1156660D02*
X1784035Y1156667D01*
G01X1784037Y1156656D02*
X1784036Y1156660D01*
G01X1784038Y1156654D02*
X1784037Y1156656D01*
G01X1784036Y1161660D02*
X1784035Y1161667D01*
G01X1784037Y1161656D02*
X1784036Y1161660D01*
G01X1784038Y1161654D02*
X1784037Y1161656D01*
G01X1784036Y1166660D02*
X1784035Y1166667D01*
G01X1784037Y1166656D02*
X1784036Y1166660D01*
G01X1784038Y1166654D02*
X1784037Y1166656D01*
G01X1784036Y1171660D02*
X1784035Y1171667D01*
G01X1784037Y1171656D02*
X1784036Y1171660D01*
G01X1784038Y1171654D02*
X1784037Y1171656D01*
G01X1784036Y1176660D02*
X1784035Y1176667D01*
G01X1784037Y1176656D02*
X1784036Y1176660D01*
G01X1784038Y1176654D02*
X1784037Y1176656D01*
G01X1783051Y1131700D02*
Y1131709D01*
G01X1783052Y1131695D02*
X1783051Y1131700D01*
G01X1783053Y1131693D02*
X1783052Y1131695D01*
G01X1783051Y1136700D02*
Y1136709D01*
G01X1783052Y1136695D02*
X1783051Y1136700D01*
G01X1783053Y1136693D02*
X1783052Y1136695D01*
G01X1783051Y1141700D02*
Y1141709D01*
G01X1783052Y1141695D02*
X1783051Y1141700D01*
G01X1783053Y1141693D02*
X1783052Y1141695D01*
G01X1783051Y1146700D02*
Y1146709D01*
G01X1783052Y1146695D02*
X1783051Y1146700D01*
G01X1783053Y1146693D02*
X1783052Y1146695D01*
G01X1783051Y1151700D02*
Y1151709D01*
G01X1783052Y1151695D02*
X1783051Y1151700D01*
G01X1783053Y1151693D02*
X1783052Y1151695D01*
G01X1783051Y1156700D02*
Y1156709D01*
G01X1783052Y1156695D02*
X1783051Y1156700D01*
G01X1783053Y1156693D02*
X1783052Y1156695D01*
G01X1783051Y1161700D02*
Y1161709D01*
G01X1783052Y1161695D02*
X1783051Y1161700D01*
G01X1783053Y1161693D02*
X1783052Y1161695D01*
G01X1783051Y1166700D02*
Y1166709D01*
G01X1783052Y1166695D02*
X1783051Y1166700D01*
G01X1783053Y1166693D02*
X1783052Y1166695D01*
G01X1783051Y1171700D02*
Y1171709D01*
G01X1783052Y1171695D02*
X1783051Y1171700D01*
G01X1783053Y1171693D02*
X1783052Y1171695D01*
G01X1783051Y1176700D02*
Y1176709D01*
G01X1783052Y1176695D02*
X1783051Y1176700D01*
G01X1783053Y1176693D02*
X1783052Y1176695D01*
G01X1784028Y1131837D02*
X1784035Y1131811D01*
G01X1784018Y1131863D02*
X1784028Y1131837D01*
G01X1784006Y1131890D02*
X1784018Y1131863D01*
G01X1784028Y1136837D02*
X1784035Y1136811D01*
G01X1784018Y1136863D02*
X1784028Y1136837D01*
G01X1784006Y1136890D02*
X1784018Y1136863D01*
G01X1784028Y1141837D02*
X1784035Y1141811D01*
G01X1784018Y1141863D02*
X1784028Y1141837D01*
G01X1784006Y1141890D02*
X1784018Y1141863D01*
G01X1784028Y1146837D02*
X1784035Y1146811D01*
G01X1784018Y1146863D02*
X1784028Y1146837D01*
G01X1784006Y1146890D02*
X1784018Y1146863D01*
G01X1784028Y1151837D02*
X1784035Y1151811D01*
G01X1784018Y1151863D02*
X1784028Y1151837D01*
G01X1784006Y1151890D02*
X1784018Y1151863D01*
G01X1784028Y1156837D02*
X1784035Y1156811D01*
G01X1784018Y1156863D02*
X1784028Y1156837D01*
G01X1784006Y1156890D02*
X1784018Y1156863D01*
G01X1784028Y1161837D02*
X1784035Y1161811D01*
G01X1784018Y1161863D02*
X1784028Y1161837D01*
G01X1784006Y1161890D02*
X1784018Y1161863D01*
G01X1784028Y1166837D02*
X1784035Y1166811D01*
G01X1784018Y1166863D02*
X1784028Y1166837D01*
G01X1784006Y1166890D02*
X1784018Y1166863D01*
G01X1784028Y1171837D02*
X1784035Y1171811D01*
G01X1784018Y1171863D02*
X1784028Y1171837D01*
G01X1784006Y1171890D02*
X1784018Y1171863D01*
G01X1784028Y1176837D02*
X1784035Y1176811D01*
G01X1784018Y1176863D02*
X1784028Y1176837D01*
G01X1784006Y1176890D02*
X1784018Y1176863D01*
G01Y1131688D02*
X1783999Y1131693D01*
G01X1784033Y1131674D02*
X1784018Y1131688D01*
G01X1784038Y1131654D02*
X1784033Y1131674D01*
G01X1784018Y1136688D02*
X1783999Y1136693D01*
G01X1784033Y1136674D02*
X1784018Y1136688D01*
G01X1784038Y1136654D02*
X1784033Y1136674D01*
G01X1784018Y1141688D02*
X1783999Y1141693D01*
G01X1784033Y1141674D02*
X1784018Y1141688D01*
G01X1784038Y1141654D02*
X1784033Y1141674D01*
G01X1784018Y1146688D02*
X1783999Y1146693D01*
G01X1784033Y1146674D02*
X1784018Y1146688D01*
G01X1784038Y1146654D02*
X1784033Y1146674D01*
G01X1784018Y1151688D02*
X1783999Y1151693D01*
G01X1784033Y1151674D02*
X1784018Y1151688D01*
G01X1784038Y1151654D02*
X1784033Y1151674D01*
G01X1784018Y1156688D02*
X1783999Y1156693D01*
G01X1784033Y1156674D02*
X1784018Y1156688D01*
G01X1784038Y1156654D02*
X1784033Y1156674D01*
G01X1784018Y1161688D02*
X1783999Y1161693D01*
G01X1784033Y1161674D02*
X1784018Y1161688D01*
G01X1784038Y1161654D02*
X1784033Y1161674D01*
G01X1784018Y1166688D02*
X1783999Y1166693D01*
G01X1784033Y1166674D02*
X1784018Y1166688D01*
G01X1784038Y1166654D02*
X1784033Y1166674D01*
G01X1784018Y1171688D02*
X1783999Y1171693D01*
G01X1784033Y1171674D02*
X1784018Y1171688D01*
G01X1784038Y1171654D02*
X1784033Y1171674D01*
G01X1784018Y1176688D02*
X1783999Y1176693D01*
G01X1784033Y1176674D02*
X1784018Y1176688D01*
G01X1784038Y1176654D02*
X1784033Y1176674D01*
G01X1788386Y1175315D02*
Y1176693D01*
G01Y1170315D02*
Y1171693D01*
G01Y1165315D02*
Y1166693D01*
G01Y1160315D02*
Y1161693D01*
G01Y1155315D02*
Y1156693D01*
G01Y1150315D02*
Y1151693D01*
G01Y1145315D02*
Y1146693D01*
G01Y1140315D02*
Y1141693D01*
G01Y1135315D02*
Y1136693D01*
G01X1784035Y1131667D02*
X1784036Y1131676D01*
G01X1784035Y1136667D02*
X1784036Y1136676D01*
G01X1784035Y1141667D02*
X1784036Y1141676D01*
G01X1784035Y1146667D02*
X1784036Y1146676D01*
G01X1784035Y1151667D02*
X1784036Y1151676D01*
G01X1784035Y1156667D02*
X1784036Y1156676D01*
G01X1784035Y1161667D02*
X1784036Y1161676D01*
G01X1784035Y1166667D02*
X1784036Y1166676D01*
G01X1784035Y1171667D02*
X1784036Y1171676D01*
G01X1784035Y1176667D02*
X1784036Y1176676D01*
G01X1785217Y1136693D02*
Y1135315D01*
G01Y1141693D02*
Y1140315D01*
G01Y1146693D02*
Y1145315D01*
G01Y1151693D02*
Y1150315D01*
G01Y1156693D02*
Y1155315D01*
G01Y1161693D02*
Y1160315D01*
G01Y1166693D02*
Y1165315D01*
G01Y1171693D02*
Y1170315D01*
G01Y1176693D02*
Y1175315D01*
G01X1784035Y1174823D02*
Y1177185D01*
G01Y1169823D02*
Y1172185D01*
G01Y1164823D02*
Y1167185D01*
G01Y1159823D02*
Y1162185D01*
G01Y1154823D02*
Y1157185D01*
G01Y1149823D02*
Y1152185D01*
G01Y1144823D02*
Y1147185D01*
G01Y1139823D02*
Y1142185D01*
G01Y1134823D02*
Y1137185D01*
G01Y1136667D02*
Y1136811D01*
G01Y1131667D02*
Y1131811D01*
G01Y1146667D02*
Y1146811D01*
G01Y1141667D02*
Y1141811D01*
G01Y1156667D02*
Y1156811D01*
G01Y1151667D02*
Y1151811D01*
G01Y1166667D02*
Y1166811D01*
G01Y1161667D02*
Y1161811D01*
G01Y1176667D02*
Y1176811D01*
G01Y1171667D02*
Y1171811D01*
G01X1783051Y1137185D02*
Y1134823D01*
G01Y1142185D02*
Y1139823D01*
G01Y1147185D02*
Y1144823D01*
G01Y1152185D02*
Y1149823D01*
G01Y1157185D02*
Y1154823D01*
G01Y1162185D02*
Y1159823D01*
G01Y1167185D02*
Y1164823D01*
G01Y1172185D02*
Y1169823D01*
G01Y1177185D02*
Y1174823D01*
G01X1784035Y1177185D02*
X1783051D01*
G01X1783053Y1176693D02*
X1788386D01*
G01Y1176654D02*
X1784038D01*
G01X1788386Y1175315D02*
X1783053D01*
G01X1783051Y1174823D02*
X1784035D01*
G01Y1172185D02*
X1783051D01*
G01X1783053Y1171693D02*
X1788386D01*
G01Y1171654D02*
X1784038D01*
G01X1788386Y1170315D02*
X1783053D01*
G01X1783051Y1169823D02*
X1784035D01*
G01Y1167185D02*
X1783051D01*
G01X1783053Y1166693D02*
X1788386D01*
G01Y1166654D02*
X1784038D01*
G01X1788386Y1165315D02*
X1783053D01*
G01X1783051Y1164823D02*
X1784035D01*
G01Y1162185D02*
X1783051D01*
G01X1783053Y1161693D02*
X1788386D01*
G01Y1161654D02*
X1784038D01*
G01X1788386Y1160315D02*
X1783053D01*
G01X1783051Y1159823D02*
X1784035D01*
G01Y1157185D02*
X1783051D01*
G01X1783053Y1156693D02*
X1788386D01*
G01Y1156654D02*
X1784038D01*
G01X1788386Y1155315D02*
X1783053D01*
G01X1783051Y1154823D02*
X1784035D01*
G01X1783051Y1176889D02*
X1784006Y1176890D01*
G01X1784035Y1175119D02*
X1783051Y1175118D01*
G01Y1171889D02*
X1784006Y1171890D01*
G01X1784035Y1170119D02*
X1783051Y1170118D01*
G01Y1166889D02*
X1784006Y1166890D01*
G01X1784035Y1165119D02*
X1783051Y1165118D01*
G01Y1161889D02*
X1784006Y1161890D01*
G01X1784035Y1160119D02*
X1783051Y1160118D01*
G01Y1156889D02*
X1784006Y1156890D01*
G01X1784035Y1155119D02*
X1783051Y1155118D01*
G01X1784035Y1152185D02*
X1783051D01*
G01X1783053Y1151693D02*
X1788386D01*
G01Y1151654D02*
X1784038D01*
G01X1788386Y1150315D02*
X1783053D01*
G01X1783051Y1149823D02*
X1784035D01*
G01Y1147185D02*
X1783051D01*
G01X1783053Y1146693D02*
X1788386D01*
G01Y1146654D02*
X1784038D01*
G01X1788386Y1145315D02*
X1783053D01*
G01X1783051Y1144823D02*
X1784035D01*
G01Y1142185D02*
X1783051D01*
G01X1783053Y1141693D02*
X1788386D01*
G01Y1141654D02*
X1784038D01*
G01X1788386Y1140315D02*
X1783053D01*
G01X1783051Y1139823D02*
X1784035D01*
G01Y1137185D02*
X1783051D01*
G01X1783053Y1136693D02*
X1788386D01*
G01Y1136654D02*
X1784038D01*
G01X1788386Y1135315D02*
X1783053D01*
G01X1783051Y1134823D02*
X1784035D01*
G01Y1132185D02*
X1783051D01*
G01X1783053Y1131693D02*
X1788386D01*
G01Y1131654D02*
X1784038D01*
G01X1783051Y1151889D02*
X1784006Y1151890D01*
G01X1784035Y1150119D02*
X1783051Y1150118D01*
G01Y1146889D02*
X1784006Y1146890D01*
G01X1784035Y1145119D02*
X1783051Y1145118D01*
G01Y1141889D02*
X1784006Y1141890D01*
G01X1784035Y1140119D02*
X1783051Y1140118D01*
G01Y1136889D02*
X1784006Y1136890D01*
G01X1784035Y1135119D02*
X1783051Y1135118D01*
G01Y1131889D02*
X1784006Y1131890D01*
G01X1784036Y1195308D02*
X1784035Y1195299D01*
G01X1784037Y1195313D02*
X1784036Y1195308D01*
G01X1784038Y1195315D02*
X1784037Y1195313D01*
G01X1784036Y1190308D02*
X1784035Y1190299D01*
G01X1784037Y1190313D02*
X1784036Y1190308D01*
G01X1784038Y1190315D02*
X1784037Y1190313D01*
G01X1784036Y1185308D02*
X1784035Y1185299D01*
G01X1784037Y1185313D02*
X1784036Y1185308D01*
G01X1784038Y1185315D02*
X1784037Y1185313D01*
G01X1784036Y1180308D02*
X1784035Y1180299D01*
G01X1784037Y1180313D02*
X1784036Y1180308D01*
G01X1784038Y1180315D02*
X1784037Y1180313D01*
G01X1784023Y1181685D02*
X1784034Y1181669D01*
G01X1783998Y1181693D02*
X1784023Y1181685D01*
G01Y1186685D02*
X1784034Y1186669D01*
G01X1783998Y1186693D02*
X1784023Y1186685D01*
G01Y1191685D02*
X1784034Y1191669D01*
G01X1783998Y1191693D02*
X1784023Y1191685D01*
G01Y1196685D02*
X1784034Y1196669D01*
G01X1783998Y1196693D02*
X1784023Y1196685D01*
G01X1783052Y1195313D02*
X1783053Y1195315D01*
G01X1783051Y1195308D02*
X1783052Y1195313D01*
G01X1783051Y1195299D02*
Y1195308D01*
G01X1783052Y1190313D02*
X1783053Y1190315D01*
G01X1783051Y1190308D02*
X1783052Y1190313D01*
G01X1783051Y1190299D02*
Y1190308D01*
G01X1783052Y1185313D02*
X1783053Y1185315D01*
G01X1783051Y1185308D02*
X1783052Y1185313D01*
G01X1783051Y1185299D02*
Y1185308D01*
G01X1783052Y1180313D02*
X1783053Y1180315D01*
G01X1783051Y1180308D02*
X1783052Y1180313D01*
G01X1783051Y1180299D02*
Y1180308D01*
G01X1784002Y1181791D02*
X1784006Y1181890D01*
G01X1783997Y1181719D02*
X1784002Y1181791D01*
G01X1783999Y1181693D02*
X1783997Y1181719D01*
G01X1784002Y1186791D02*
X1784006Y1186890D01*
G01X1783997Y1186719D02*
X1784002Y1186791D01*
G01X1783999Y1186693D02*
X1783997Y1186719D01*
G01X1784002Y1191791D02*
X1784006Y1191890D01*
G01X1783997Y1191719D02*
X1784002Y1191791D01*
G01X1783999Y1191693D02*
X1783997Y1191719D01*
G01X1784002Y1196791D02*
X1784006Y1196890D01*
G01X1783997Y1196719D02*
X1784002Y1196791D01*
G01X1783999Y1196693D02*
X1783997Y1196719D01*
G01X1784036Y1181660D02*
X1784035Y1181667D01*
G01X1784037Y1181656D02*
X1784036Y1181660D01*
G01X1784038Y1181654D02*
X1784037Y1181656D01*
G01X1784036Y1186660D02*
X1784035Y1186667D01*
G01X1784037Y1186656D02*
X1784036Y1186660D01*
G01X1784038Y1186654D02*
X1784037Y1186656D01*
G01X1784036Y1191660D02*
X1784035Y1191667D01*
G01X1784037Y1191656D02*
X1784036Y1191660D01*
G01X1784038Y1191654D02*
X1784037Y1191656D01*
G01X1784036Y1196660D02*
X1784035Y1196667D01*
G01X1784037Y1196656D02*
X1784036Y1196660D01*
G01X1784038Y1196654D02*
X1784037Y1196656D01*
G01X1783051Y1181700D02*
Y1181709D01*
G01X1783052Y1181695D02*
X1783051Y1181700D01*
G01X1783053Y1181693D02*
X1783052Y1181695D01*
G01X1783051Y1186700D02*
Y1186709D01*
G01X1783052Y1186695D02*
X1783051Y1186700D01*
G01X1783053Y1186693D02*
X1783052Y1186695D01*
G01X1784028Y1181837D02*
X1784035Y1181811D01*
G01X1784018Y1181863D02*
X1784028Y1181837D01*
G01X1784006Y1181890D02*
X1784018Y1181863D01*
G01Y1181688D02*
X1783999Y1181693D01*
G01X1784033Y1181674D02*
X1784018Y1181688D01*
G01X1784038Y1181654D02*
X1784033Y1181674D01*
G01X1784018Y1186688D02*
X1783999Y1186693D01*
G01X1784033Y1186674D02*
X1784018Y1186688D01*
G01X1784038Y1186654D02*
X1784033Y1186674D01*
G01X1784018Y1191688D02*
X1783999Y1191693D01*
G01X1784033Y1191674D02*
X1784018Y1191688D01*
G01X1784038Y1191654D02*
X1784033Y1191674D01*
G01X1784018Y1196688D02*
X1783999Y1196693D01*
G01X1784033Y1196674D02*
X1784018Y1196688D01*
G01X1784038Y1196654D02*
X1784033Y1196674D01*
G01X1783051Y1191700D02*
Y1191709D01*
G01X1783052Y1191695D02*
X1783051Y1191700D01*
G01X1783053Y1191693D02*
X1783052Y1191695D01*
G01X1783051Y1196700D02*
Y1196709D01*
G01X1783052Y1196695D02*
X1783051Y1196700D01*
G01X1783053Y1196693D02*
X1783052Y1196695D01*
G01X1784028Y1186837D02*
X1784035Y1186811D01*
G01X1784018Y1186863D02*
X1784028Y1186837D01*
G01X1784006Y1186890D02*
X1784018Y1186863D01*
G01X1784028Y1191837D02*
X1784035Y1191811D01*
G01X1784018Y1191863D02*
X1784028Y1191837D01*
G01X1784006Y1191890D02*
X1784018Y1191863D01*
G01X1784028Y1196837D02*
X1784035Y1196811D01*
G01X1784018Y1196863D02*
X1784028Y1196837D01*
G01X1784006Y1196890D02*
X1784018Y1196863D01*
G01X1782480Y1222185D02*
G03X1781890Y1222776I-591J0D01*
G01X1775197D02*
G03X1774606Y1222185I0J-591D01*
G01X1777362Y1221004D02*
G03Y1219035I0J-985D01*
G01X1779724D02*
G03Y1221004I0J985D01*
G01X1789370Y1221594D02*
G03X1787402Y1223563I-1968J1D01*
G01X1769685D02*
G03X1767717Y1221594I0J-1968D01*
G01X1775984Y1213091D02*
G03X1774803Y1211909I0J-1181D01*
G01X1782283D02*
G03X1781102Y1213091I-1181J1D01*
G01X1780433Y1207815D02*
G03I-1890J0D01*
G01X1780906D02*
G03I-2363J0D01*
G01X1777362Y1208406D02*
X1775052Y1212635D01*
G01X1779724Y1206713D02*
X1781028Y1204744D01*
G01X1772835Y1201004D02*
X1774016Y1199823D01*
G01X1767717Y1205846D02*
X1771063Y1202500D01*
G01X1789370Y1205846D02*
Y1221594D01*
G01X1788386Y1195315D02*
Y1196693D01*
G01Y1190315D02*
Y1191693D01*
G01Y1185315D02*
Y1186693D01*
G01Y1180315D02*
Y1181693D01*
G01X1784035Y1181667D02*
X1784036Y1181676D01*
G01X1784035Y1186667D02*
X1784036Y1186676D01*
G01X1784035Y1191667D02*
X1784036Y1191676D01*
G01X1784035Y1196667D02*
X1784036Y1196676D01*
G01X1785217Y1181693D02*
Y1180315D01*
G01Y1186693D02*
Y1185315D01*
G01Y1191693D02*
Y1190315D01*
G01Y1196693D02*
Y1195315D01*
G01X1784035Y1194823D02*
Y1197185D01*
G01Y1189823D02*
Y1192185D01*
G01Y1184823D02*
Y1187185D01*
G01Y1179823D02*
Y1182185D01*
G01Y1186667D02*
Y1186811D01*
G01Y1181667D02*
Y1181811D01*
G01Y1196667D02*
Y1196811D01*
G01Y1191667D02*
Y1191811D01*
G01X1783051Y1182185D02*
Y1179823D01*
G01Y1187185D02*
Y1184823D01*
G01Y1192185D02*
Y1189823D01*
G01Y1197185D02*
Y1194823D01*
G01X1782480Y1216083D02*
Y1222185D01*
G01X1782283Y1211909D02*
Y1203366D01*
G01X1779724Y1208406D02*
Y1206713D01*
G01X1777362D02*
Y1208406D01*
G01X1774803Y1203366D02*
Y1211909D01*
G01X1774606Y1216083D02*
Y1222185D01*
G01X1767717Y1221594D02*
Y1205846D01*
G01X1782035Y1212635D02*
X1779724Y1208406D01*
G01X1787402Y1223563D02*
X1769685D01*
G01X1781890Y1222776D02*
X1775197D01*
G01X1779724Y1221004D02*
X1777362D01*
G01Y1219035D02*
X1779724D01*
G01X1782480Y1217657D02*
X1774606D01*
G01Y1216083D02*
X1782480D01*
G01X1789370Y1213130D02*
X1767717D01*
G01X1775984Y1213091D02*
X1781102D01*
G01X1777362Y1208406D02*
X1779724D01*
G01X1777362Y1206713D02*
X1779724D01*
G01X1771063Y1204744D02*
X1785433D01*
G01X1771063Y1203366D02*
X1774803D01*
G01X1785433D02*
X1782283D01*
G01X1771063Y1202500D02*
X1786024D01*
G01X1772835Y1201004D02*
X1780709D01*
G01X1774016Y1199823D02*
X1779528D01*
G01X1784035Y1197185D02*
X1783051D01*
G01X1783053Y1196693D02*
X1788386D01*
G01Y1196654D02*
X1784038D01*
G01X1788386Y1195315D02*
X1783053D01*
G01X1783051Y1194823D02*
X1784035D01*
G01Y1192185D02*
X1783051D01*
G01X1783053Y1191693D02*
X1788386D01*
G01Y1191654D02*
X1784038D01*
G01X1788386Y1190315D02*
X1783053D01*
G01X1783051Y1189823D02*
X1784035D01*
G01Y1187185D02*
X1783051D01*
G01X1783053Y1186693D02*
X1788386D01*
G01Y1186654D02*
X1784038D01*
G01X1788386Y1185315D02*
X1783053D01*
G01X1783051Y1184823D02*
X1784035D01*
G01Y1182185D02*
X1783051D01*
G01X1783053Y1181693D02*
X1788386D01*
G01Y1181654D02*
X1784038D01*
G01X1788386Y1180315D02*
X1783053D01*
G01X1783051Y1179823D02*
X1784035D01*
G01X1783051Y1196889D02*
X1784006Y1196890D01*
G01X1784035Y1195119D02*
X1783051Y1195118D01*
G01Y1191889D02*
X1784006Y1191890D01*
G01X1784035Y1190119D02*
X1783051Y1190118D01*
G01Y1186889D02*
X1784006Y1186890D01*
G01X1784035Y1185119D02*
X1783051Y1185118D01*
G01Y1181889D02*
X1784006Y1181890D01*
G01X1784035Y1180119D02*
X1783051Y1180118D01*
G01X1776059Y1204744D02*
X1777362Y1206713D01*
G01X1789370Y1205846D02*
X1786024Y1202500D01*
G01X1779528Y1199823D02*
X1780709Y1201004D01*
G01X1781028Y1284397D02*
G03X1814838I16905J-13531D01*
G01X1781028D02*
G03X1814839I16906J-13531D01*
G01X1807914Y1297528D02*
G03X1814838Y1284397I37663J11469D01*
G01X1807914Y1297528D02*
G03X1787953I-9980J-3040D01*
G01X1781028Y1284397D02*
G03X1787953Y1297528I-30737J24602D01*
G01X1807913D02*
G03X1814839Y1284397I37661J11473D01*
G01X1781028D02*
G03X1787953Y1297528I-30737J24602D01*
G01X1807913D02*
G03X1787953I-9980J-3040D01*
G01X1858252Y-335933D02*
Y-354870D01*
G01X1844783Y20472D02*
G03X1853445I4331J0D01*
G01Y20473D02*
G03I-4331J0D01*
G01Y20472D02*
G03X1844783I-4331J0D01*
G01X1814272Y36220D02*
G03X1836713I11220J0D01*
G01D02*
G03X1814272I-11221J0D01*
G01X1836713Y36221D02*
G03I-11221J0D01*
G01X1860827Y368504D02*
G03X1859646I-590J0D01*
G01Y374803D02*
G03X1860827I591J0D01*
G01Y368504D02*
G03X1859646I-590J0D01*
G01Y374803D02*
G03X1860827I591J0D01*
G01X1858858Y368504D02*
Y374803D01*
G01D02*
Y368504D01*
G01X1859646Y374803D02*
X1858858D01*
G01X1859646D02*
X1858858D01*
G01X1862795D02*
X1860827D01*
G01X1862795D02*
X1860827D01*
G01X1864764Y373819D02*
X1858858D01*
G01Y373622D02*
X1864764D01*
G01X1858858Y369685D02*
X1864764D01*
G01Y369488D02*
X1858858D01*
G01X1860827Y368504D02*
X1862795D01*
G01X1860827D02*
X1862795D01*
G01X1858858D02*
X1859646D01*
G01X1858858D02*
X1859646D01*
G01X1860827Y821260D02*
G03X1859646I-590J0D01*
G01Y827559D02*
G03X1860827I591J0D01*
G01Y821260D02*
G03X1859646I-590J0D01*
G01Y827559D02*
G03X1860827I591J0D01*
G01X1858858Y821260D02*
Y827559D01*
G01D02*
Y821260D01*
G01X1859646Y827559D02*
X1858858D01*
G01X1859646D02*
X1858858D01*
G01X1862795D02*
X1860827D01*
G01X1862795D02*
X1860827D01*
G01X1864764Y826575D02*
X1858858D01*
G01Y826378D02*
X1864764D01*
G01X1858858Y822441D02*
X1864764D01*
G01Y822244D02*
X1858858D01*
G01X1860827Y821260D02*
X1862795D01*
G01X1860827D02*
X1862795D01*
G01X1858858D02*
X1859646D01*
G01X1858858D02*
X1859646D01*
G01X1833563Y1062992D02*
G03X1847539I6988J0D01*
G01D02*
G03X1833563I-6988J0D01*
G01X1847539D02*
G03I-6988J0D01*
G01X1835039Y1114173D02*
G03X1846063I5512J0D01*
G01D02*
G03X1835039I-5512J0D01*
G01X1846063D02*
G03I-5512J0D01*
G01X1860827Y1274016D02*
G03X1859646I-590J0D01*
G01X1860827D02*
G03X1859646I-590J0D01*
G01X1858858D02*
Y1280315D01*
G01D02*
Y1274016D01*
G01Y1275197D02*
X1864764D01*
G01Y1275000D02*
X1858858D01*
G01X1860827Y1274016D02*
X1862795D01*
G01X1860827D02*
X1862795D01*
G01X1858858D02*
X1859646D01*
G01X1858858D02*
X1859646D01*
G01Y1280315D02*
G03X1860827I591J0D01*
G01X1859646D02*
G03X1860827I591J0D01*
G01X1859646D02*
X1858858D01*
G01X1859646D02*
X1858858D01*
G01X1862795D02*
X1860827D01*
G01X1862795D02*
X1860827D01*
G01X1864764Y1279331D02*
X1858858D01*
G01Y1279134D02*
X1864764D01*
G01X1869996Y1573374D02*
G03I-4291J0D01*
G01D02*
G03I-4291J0D01*
G01X1858252Y1841823D02*
Y1822886D01*
G01X1902723Y-93682D02*
G03I-4291J0D01*
G01X1878817Y-110232D02*
G03I-3999J0D01*
G01X1876817D02*
G03I-1999J0D01*
G01X1902723Y-93682D02*
G03I-4291J0D01*
G01X1911220Y0D02*
G03Y-7874I0J-3937D01*
G01X1880512D02*
G03Y0I0J3937D01*
G01X1886417Y21654D02*
G03X1902953I8268J0D01*
G01X1911220Y0D02*
G03Y-7874I0J-3937D01*
G01X1880512D02*
G03Y0I0J3937D01*
G01X1902953Y21654D02*
G03I-8268J0D01*
G01D02*
G03X1886417I-8268J0D01*
G01X1903858Y153681D02*
G03I-1102J0D01*
G01X1904331D02*
G03I-1575J0D01*
G01X1898819Y139311D02*
G03X1899409Y138720I591J0D01*
G01X1906102D02*
G03X1906693Y139311I0J591D01*
G01X1903937Y140492D02*
G03Y142461I0J984D01*
G01X1901575D02*
G03Y140492I0J-984D01*
G01X1905315Y148406D02*
G03X1906496Y149587I0J1181D01*
G01X1899016D02*
G03X1900197Y148406I1181J0D01*
G01X1891929Y139902D02*
G03X1893898Y137933I1969J0D01*
G01X1898228Y161673D02*
X1897047Y160492D01*
G01X1895276Y158996D02*
X1891929Y155650D01*
G01X1905241Y156752D02*
X1903937Y154783D01*
G01X1899265Y148861D02*
X1901575Y153091D01*
G01X1909646Y299232D02*
Y156752D01*
G01X1906693Y145413D02*
Y139311D01*
G01X1906496Y158130D02*
Y149587D01*
G01X1904921Y196949D02*
Y160492D01*
G01X1903937Y154783D02*
Y153091D01*
G01X1903740Y198130D02*
Y161673D01*
G01X1901575Y153091D02*
Y154783D01*
G01X1899016Y149587D02*
Y158130D01*
G01X1898819Y145413D02*
Y139311D01*
G01X1898228Y161673D02*
Y294311D01*
G01X1897047Y160492D02*
Y295492D01*
G01X1895276Y195787D02*
Y156752D01*
G01X1891929Y155650D02*
Y139902D01*
G01X1903937Y153091D02*
X1906247Y148861D01*
G01X1901575Y154783D02*
X1900271Y156752D01*
G01X1903740Y161673D02*
X1904921Y160492D01*
G01X1903740Y161673D02*
X1898228D01*
G01X1904921Y160492D02*
X1897047D01*
G01X1910236Y158996D02*
X1895276D01*
G01X1906496Y158130D02*
X1909646D01*
G01X1899016D02*
X1895276D01*
G01Y156752D02*
X1909646D01*
G01X1903937Y154783D02*
X1901575D01*
G01X1903937Y153091D02*
X1901575D01*
G01X1905315Y148406D02*
X1900197D01*
G01X1913583Y148366D02*
X1891929D01*
G01X1906693Y145413D02*
X1898819D01*
G01Y143839D02*
X1906693D01*
G01X1903937Y142461D02*
X1901575D01*
G01Y140492D02*
X1903937D01*
G01X1906102Y138720D02*
X1899409D01*
G01X1911614Y137933D02*
X1893898D01*
G01X1893841Y199114D02*
X1893836Y199094D01*
G01X1893856Y199129D02*
X1893841Y199114D01*
G01X1893876Y199134D02*
X1893856Y199129D01*
G01X1893841Y202264D02*
X1893836Y202244D01*
G01X1893856Y202278D02*
X1893841Y202264D01*
G01X1893876Y202283D02*
X1893856Y202278D01*
G01X1893841Y205413D02*
X1893836Y205394D01*
G01X1893856Y205428D02*
X1893841Y205413D01*
G01X1893876Y205433D02*
X1893856Y205428D01*
G01X1894816Y197972D02*
X1894821Y197992D01*
G01X1894802Y197958D02*
X1894816Y197972D01*
G01X1894782Y197953D02*
X1894802Y197958D01*
G01X1894816Y201122D02*
X1894821Y201142D01*
G01X1894802Y201108D02*
X1894816Y201122D01*
G01X1894782Y201102D02*
X1894802Y201108D01*
G01X1894816Y204272D02*
X1894821Y204291D01*
G01X1894802Y204257D02*
X1894816Y204272D01*
G01X1894782Y204252D02*
X1894802Y204257D01*
G01X1894816Y207421D02*
X1894821Y207441D01*
G01X1894802Y207407D02*
X1894816Y207421D01*
G01X1894782Y207402D02*
X1894802Y207407D01*
G01X1893841Y208563D02*
X1893836Y208543D01*
G01X1893856Y208578D02*
X1893841Y208563D01*
G01X1893876Y208583D02*
X1893856Y208578D01*
G01X1893841Y211713D02*
X1893836Y211693D01*
G01X1893856Y211727D02*
X1893841Y211713D01*
G01X1893876Y211732D02*
X1893856Y211727D01*
G01X1894816Y210571D02*
X1894821Y210591D01*
G01X1894802Y210557D02*
X1894816Y210571D01*
G01X1894782Y210551D02*
X1894802Y210557D01*
G01X1894800Y197945D02*
X1894804Y197947D01*
G01X1894797Y197944D02*
X1894800Y197945D01*
G01X1894794Y197943D02*
X1894797Y197944D01*
G01X1894791Y197942D02*
X1894794Y197943D01*
G01X1894787Y197942D02*
X1894791D01*
G01X1894783D02*
X1894787D01*
G01X1893861Y199142D02*
X1893858Y199140D01*
G01X1893864Y199143D02*
X1893861Y199142D01*
G01X1893867Y199144D02*
X1893864Y199143D01*
G01X1893871Y199144D02*
X1893867D01*
G01X1893874Y199145D02*
X1893871Y199144D01*
G01X1893878Y199145D02*
X1893874D01*
G01X1894800Y201095D02*
X1894804Y201096D01*
G01X1894797Y201094D02*
X1894800Y201095D01*
G01X1894794Y201093D02*
X1894797Y201094D01*
G01X1894791Y201092D02*
X1894794Y201093D01*
G01X1894787Y201091D02*
X1894791Y201092D01*
G01X1894783Y201091D02*
X1894787D01*
G01X1893861Y202291D02*
X1893858Y202290D01*
G01X1893864Y202293D02*
X1893861Y202291D01*
G01X1893867Y202294D02*
X1893864Y202293D01*
G01X1893871Y202294D02*
X1893867D01*
G01X1893874Y202295D02*
X1893871Y202294D01*
G01X1893878Y202295D02*
X1893874D01*
G01X1894800Y204244D02*
X1894804Y204246D01*
G01X1894797Y204243D02*
X1894800Y204244D01*
G01X1894794Y204242D02*
X1894797Y204243D01*
G01X1894791Y204241D02*
X1894794Y204242D01*
G01X1894787Y204241D02*
X1894791D01*
G01X1894783D02*
X1894787D01*
G01X1893861Y205441D02*
X1893858Y205439D01*
G01X1893864Y205442D02*
X1893861Y205441D01*
G01X1893867Y205443D02*
X1893864Y205442D01*
G01X1893871Y205444D02*
X1893867Y205443D01*
G01X1893874Y205444D02*
X1893871D01*
G01X1893878D02*
X1893874D01*
G01X1894800Y207394D02*
X1894804Y207396D01*
G01X1894797Y207393D02*
X1894800Y207394D01*
G01X1894794Y207392D02*
X1894797Y207393D01*
G01X1894791Y207391D02*
X1894794Y207392D01*
G01X1894787Y207391D02*
X1894791D01*
G01X1894783D02*
X1894787D01*
G01X1893861Y208591D02*
X1893858Y208589D01*
G01X1893864Y208592D02*
X1893861Y208591D01*
G01X1893867Y208593D02*
X1893864Y208592D01*
G01X1893871Y208593D02*
X1893867D01*
G01X1893874Y208594D02*
X1893871Y208593D01*
G01X1893878Y208594D02*
X1893874D01*
G01X1894800Y210544D02*
X1894804Y210545D01*
G01X1894797Y210543D02*
X1894800Y210544D01*
G01X1894794Y210541D02*
X1894797Y210543D01*
G01X1894791Y210541D02*
X1894794D01*
G01X1894787Y210540D02*
X1894791Y210541D01*
G01X1894783Y210540D02*
X1894787D01*
G01X1893861Y211740D02*
X1893858Y211739D01*
G01X1893864Y211741D02*
X1893861Y211740D01*
G01X1893867Y211743D02*
X1893864Y211741D01*
G01X1893871Y211743D02*
X1893867D01*
G01X1893874Y211744D02*
X1893871Y211743D01*
G01X1893878Y211744D02*
X1893874D01*
G01X1894813Y199132D02*
X1894817Y199127D01*
G01X1894809Y199137D02*
X1894813Y199132D01*
G01X1894803Y199141D02*
X1894809Y199137D01*
G01X1894797Y199143D02*
X1894803Y199141D01*
G01X1894790Y199145D02*
X1894797Y199143D01*
G01X1894783Y199145D02*
X1894790D01*
G01X1894813Y202282D02*
X1894817Y202277D01*
G01X1894809Y202286D02*
X1894813Y202282D01*
G01X1894803Y202290D02*
X1894809Y202286D01*
G01X1894797Y202293D02*
X1894803Y202290D01*
G01X1894790Y202294D02*
X1894797Y202293D01*
G01X1894783Y202295D02*
X1894790Y202294D01*
G01X1894813Y205431D02*
X1894817Y205426D01*
G01X1894809Y205436D02*
X1894813Y205431D01*
G01X1894803Y205440D02*
X1894809Y205436D01*
G01X1894797Y205442D02*
X1894803Y205440D01*
G01X1894790Y205444D02*
X1894797Y205442D01*
G01X1894783Y205444D02*
X1894790D01*
G01X1894813Y208581D02*
X1894817Y208576D01*
G01X1894809Y208585D02*
X1894813Y208581D01*
G01X1894803Y208589D02*
X1894809Y208585D01*
G01X1894797Y208592D02*
X1894803Y208589D01*
G01X1894790Y208594D02*
X1894797Y208592D01*
G01X1894783Y208594D02*
X1894790D01*
G01X1894813Y211731D02*
X1894817Y211726D01*
G01X1894809Y211735D02*
X1894813Y211731D01*
G01X1894803Y211739D02*
X1894809Y211735D01*
G01X1894797Y211741D02*
X1894803Y211739D01*
G01X1894790Y211743D02*
X1894797Y211741D01*
G01X1894783Y211744D02*
X1894790Y211743D01*
G01X1893839Y197971D02*
Y197979D01*
G01X1893842Y197965D02*
X1893839Y197971D01*
G01X1893845Y197958D02*
X1893842Y197965D01*
G01X1893850Y197952D02*
X1893845Y197958D01*
G01X1893856Y197948D02*
X1893850Y197952D01*
G01X1893863Y197944D02*
X1893856Y197948D01*
G01X1893870Y197943D02*
X1893863Y197944D01*
G01X1893878Y197942D02*
X1893870Y197943D01*
G01X1893839Y201121D02*
Y201128D01*
G01X1893842Y201114D02*
X1893839Y201121D01*
G01X1893845Y201108D02*
X1893842Y201114D01*
G01X1893850Y201102D02*
X1893845Y201108D01*
G01X1893856Y201097D02*
X1893850Y201102D01*
G01X1893863Y201094D02*
X1893856Y201097D01*
G01X1893870Y201092D02*
X1893863Y201094D01*
G01X1893878Y201091D02*
X1893870Y201092D01*
G01X1893839Y204270D02*
Y204278D01*
G01X1893842Y204264D02*
X1893839Y204270D01*
G01X1893845Y204257D02*
X1893842Y204264D01*
G01X1893850Y204252D02*
X1893845Y204257D01*
G01X1893856Y204247D02*
X1893850Y204252D01*
G01X1893863Y204244D02*
X1893856Y204247D01*
G01X1893870Y204242D02*
X1893863Y204244D01*
G01X1893878Y204241D02*
X1893870Y204242D01*
G01X1893839Y207420D02*
Y207428D01*
G01X1893842Y207413D02*
X1893839Y207420D01*
G01X1893845Y207407D02*
X1893842Y207413D01*
G01X1893850Y207401D02*
X1893845Y207407D01*
G01X1893856Y207396D02*
X1893850Y207401D01*
G01X1893863Y207393D02*
X1893856Y207396D01*
G01X1893870Y207391D02*
X1893863Y207393D01*
G01X1893878Y207391D02*
X1893870D01*
G01X1893839Y210570D02*
Y210577D01*
G01X1893842Y210563D02*
X1893839Y210570D01*
G01X1893845Y210557D02*
X1893842Y210563D01*
G01X1893850Y210551D02*
X1893845Y210557D01*
G01X1893856Y210546D02*
X1893850Y210551D01*
G01X1893863Y210543D02*
X1893856Y210546D01*
G01X1893870Y210541D02*
X1893863Y210543D01*
G01X1893878Y210540D02*
X1893870Y210541D01*
G01X1894793Y199133D02*
X1894802Y199128D01*
G01X1894782Y199134D02*
X1894793Y199133D01*
G01Y202282D02*
X1894802Y202278D01*
G01X1894782Y202283D02*
X1894793Y202282D01*
G01Y205432D02*
X1894802Y205428D01*
G01X1894782Y205433D02*
X1894793Y205432D01*
G01Y208581D02*
X1894802Y208577D01*
G01X1894782Y208583D02*
X1894793Y208581D01*
G01Y211731D02*
X1894802Y211727D01*
G01X1894782Y211732D02*
X1894793Y211731D01*
G01X1893839Y201132D02*
Y201128D01*
G01X1893840Y201126D02*
X1893839Y201132D01*
G01X1893852Y201111D02*
X1893840Y201126D01*
G01X1893877Y201102D02*
X1893852Y201111D01*
G01X1908235Y166173D02*
X1908246Y166157D01*
G01X1908211Y166181D02*
X1908235Y166173D01*
G01Y171173D02*
X1908246Y171157D01*
G01X1908211Y171181D02*
X1908235Y171173D01*
G01Y176173D02*
X1908246Y176157D01*
G01X1908211Y176181D02*
X1908235Y176173D01*
G01X1893839Y204282D02*
Y204278D01*
G01X1893840Y204276D02*
X1893839Y204282D01*
G01X1893852Y204260D02*
X1893840Y204276D01*
G01X1893876Y204252D02*
X1893852Y204260D01*
G01X1893839Y210581D02*
Y210577D01*
G01X1893840Y210575D02*
X1893839Y210581D01*
G01X1893852Y210559D02*
X1893840Y210575D01*
G01X1893876Y210551D02*
X1893852Y210559D01*
G01X1893839Y197983D02*
Y197979D01*
G01X1893840Y197976D02*
X1893839Y197983D01*
G01X1893852Y197961D02*
X1893840Y197976D01*
G01X1893876Y197953D02*
X1893852Y197961D01*
G01X1908235Y181173D02*
X1908246Y181157D01*
G01X1908211Y181181D02*
X1908235Y181173D01*
G01Y186173D02*
X1908246Y186157D01*
G01X1908211Y186181D02*
X1908235Y186173D01*
G01Y191173D02*
X1908246Y191157D01*
G01X1908211Y191181D02*
X1908235Y191173D01*
G01Y196173D02*
X1908246Y196157D01*
G01X1908211Y196181D02*
X1908235Y196173D01*
G01X1893839Y207431D02*
Y207428D01*
G01X1893840Y207426D02*
X1893839Y207431D01*
G01X1893850Y207411D02*
X1893840Y207426D01*
G01X1893873Y207402D02*
X1893850Y207411D01*
G01X1894791Y205432D02*
X1894782Y205433D01*
G01X1894800Y205429D02*
X1894791Y205432D01*
G01X1894808Y205424D02*
X1894800Y205429D01*
G01X1894791Y199133D02*
X1894782Y199134D01*
G01X1894800Y199130D02*
X1894791Y199133D01*
G01X1894808Y199124D02*
X1894800Y199130D01*
G01X1894791Y202282D02*
X1894782Y202283D01*
G01X1894800Y202279D02*
X1894791Y202282D01*
G01X1894808Y202274D02*
X1894800Y202279D01*
G01X1894791Y208581D02*
X1894782Y208583D01*
G01X1894800Y208578D02*
X1894791Y208581D01*
G01X1894808Y208573D02*
X1894800Y208578D01*
G01X1894791Y211731D02*
X1894782Y211732D01*
G01X1894800Y211728D02*
X1894791Y211731D01*
G01X1894808Y211723D02*
X1894800Y211728D01*
G01X1893878Y197948D02*
Y197942D01*
G01X1893877Y197952D02*
X1893878Y197948D01*
G01X1893876Y197953D02*
X1893877Y197952D01*
G01X1893878Y201098D02*
Y201091D01*
G01X1893877Y201101D02*
X1893878Y201098D01*
G01X1893876Y201102D02*
X1893877Y201101D01*
G01X1893878Y204247D02*
Y204241D01*
G01X1893877Y204251D02*
X1893878Y204247D01*
G01X1893876Y204252D02*
X1893877Y204251D01*
G01X1893878Y207397D02*
Y207391D01*
G01X1893877Y207400D02*
X1893878Y207397D01*
G01X1893876Y207402D02*
X1893877Y207400D01*
G01X1893878Y210546D02*
Y210540D01*
G01X1893877Y210550D02*
X1893878Y210546D01*
G01X1893876Y210551D02*
X1893877Y210550D01*
G01X1908248Y166148D02*
Y166156D01*
G01X1908249Y166144D02*
X1908248Y166148D01*
G01X1908250Y166142D02*
X1908249Y166144D01*
G01X1908248Y171148D02*
Y171156D01*
G01X1908249Y171144D02*
X1908248Y171148D01*
G01X1908250Y171142D02*
X1908249Y171144D01*
G01X1908248Y176148D02*
Y176156D01*
G01X1908249Y176144D02*
X1908248Y176148D01*
G01X1908250Y176142D02*
X1908249Y176144D01*
G01X1908248Y181148D02*
Y181156D01*
G01X1908249Y181144D02*
X1908248Y181148D01*
G01X1908250Y181142D02*
X1908249Y181144D01*
G01X1908248Y186148D02*
Y186156D01*
G01X1908249Y186144D02*
X1908248Y186148D01*
G01X1908250Y186142D02*
X1908249Y186144D01*
G01X1908248Y191148D02*
Y191156D01*
G01X1908249Y191144D02*
X1908248Y191148D01*
G01X1908250Y191142D02*
X1908249Y191144D01*
G01X1908248Y196148D02*
Y196156D01*
G01X1908249Y196144D02*
X1908248Y196148D01*
G01X1908250Y196142D02*
X1908249Y196144D01*
G01X1893861Y201105D02*
X1893876Y201102D01*
G01X1893850Y201112D02*
X1893861Y201105D01*
G01X1893838Y201131D02*
X1893850Y201112D01*
G01X1893861Y210554D02*
X1893876Y210551D01*
G01X1893850Y210561D02*
X1893861Y210554D01*
G01X1893838Y210580D02*
X1893850Y210561D01*
G01X1893861Y204255D02*
X1893876Y204252D01*
G01X1893849Y204263D02*
X1893861Y204255D01*
G01X1893837Y204283D02*
X1893849Y204263D01*
G01X1894823Y197986D02*
Y197979D01*
G01X1894822Y197991D02*
X1894823Y197986D01*
G01X1894821Y197992D02*
X1894822Y197991D01*
G01X1894823Y201136D02*
Y201128D01*
G01X1894822Y201141D02*
X1894823Y201136D01*
G01X1894821Y201142D02*
X1894822Y201141D01*
G01X1894823Y204285D02*
Y204278D01*
G01X1894822Y204290D02*
X1894823Y204285D01*
G01X1894821Y204291D02*
X1894822Y204290D01*
G01X1894823Y207435D02*
Y207428D01*
G01X1894822Y207440D02*
X1894823Y207435D01*
G01X1894821Y207441D02*
X1894822Y207440D01*
G01X1894823Y210585D02*
Y210577D01*
G01X1894822Y210589D02*
X1894823Y210585D01*
G01X1894821Y210591D02*
X1894822Y210589D01*
G01X1893861Y197956D02*
X1893876Y197953D01*
G01X1893848Y197964D02*
X1893861Y197956D01*
G01X1893837Y197985D02*
X1893848Y197964D01*
G01X1894822Y199115D02*
X1894823Y199108D01*
G01X1894820Y199121D02*
X1894822Y199115D01*
G01X1894817Y199127D02*
X1894820Y199121D01*
G01X1894822Y202265D02*
X1894823Y202258D01*
G01X1894820Y202271D02*
X1894822Y202265D01*
G01X1894817Y202277D02*
X1894820Y202271D01*
G01X1894822Y205414D02*
X1894823Y205407D01*
G01X1894820Y205420D02*
X1894822Y205414D01*
G01X1894817Y205426D02*
X1894820Y205420D01*
G01X1894822Y208564D02*
X1894823Y208557D01*
G01X1894820Y208570D02*
X1894822Y208564D01*
G01X1894817Y208576D02*
X1894820Y208570D01*
G01X1894822Y211713D02*
X1894823Y211707D01*
G01X1894820Y211720D02*
X1894822Y211713D01*
G01X1894817Y211726D02*
X1894820Y211720D01*
G01X1894784Y197948D02*
Y197942D01*
G01X1894783Y197952D02*
X1894784Y197948D01*
G01X1894782Y197953D02*
X1894783Y197952D01*
G01X1894784Y201097D02*
Y201091D01*
G01X1894783Y201101D02*
X1894784Y201097D01*
G01X1894782Y201102D02*
X1894783Y201101D01*
G01X1894784Y204247D02*
Y204241D01*
G01X1894783Y204251D02*
X1894784Y204247D01*
G01X1894782Y204252D02*
X1894783Y204251D01*
G01X1894784Y207396D02*
Y207391D01*
G01X1894783Y207400D02*
X1894784Y207396D01*
G01X1894782Y207402D02*
X1894783Y207400D01*
G01X1894784Y210546D02*
Y210540D01*
G01X1894783Y210550D02*
X1894784Y210546D01*
G01X1894782Y210551D02*
X1894783Y210550D01*
G01X1907264Y166189D02*
Y166198D01*
G01X1907265Y166183D02*
X1907264Y166189D01*
G01X1907265Y166181D02*
Y166183D01*
G01X1907264Y171189D02*
Y171198D01*
G01X1907265Y171183D02*
X1907264Y171189D01*
G01X1907265Y171181D02*
Y171183D01*
G01X1907264Y176189D02*
Y176198D01*
G01X1907265Y176183D02*
X1907264Y176189D01*
G01X1907265Y176181D02*
Y176183D01*
G01X1907264Y181189D02*
Y181198D01*
G01X1907265Y181183D02*
X1907264Y181189D01*
G01X1907265Y181181D02*
Y181183D01*
G01X1907264Y186189D02*
Y186198D01*
G01X1907265Y186183D02*
X1907264Y186189D01*
G01X1907265Y186181D02*
Y186183D01*
G01X1907264Y191189D02*
Y191198D01*
G01X1907265Y191183D02*
X1907264Y191189D01*
G01X1907265Y191181D02*
Y191183D01*
G01X1907264Y196189D02*
Y196198D01*
G01X1907265Y196183D02*
X1907264Y196189D01*
G01X1907265Y196181D02*
Y196183D01*
G01X1908240Y166325D02*
X1908248Y166299D01*
G01X1908230Y166352D02*
X1908240Y166325D01*
G01X1908219Y166378D02*
X1908230Y166352D01*
G01X1908240Y171325D02*
X1908248Y171299D01*
G01X1908230Y171352D02*
X1908240Y171325D01*
G01X1908219Y171378D02*
X1908230Y171352D01*
G01X1908240Y176325D02*
X1908248Y176299D01*
G01X1908230Y176352D02*
X1908240Y176325D01*
G01X1908219Y176378D02*
X1908230Y176352D01*
G01X1908240Y181325D02*
X1908248Y181299D01*
G01X1908230Y181352D02*
X1908240Y181325D01*
G01X1908219Y181378D02*
X1908230Y181352D01*
G01X1908240Y186325D02*
X1908248Y186299D01*
G01X1908230Y186352D02*
X1908240Y186325D01*
G01X1908219Y186378D02*
X1908230Y186352D01*
G01X1908240Y191325D02*
X1908248Y191299D01*
G01X1908230Y191352D02*
X1908240Y191325D01*
G01X1908219Y191378D02*
X1908230Y191352D01*
G01X1908240Y196325D02*
X1908248Y196299D01*
G01X1908230Y196352D02*
X1908240Y196325D01*
G01X1908219Y196378D02*
X1908230Y196352D01*
G01X1893856Y207407D02*
X1893876Y207402D01*
G01X1893843Y207419D02*
X1893856Y207407D01*
G01X1893836Y207437D02*
X1893843Y207419D01*
G01X1908231Y166176D02*
X1908211Y166181D01*
G01X1908245Y166162D02*
X1908231Y166176D01*
G01X1908250Y166142D02*
X1908245Y166162D01*
G01X1908231Y171176D02*
X1908211Y171181D01*
G01X1908245Y171162D02*
X1908231Y171176D01*
G01X1908250Y171142D02*
X1908245Y171162D01*
G01X1908231Y176176D02*
X1908211Y176181D01*
G01X1908245Y176162D02*
X1908231Y176176D01*
G01X1908250Y176142D02*
X1908245Y176162D01*
G01X1908231Y181176D02*
X1908211Y181181D01*
G01X1908245Y181162D02*
X1908231Y181176D01*
G01X1908250Y181142D02*
X1908245Y181162D01*
G01X1908231Y186176D02*
X1908211Y186181D01*
G01X1908245Y186162D02*
X1908231Y186176D01*
G01X1908250Y186142D02*
X1908245Y186162D01*
G01X1908231Y191176D02*
X1908211Y191181D01*
G01X1908245Y191162D02*
X1908231Y191176D01*
G01X1908250Y191142D02*
X1908245Y191162D01*
G01X1908231Y196176D02*
X1908211Y196181D01*
G01X1908245Y196162D02*
X1908231Y196176D01*
G01X1908250Y196142D02*
X1908245Y196162D01*
G01X1908215Y166279D02*
X1908219Y166378D01*
G01X1908209Y166207D02*
X1908215Y166279D01*
G01X1908211Y166181D02*
X1908209Y166207D01*
G01X1908215Y171279D02*
X1908219Y171378D01*
G01X1908209Y171207D02*
X1908215Y171279D01*
G01X1908211Y171181D02*
X1908209Y171207D01*
G01X1908215Y176279D02*
X1908219Y176378D01*
G01X1908209Y176207D02*
X1908215Y176279D01*
G01X1908211Y176181D02*
X1908209Y176207D01*
G01X1908215Y181279D02*
X1908219Y181378D01*
G01X1908209Y181207D02*
X1908215Y181279D01*
G01X1908211Y181181D02*
X1908209Y181207D01*
G01X1908215Y186279D02*
X1908219Y186378D01*
G01X1908209Y186207D02*
X1908215Y186279D01*
G01X1908211Y186181D02*
X1908209Y186207D01*
G01X1908215Y191279D02*
X1908219Y191378D01*
G01X1908209Y191207D02*
X1908215Y191279D01*
G01X1908211Y191181D02*
X1908209Y191207D01*
G01X1908215Y196279D02*
X1908219Y196378D01*
G01X1908209Y196207D02*
X1908215Y196279D01*
G01X1908211Y196181D02*
X1908209Y196207D01*
G01X1894815Y205415D02*
X1894808Y205424D01*
G01X1894820Y205405D02*
X1894815Y205415D01*
G01X1894822Y205394D02*
X1894820Y205405D01*
G01X1894815Y199116D02*
X1894808Y199124D01*
G01X1894820Y199106D02*
X1894815Y199116D01*
G01X1894822Y199094D02*
X1894820Y199106D01*
G01X1894815Y202265D02*
X1894808Y202274D01*
G01X1894820Y202255D02*
X1894815Y202265D01*
G01X1894822Y202244D02*
X1894820Y202255D01*
G01X1894815Y208565D02*
X1894808Y208573D01*
G01X1894820Y208554D02*
X1894815Y208565D01*
G01X1894822Y208543D02*
X1894820Y208554D01*
G01X1894815Y211714D02*
X1894808Y211723D01*
G01X1894820Y211704D02*
X1894815Y211714D01*
G01X1894822Y211693D02*
X1894820Y211704D01*
G01X1893838Y210585D02*
X1893839Y210577D01*
G01X1893837Y210589D02*
X1893838Y210585D01*
G01Y210580D02*
X1893837Y210589D01*
G01X1893879Y211917D02*
X1893878Y211929D01*
G01X1893876Y211904D02*
X1893879Y211917D01*
G01X1893876Y211890D02*
Y211904D01*
G01X1893879Y208767D02*
X1893878Y208780D01*
G01X1893876Y208754D02*
X1893879Y208767D01*
G01X1893876Y208741D02*
Y208754D01*
G01X1893879Y205618D02*
X1893878Y205630D01*
G01X1893876Y205605D02*
X1893879Y205618D01*
G01X1893876Y205591D02*
Y205605D01*
G01X1893879Y202468D02*
X1893878Y202480D01*
G01X1893876Y202455D02*
X1893879Y202468D01*
G01X1893876Y202441D02*
Y202455D01*
G01X1893879Y199319D02*
X1893878Y199331D01*
G01X1893876Y199306D02*
X1893879Y199319D01*
G01X1893876Y199292D02*
Y199306D01*
G01X1907265Y194802D02*
Y194803D01*
G01X1907264Y194796D02*
X1907265Y194802D01*
G01X1907264Y194787D02*
Y194796D01*
G01X1907265Y189802D02*
Y189803D01*
G01X1907264Y189796D02*
X1907265Y189802D01*
G01X1907264Y189787D02*
Y189796D01*
G01X1907265Y184802D02*
Y184803D01*
G01X1907264Y184796D02*
X1907265Y184802D01*
G01X1907264Y184787D02*
Y184796D01*
G01X1907265Y179802D02*
Y179803D01*
G01X1907264Y179796D02*
X1907265Y179802D01*
G01X1907264Y179787D02*
Y179796D01*
G01X1907265Y174802D02*
Y174803D01*
G01X1907264Y174796D02*
X1907265Y174802D01*
G01X1907264Y174787D02*
Y174796D01*
G01X1907265Y169802D02*
Y169803D01*
G01X1907264Y169796D02*
X1907265Y169802D01*
G01X1907264Y169787D02*
Y169796D01*
G01X1907265Y164802D02*
Y164803D01*
G01X1907264Y164796D02*
X1907265Y164802D01*
G01X1907264Y164787D02*
Y164796D01*
G01X1893876Y210380D02*
X1893874Y210393D01*
G01X1893879Y210367D02*
X1893876Y210380D01*
G01X1893878Y210354D02*
X1893879Y210367D01*
G01X1893876Y207230D02*
X1893874Y207244D01*
G01X1893879Y207217D02*
X1893876Y207230D01*
G01X1893878Y207205D02*
X1893879Y207217D01*
G01X1893876Y204081D02*
X1893874Y204094D01*
G01X1893879Y204068D02*
X1893876Y204081D01*
G01X1893878Y204055D02*
X1893879Y204068D01*
G01X1893876Y200931D02*
X1893874Y200944D01*
G01X1893879Y200918D02*
X1893876Y200931D01*
G01X1893878Y200906D02*
X1893879Y200918D01*
G01X1893876Y197781D02*
X1893874Y197795D01*
G01X1893879Y197769D02*
X1893876Y197781D01*
G01X1893878Y197756D02*
X1893879Y197769D01*
G01X1894786Y211904D02*
X1894787Y211890D01*
G01X1894783Y211917D02*
X1894786Y211904D01*
G01X1894783Y211929D02*
Y211917D01*
G01X1894786Y208754D02*
X1894787Y208741D01*
G01X1894783Y208767D02*
X1894786Y208754D01*
G01X1894783Y208780D02*
Y208767D01*
G01X1894786Y205604D02*
X1894787Y205591D01*
G01X1894783Y205617D02*
X1894786Y205604D01*
G01X1894783Y205630D02*
Y205617D01*
G01X1894786Y202455D02*
X1894787Y202441D01*
G01X1894783Y202468D02*
X1894786Y202455D01*
G01X1894783Y202480D02*
Y202468D01*
G01X1894786Y199305D02*
X1894787Y199292D01*
G01X1894783Y199318D02*
X1894786Y199305D01*
G01X1894783Y199331D02*
Y199318D01*
G01X1893838Y204285D02*
X1893839Y204278D01*
G01X1893837Y204290D02*
X1893838Y204285D01*
G01X1893837Y204283D02*
Y204290D01*
G01X1894783Y210367D02*
Y210354D01*
G01X1894785Y210380D02*
X1894783Y210367D01*
G01X1894787Y210393D02*
X1894785Y210380D01*
G01X1894783Y207217D02*
Y207205D01*
G01X1894785Y207230D02*
X1894783Y207217D01*
G01X1894787Y207244D02*
X1894785Y207230D01*
G01X1894783Y204068D02*
Y204055D01*
G01X1894785Y204081D02*
X1894783Y204068D01*
G01X1894787Y204094D02*
X1894785Y204081D01*
G01X1894783Y200918D02*
Y200906D01*
G01X1894785Y200931D02*
X1894783Y200918D01*
G01X1894787Y200944D02*
X1894785Y200931D01*
G01X1894783Y197769D02*
Y197756D01*
G01X1894785Y197781D02*
X1894783Y197769D01*
G01X1894787Y197795D02*
X1894785Y197781D01*
G01X1893838Y197987D02*
X1893839Y197979D01*
G01X1893837Y197991D02*
X1893838Y197987D01*
G01X1893837Y197985D02*
Y197991D01*
G01X1893839Y211713D02*
Y211707D01*
G01X1893841Y211719D02*
X1893839Y211713D01*
G01X1893844Y211725D02*
X1893841Y211719D01*
G01X1893848Y211730D02*
X1893844Y211725D01*
G01X1893852Y211735D02*
X1893848Y211730D01*
G01X1893858Y211739D02*
X1893852Y211735D01*
G01X1893839Y208563D02*
Y208557D01*
G01X1893841Y208570D02*
X1893839Y208563D01*
G01X1893844Y208575D02*
X1893841Y208570D01*
G01X1893848Y208581D02*
X1893844Y208575D01*
G01X1893852Y208585D02*
X1893848Y208581D01*
G01X1893858Y208589D02*
X1893852Y208585D01*
G01X1893839Y205414D02*
Y205407D01*
G01X1893841Y205420D02*
X1893839Y205414D01*
G01X1893844Y205426D02*
X1893841Y205420D01*
G01X1893848Y205431D02*
X1893844Y205426D01*
G01X1893852Y205435D02*
X1893848Y205431D01*
G01X1893858Y205439D02*
X1893852Y205435D01*
G01X1894794Y210553D02*
X1894782Y210551D01*
G01X1894804Y210558D02*
X1894794Y210553D01*
G01Y207404D02*
X1894782Y207402D01*
G01X1894804Y207409D02*
X1894794Y207404D01*
G01Y204254D02*
X1894782Y204252D01*
G01X1894804Y204259D02*
X1894794Y204254D01*
G01Y201104D02*
X1894782Y201102D01*
G01X1894804Y201109D02*
X1894794Y201104D01*
G01Y197955D02*
X1894782Y197953D01*
G01X1894804Y197960D02*
X1894794Y197955D01*
G01X1893852Y211724D02*
X1893876Y211732D01*
G01X1893840Y211709D02*
X1893852Y211724D01*
G01X1893839Y211703D02*
X1893840Y211709D01*
G01X1893852Y208574D02*
X1893876Y208583D01*
G01X1893840Y208560D02*
X1893852Y208574D01*
G01X1893839Y208553D02*
X1893840Y208560D01*
G01X1893852Y205425D02*
X1893876Y205433D01*
G01X1893840Y205410D02*
X1893852Y205425D01*
G01X1893839Y205404D02*
X1893840Y205410D01*
G01X1893852Y202275D02*
X1893876Y202283D01*
G01X1893840Y202261D02*
X1893852Y202275D01*
G01X1893839Y202254D02*
X1893840Y202261D01*
G01X1893852Y199126D02*
X1893876Y199134D01*
G01X1893840Y199111D02*
X1893852Y199126D01*
G01X1893839Y199104D02*
X1893840Y199111D01*
G01X1894823Y211699D02*
Y211706D01*
G01X1894822Y211695D02*
X1894823Y211699D01*
G01X1894822Y211693D02*
Y211695D01*
G01X1894823Y208550D02*
Y208557D01*
G01X1894822Y208545D02*
X1894823Y208550D01*
G01X1894822Y208543D02*
Y208545D01*
G01X1894823Y205400D02*
Y205407D01*
G01X1894822Y205396D02*
X1894823Y205400D01*
G01X1894822Y205394D02*
Y205396D01*
G01X1894823Y202250D02*
Y202257D01*
G01X1894822Y202246D02*
X1894823Y202250D01*
G01X1894822Y202244D02*
Y202246D01*
G01X1894823Y199101D02*
Y199108D01*
G01X1894822Y199096D02*
X1894823Y199101D01*
G01X1894822Y199094D02*
Y199096D01*
G01X1893838Y207435D02*
X1893839Y207428D01*
G01X1893837Y207440D02*
X1893838Y207435D01*
G01X1893836Y207437D02*
X1893837Y207440D01*
G01X1893838Y211699D02*
X1893839Y211707D01*
G01X1893837Y211694D02*
X1893838Y211699D01*
G01X1893836Y211693D02*
X1893837Y211694D01*
G01X1893838Y208550D02*
X1893839Y208557D01*
G01X1893837Y208545D02*
X1893838Y208550D01*
G01X1893836Y208543D02*
X1893837Y208545D01*
G01X1893838Y205400D02*
X1893839Y205407D01*
G01X1893837Y205395D02*
X1893838Y205400D01*
G01X1893836Y205394D02*
X1893837Y205395D01*
G01X1893838Y202250D02*
X1893839Y202258D01*
G01X1893837Y202246D02*
X1893838Y202250D01*
G01X1893836Y202244D02*
X1893837Y202246D01*
G01X1893838Y199101D02*
X1893839Y199108D01*
G01X1893837Y199096D02*
X1893838Y199101D01*
G01X1893836Y199094D02*
X1893837Y199096D01*
G01X1894820Y210565D02*
X1894823Y210577D01*
G01X1894814Y210554D02*
X1894820Y210565D01*
G01X1894804Y210545D02*
X1894814Y210554D01*
G01X1894820Y207415D02*
X1894823Y207428D01*
G01X1894814Y207404D02*
X1894820Y207415D01*
G01X1894804Y207396D02*
X1894814Y207404D01*
G01X1894820Y204265D02*
X1894823Y204278D01*
G01X1894814Y204254D02*
X1894820Y204265D01*
G01X1894804Y204246D02*
X1894814Y204254D01*
G01X1894820Y201116D02*
X1894823Y201128D01*
G01X1894814Y201105D02*
X1894820Y201116D01*
G01X1894804Y201096D02*
X1894814Y201105D01*
G01X1894820Y197966D02*
X1894823Y197979D01*
G01X1894814Y197955D02*
X1894820Y197966D01*
G01X1894804Y197947D02*
X1894814Y197955D01*
G01X1893877Y211737D02*
Y211744D01*
G01Y211733D02*
Y211737D01*
G01X1893875Y211732D02*
X1893877Y211733D01*
G01Y208588D02*
Y208594D01*
G01Y208584D02*
Y208588D01*
G01X1893875Y208583D02*
X1893877Y208584D01*
G01Y205438D02*
Y205444D01*
G01Y205434D02*
Y205438D01*
G01X1893875Y205433D02*
X1893877Y205434D01*
G01Y202289D02*
Y202295D01*
G01Y202285D02*
Y202289D01*
G01X1893875Y202283D02*
X1893877Y202285D01*
G01Y199139D02*
Y199145D01*
G01Y199135D02*
Y199139D01*
G01X1893875Y199134D02*
X1893877Y199135D01*
G01X1893839Y202264D02*
Y202258D01*
G01X1893841Y202270D02*
X1893839Y202264D01*
G01X1893844Y202276D02*
X1893841Y202270D01*
G01X1893848Y202281D02*
X1893844Y202276D01*
G01X1893852Y202286D02*
X1893848Y202281D01*
G01X1893858Y202290D02*
X1893852Y202286D01*
G01X1893839Y199115D02*
Y199108D01*
G01X1893841Y199121D02*
X1893839Y199115D01*
G01X1893844Y199126D02*
X1893841Y199121D01*
G01X1893848Y199132D02*
X1893844Y199126D01*
G01X1893852Y199136D02*
X1893848Y199132D01*
G01X1893858Y199140D02*
X1893852Y199136D01*
G01X1893838Y201136D02*
X1893839Y201128D01*
G01X1893837Y201141D02*
X1893838Y201136D01*
G01X1893836Y201138D02*
X1893837Y201141D01*
G01X1894783Y211737D02*
Y211744D01*
G01Y211734D02*
Y211737D01*
G01X1894782Y211732D02*
X1894783Y211734D01*
G01Y208588D02*
Y208594D01*
G01Y208584D02*
Y208588D01*
G01X1894782Y208583D02*
X1894783Y208584D01*
G01Y205438D02*
Y205444D01*
G01Y205435D02*
Y205438D01*
G01X1894782Y205433D02*
X1894783Y205435D01*
G01Y202289D02*
Y202295D01*
G01Y202285D02*
Y202289D01*
G01X1894782Y202283D02*
X1894783Y202285D01*
G01Y199139D02*
Y199145D01*
G01Y199135D02*
Y199139D01*
G01X1894782Y199134D02*
X1894783Y199135D01*
G01X1908248Y194796D02*
Y194787D01*
G01X1908249Y194802D02*
X1908248Y194796D01*
G01X1908251Y194803D02*
X1908249Y194802D01*
G01X1908248Y189796D02*
Y189787D01*
G01X1908249Y189802D02*
X1908248Y189796D01*
G01X1908251Y189803D02*
X1908249Y189802D01*
G01X1908248Y184796D02*
Y184787D01*
G01X1908249Y184802D02*
X1908248Y184796D01*
G01X1908251Y184803D02*
X1908249Y184802D01*
G01X1908248Y179796D02*
Y179787D01*
G01X1908249Y179802D02*
X1908248Y179796D01*
G01X1908251Y179803D02*
X1908249Y179802D01*
G01X1908248Y174796D02*
Y174787D01*
G01X1908249Y174802D02*
X1908248Y174796D01*
G01X1908251Y174803D02*
X1908249Y174802D01*
G01X1908248Y169796D02*
Y169787D01*
G01X1908249Y169802D02*
X1908248Y169796D01*
G01X1908251Y169803D02*
X1908249Y169802D01*
G01X1908248Y164796D02*
Y164787D01*
G01X1908249Y164802D02*
X1908248Y164796D01*
G01X1908251Y164803D02*
X1908249Y164802D01*
G01X1894822Y199097D02*
X1894823Y199108D01*
G01X1894822Y202246D02*
X1894823Y202257D01*
G01X1894822Y205396D02*
X1894823Y205407D01*
G01X1894822Y208546D02*
X1894823Y208557D01*
G01X1894822Y211695D02*
X1894823Y211706D01*
G01X1908248Y166155D02*
Y166164D01*
G01Y171155D02*
Y171164D01*
G01Y176155D02*
Y176164D01*
G01Y181155D02*
Y181164D01*
G01Y186155D02*
Y186164D01*
G01Y191155D02*
Y191164D01*
G01Y196155D02*
Y196164D01*
G01X1909429Y166181D02*
Y164803D01*
G01Y171181D02*
Y169803D01*
G01Y176181D02*
Y174803D01*
G01Y181181D02*
Y179803D01*
G01Y186181D02*
Y184803D01*
G01Y191181D02*
Y189803D01*
G01Y196181D02*
Y194803D01*
G01X1908858Y219035D02*
Y196949D01*
G01X1908248Y166156D02*
Y166299D01*
G01Y176156D02*
Y176299D01*
G01Y171156D02*
Y171299D01*
G01Y186156D02*
Y186299D01*
G01Y181156D02*
Y181299D01*
G01Y196156D02*
Y196299D01*
G01Y191156D02*
Y191299D01*
G01Y194311D02*
Y196673D01*
G01Y189311D02*
Y191673D01*
G01Y184311D02*
Y186673D01*
G01Y179311D02*
Y181673D01*
G01Y174311D02*
Y176673D01*
G01Y169311D02*
Y171673D01*
G01Y164311D02*
Y166673D01*
G01X1907677Y217854D02*
Y198130D01*
G01X1907264Y166673D02*
Y164311D01*
G01Y171673D02*
Y169311D01*
G01Y176673D02*
Y174311D01*
G01Y181673D02*
Y179311D01*
G01Y186673D02*
Y184311D01*
G01Y191673D02*
Y189311D01*
G01Y196673D02*
Y194311D01*
G01X1894823Y210394D02*
Y211890D01*
G01Y207244D02*
Y208740D01*
G01Y204094D02*
Y205591D01*
G01Y200945D02*
Y202441D01*
G01Y197795D02*
Y199291D01*
G01X1894783Y197942D02*
Y197795D01*
G01Y201091D02*
Y200944D01*
G01Y202441D02*
Y202295D01*
G01Y199292D02*
Y199145D01*
G01Y207391D02*
Y207244D01*
G01Y204241D02*
Y204094D01*
G01Y205591D02*
Y205444D01*
G01Y210540D02*
Y210393D01*
G01Y211890D02*
Y211744D01*
G01Y208741D02*
Y208594D01*
G01X1893878Y210393D02*
Y210540D01*
G01Y211744D02*
Y211891D01*
G01Y208594D02*
Y208741D01*
G01Y207243D02*
Y207391D01*
G01Y204094D02*
Y204241D01*
G01Y205444D02*
Y205591D01*
G01Y200944D02*
Y201091D01*
G01Y202295D02*
Y202442D01*
G01Y199145D02*
Y199292D01*
G01Y197794D02*
Y197942D01*
G01X1893839Y202441D02*
Y200945D01*
G01Y199291D02*
Y197795D01*
G01Y205591D02*
Y204094D01*
G01Y211890D02*
Y210394D01*
G01Y208740D02*
Y207244D01*
G01X1892657Y199134D02*
Y197953D01*
G01Y202283D02*
Y201102D01*
G01Y208583D02*
Y207402D01*
G01Y205433D02*
Y204252D01*
G01Y211732D02*
Y210551D01*
G01X1892323Y220197D02*
Y195787D01*
G01X1891929D02*
Y220197D01*
G01X1888898Y210551D02*
Y211732D01*
G01Y207402D02*
Y208583D01*
G01Y204252D02*
Y205433D01*
G01Y201102D02*
Y202283D01*
G01Y197953D02*
Y199134D01*
G01X1894823Y210577D02*
X1894822Y210588D01*
G01X1894823Y207428D02*
X1894822Y207439D01*
G01X1894823Y204278D02*
X1894822Y204289D01*
G01X1894823Y201128D02*
X1894822Y201139D01*
G01X1894823Y197979D02*
X1894822Y197990D01*
G01X1907677Y198130D02*
X1908858Y196949D01*
G01X1903740Y198130D02*
X1904921Y196949D01*
G01X1893836Y207437D02*
X1893725Y207441D01*
G01X1893836Y201138D02*
X1893725Y201142D01*
G01X1893836Y210587D02*
X1893725Y210591D01*
G01X1894783Y211929D02*
X1893878D01*
G01X1894823Y211890D02*
X1893839D01*
G01X1894782Y211732D02*
X1888898D01*
G01Y211693D02*
X1894822D01*
G01X1893091Y210591D02*
X1892657D01*
G01X1894821D02*
X1888898D01*
G01X1894782Y210551D02*
X1888898D01*
G01X1893839Y210394D02*
X1894823D01*
G01X1893878Y210354D02*
X1894783D01*
G01Y208780D02*
X1893878D01*
G01X1894823Y208740D02*
X1893839D01*
G01X1894782Y208583D02*
X1888898D01*
G01Y208543D02*
X1894822D01*
G01X1893091Y207441D02*
X1892657D01*
G01X1894821D02*
X1888898D01*
G01X1894782Y207402D02*
X1888898D01*
G01X1893839Y207244D02*
X1894823D01*
G01X1893878Y207205D02*
X1894783D01*
G01Y205630D02*
X1893878D01*
G01X1894823Y205591D02*
X1893839D01*
G01X1894782Y205433D02*
X1888898D01*
G01Y205394D02*
X1894822D01*
G01X1894821Y204291D02*
X1888898D01*
G01X1894782Y204252D02*
X1888898D01*
G01X1893839Y204094D02*
X1894823D01*
G01X1893878Y204055D02*
X1894783D01*
G01Y202480D02*
X1893878D01*
G01X1894823Y202441D02*
X1893839D01*
G01X1894782Y202283D02*
X1888898D01*
G01Y202244D02*
X1894822D01*
G01X1893091Y201142D02*
X1892657D01*
G01X1894821D02*
X1888898D01*
G01X1894782Y201102D02*
X1888898D01*
G01X1893839Y200945D02*
X1894823D01*
G01X1893878Y200906D02*
X1894783D01*
G01Y199331D02*
X1893878D01*
G01X1894823Y199291D02*
X1893839D01*
G01X1894782Y199134D02*
X1888898D01*
G01Y199094D02*
X1894822D01*
G01X1907677Y198130D02*
X1903740D01*
G01X1894821Y197992D02*
X1888898D01*
G01X1894782Y197953D02*
X1888898D01*
G01X1893839Y197795D02*
X1894823D01*
G01X1893878Y197756D02*
X1894783D01*
G01X1908858Y196949D02*
X1904921D01*
G01X1908248Y196673D02*
X1907264D01*
G01X1907265Y196181D02*
X1912598D01*
G01Y196142D02*
X1908250D01*
G01X1895276Y195787D02*
X1891929D01*
G01X1912598Y194803D02*
X1907265D01*
G01X1907264Y194311D02*
X1908248D01*
G01Y191673D02*
X1907264D01*
G01X1907265Y191181D02*
X1912598D01*
G01Y191142D02*
X1908250D01*
G01X1912598Y189803D02*
X1907265D01*
G01X1907264Y189311D02*
X1908248D01*
G01Y186673D02*
X1907264D01*
G01X1907265Y186181D02*
X1912598D01*
G01Y186142D02*
X1908250D01*
G01X1912598Y184803D02*
X1907265D01*
G01X1907264Y184311D02*
X1908248D01*
G01Y181673D02*
X1907264D01*
G01X1907265Y181181D02*
X1912598D01*
G01Y181142D02*
X1908250D01*
G01X1912598Y179803D02*
X1907265D01*
G01X1907264Y179311D02*
X1908248D01*
G01Y176673D02*
X1907264D01*
G01X1907265Y176181D02*
X1912598D01*
G01Y176142D02*
X1908250D01*
G01X1912598Y174803D02*
X1907265D01*
G01X1907264Y174311D02*
X1908248D01*
G01Y171673D02*
X1907264D01*
G01X1907265Y171181D02*
X1912598D01*
G01Y171142D02*
X1908250D01*
G01X1912598Y169803D02*
X1907265D01*
G01X1907264Y169311D02*
X1908248D01*
G01X1907264Y196377D02*
X1908219Y196378D01*
G01X1908248Y194607D02*
X1907264Y194606D01*
G01Y191377D02*
X1908219Y191378D01*
G01X1908248Y189607D02*
X1907264Y189606D01*
G01Y186377D02*
X1908219Y186378D01*
G01X1908248Y184607D02*
X1907264Y184606D01*
G01Y181377D02*
X1908219Y181378D01*
G01X1908248Y179607D02*
X1907264Y179606D01*
G01Y176377D02*
X1908219Y176378D01*
G01X1908248Y174607D02*
X1907264Y174606D01*
G01Y171377D02*
X1908219Y171378D01*
G01X1908248Y169607D02*
X1907264Y169606D01*
G01X1908248Y166673D02*
X1907264D01*
G01X1907265Y166181D02*
X1912598D01*
G01Y166142D02*
X1908250D01*
G01X1912598Y164803D02*
X1907265D01*
G01X1907264Y164311D02*
X1908248D01*
G01X1907264Y166377D02*
X1908219Y166378D01*
G01X1908248Y164607D02*
X1907264Y164606D01*
G01X1893841Y214862D02*
X1893836Y214843D01*
G01X1893856Y214877D02*
X1893841Y214862D01*
G01X1893876Y214882D02*
X1893856Y214877D01*
G01X1893841Y218012D02*
X1893836Y217992D01*
G01X1893856Y218026D02*
X1893841Y218012D01*
G01X1893876Y218031D02*
X1893856Y218026D01*
G01X1894816Y213720D02*
X1894821Y213740D01*
G01X1894802Y213706D02*
X1894816Y213720D01*
G01X1894782Y213701D02*
X1894802Y213706D01*
G01X1894816Y216870D02*
X1894821Y216890D01*
G01X1894802Y216856D02*
X1894816Y216870D01*
G01X1894782Y216850D02*
X1894802Y216856D01*
G01X1894822Y213719D02*
X1894823Y213727D01*
G01X1894820Y213713D02*
X1894822Y213719D01*
G01X1894816Y213706D02*
X1894820Y213713D01*
G01X1894811Y213700D02*
X1894816Y213706D01*
G01X1894805Y213696D02*
X1894811Y213700D01*
G01X1894798Y213693D02*
X1894805Y213696D01*
G01X1894791Y213691D02*
X1894798Y213693D01*
G01X1894783Y213690D02*
X1894791Y213691D01*
G01X1893861Y214890D02*
X1893858Y214888D01*
G01X1893864Y214891D02*
X1893861Y214890D01*
G01X1893867Y214892D02*
X1893864Y214891D01*
G01X1893871Y214893D02*
X1893867Y214892D01*
G01X1893874Y214893D02*
X1893871D01*
G01X1893878D02*
X1893874D01*
G01X1894800Y216843D02*
X1894804Y216844D01*
G01X1894797Y216842D02*
X1894800Y216843D01*
G01X1894794Y216841D02*
X1894797Y216842D01*
G01X1894791Y216840D02*
X1894794Y216841D01*
G01X1894787Y216839D02*
X1894791Y216840D01*
G01X1894783Y216839D02*
X1894787D01*
G01X1893861Y218039D02*
X1893858Y218038D01*
G01X1893864Y218041D02*
X1893861Y218039D01*
G01X1893867Y218042D02*
X1893864Y218041D01*
G01X1893871Y218042D02*
X1893867D01*
G01X1893874Y218043D02*
X1893871Y218042D01*
G01X1893878Y218043D02*
X1893874D01*
G01X1894813Y214880D02*
X1894817Y214875D01*
G01X1894809Y214885D02*
X1894813Y214880D01*
G01X1894803Y214889D02*
X1894809Y214885D01*
G01X1894797Y214891D02*
X1894803Y214889D01*
G01X1894790Y214893D02*
X1894797Y214891D01*
G01X1894783Y214893D02*
X1894790D01*
G01X1894813Y218030D02*
X1894817Y218025D01*
G01X1894809Y218034D02*
X1894813Y218030D01*
G01X1894803Y218038D02*
X1894809Y218034D01*
G01X1894797Y218041D02*
X1894803Y218038D01*
G01X1894790Y218043D02*
X1894797Y218041D01*
G01X1894783Y218043D02*
X1894790D01*
G01X1893839Y213719D02*
Y213727D01*
G01X1893842Y213713D02*
X1893839Y213719D01*
G01X1893845Y213706D02*
X1893842Y213713D01*
G01X1893850Y213700D02*
X1893845Y213706D01*
G01X1893856Y213696D02*
X1893850Y213700D01*
G01X1893863Y213693D02*
X1893856Y213696D01*
G01X1893870Y213691D02*
X1893863Y213693D01*
G01X1893878Y213690D02*
X1893870Y213691D01*
G01X1893839Y216869D02*
Y216876D01*
G01X1893842Y216862D02*
X1893839Y216869D01*
G01X1893845Y216856D02*
X1893842Y216862D01*
G01X1893850Y216850D02*
X1893845Y216856D01*
G01X1893856Y216845D02*
X1893850Y216850D01*
G01X1893863Y216842D02*
X1893856Y216845D01*
G01X1893870Y216840D02*
X1893863Y216842D01*
G01X1893878Y216839D02*
X1893870Y216840D01*
G01X1894793Y214881D02*
X1894802Y214876D01*
G01X1894782Y214882D02*
X1894793Y214881D01*
G01Y218030D02*
X1894802Y218026D01*
G01X1894782Y218031D02*
X1894793Y218030D01*
G01X1893839Y213731D02*
Y213727D01*
G01X1893840Y213724D02*
X1893839Y213731D01*
G01X1893852Y213709D02*
X1893840Y213724D01*
G01X1893876Y213701D02*
X1893852Y213709D01*
G01X1893839Y216880D02*
Y216876D01*
G01X1893840Y216874D02*
X1893839Y216880D01*
G01X1893852Y216859D02*
X1893840Y216874D01*
G01X1893876Y216850D02*
X1893852Y216859D01*
G01X1908235Y221173D02*
X1908246Y221157D01*
G01X1908211Y221181D02*
X1908235Y221173D01*
G01Y226173D02*
X1908246Y226157D01*
G01X1908211Y226181D02*
X1908235Y226173D01*
G01Y231173D02*
X1908246Y231157D01*
G01X1908211Y231181D02*
X1908235Y231173D01*
G01Y236173D02*
X1908246Y236157D01*
G01X1908211Y236181D02*
X1908235Y236173D01*
G01Y241173D02*
X1908246Y241157D01*
G01X1908211Y241181D02*
X1908235Y241173D01*
G01Y246173D02*
X1908246Y246157D01*
G01X1908211Y246181D02*
X1908235Y246173D01*
G01Y251173D02*
X1908246Y251157D01*
G01X1908211Y251181D02*
X1908235Y251173D01*
G01Y256173D02*
X1908246Y256157D01*
G01X1908211Y256181D02*
X1908235Y256173D01*
G01X1894791Y214881D02*
X1894782Y214882D01*
G01X1894800Y214878D02*
X1894791Y214881D01*
G01X1894808Y214872D02*
X1894800Y214878D01*
G01X1894791Y218030D02*
X1894782Y218031D01*
G01X1894800Y218027D02*
X1894791Y218030D01*
G01X1894808Y218022D02*
X1894800Y218027D01*
G01X1893878Y213696D02*
Y213690D01*
G01X1893877Y213700D02*
X1893878Y213696D01*
G01X1893876Y213701D02*
X1893877Y213700D01*
G01X1893878Y216846D02*
Y216839D01*
G01X1893877Y216849D02*
X1893878Y216846D01*
G01X1893876Y216850D02*
X1893877Y216849D01*
G01X1908248Y221148D02*
Y221156D01*
G01X1908249Y221144D02*
X1908248Y221148D01*
G01X1908250Y221142D02*
X1908249Y221144D01*
G01X1908248Y226148D02*
Y226156D01*
G01X1908249Y226144D02*
X1908248Y226148D01*
G01X1908250Y226142D02*
X1908249Y226144D01*
G01X1908248Y231148D02*
Y231156D01*
G01X1908249Y231144D02*
X1908248Y231148D01*
G01X1908250Y231142D02*
X1908249Y231144D01*
G01X1908248Y236148D02*
Y236156D01*
G01X1908249Y236144D02*
X1908248Y236148D01*
G01X1908250Y236142D02*
X1908249Y236144D01*
G01X1908248Y241148D02*
Y241156D01*
G01X1908249Y241144D02*
X1908248Y241148D01*
G01X1908250Y241142D02*
X1908249Y241144D01*
G01X1908248Y246148D02*
Y246156D01*
G01X1908249Y246144D02*
X1908248Y246148D01*
G01X1908250Y246142D02*
X1908249Y246144D01*
G01X1908248Y251148D02*
Y251156D01*
G01X1908249Y251144D02*
X1908248Y251148D01*
G01X1908250Y251142D02*
X1908249Y251144D01*
G01X1908248Y256148D02*
Y256156D01*
G01X1908249Y256144D02*
X1908248Y256148D01*
G01X1908250Y256142D02*
X1908249Y256144D01*
G01X1893861Y213704D02*
X1893876Y213701D01*
G01X1893849Y213711D02*
X1893861Y213704D01*
G01X1893837Y213731D02*
X1893849Y213711D01*
G01X1894823Y213734D02*
Y213727D01*
G01X1894822Y213739D02*
X1894823Y213734D01*
G01X1894821Y213740D02*
X1894822Y213739D01*
G01X1894823Y216884D02*
Y216876D01*
G01X1894822Y216889D02*
X1894823Y216884D01*
G01X1894821Y216890D02*
X1894822Y216889D01*
G01X1893861Y216853D02*
X1893876Y216850D01*
G01X1893848Y216861D02*
X1893861Y216853D01*
G01X1893837Y216881D02*
X1893848Y216861D01*
G01X1894822Y214863D02*
X1894823Y214856D01*
G01X1894820Y214869D02*
X1894822Y214863D01*
G01X1894817Y214875D02*
X1894820Y214869D01*
G01X1894822Y218013D02*
X1894823Y218006D01*
G01X1894820Y218019D02*
X1894822Y218013D01*
G01X1894817Y218025D02*
X1894820Y218019D01*
G01X1894784Y216845D02*
Y216839D01*
G01X1894783Y216849D02*
X1894784Y216845D01*
G01X1894782Y216850D02*
X1894783Y216849D01*
G01X1907264Y221189D02*
Y221198D01*
G01X1907265Y221183D02*
X1907264Y221189D01*
G01X1907265Y221181D02*
Y221183D01*
G01X1907264Y226189D02*
Y226198D01*
G01X1907265Y226183D02*
X1907264Y226189D01*
G01X1907265Y226181D02*
Y226183D01*
G01X1907264Y231189D02*
Y231198D01*
G01X1907265Y231183D02*
X1907264Y231189D01*
G01X1907265Y231181D02*
Y231183D01*
G01X1907264Y236189D02*
Y236198D01*
G01X1907265Y236183D02*
X1907264Y236189D01*
G01X1907265Y236181D02*
Y236183D01*
G01X1907264Y241189D02*
Y241198D01*
G01X1907265Y241183D02*
X1907264Y241189D01*
G01X1907265Y241181D02*
Y241183D01*
G01X1907264Y246189D02*
Y246198D01*
G01X1907265Y246183D02*
X1907264Y246189D01*
G01X1907265Y246181D02*
Y246183D01*
G01X1907264Y251189D02*
Y251198D01*
G01X1907265Y251183D02*
X1907264Y251189D01*
G01X1907265Y251181D02*
Y251183D01*
G01X1907264Y256189D02*
Y256198D01*
G01X1907265Y256183D02*
X1907264Y256189D01*
G01X1907265Y256181D02*
Y256183D01*
G01X1908240Y221325D02*
X1908248Y221299D01*
G01X1908230Y221352D02*
X1908240Y221325D01*
G01X1908219Y221378D02*
X1908230Y221352D01*
G01X1908240Y226325D02*
X1908248Y226299D01*
G01X1908230Y226352D02*
X1908240Y226325D01*
G01X1908219Y226378D02*
X1908230Y226352D01*
G01X1908240Y231325D02*
X1908248Y231299D01*
G01X1908230Y231352D02*
X1908240Y231325D01*
G01X1908219Y231378D02*
X1908230Y231352D01*
G01X1908240Y236325D02*
X1908248Y236299D01*
G01X1908230Y236352D02*
X1908240Y236325D01*
G01X1908219Y236378D02*
X1908230Y236352D01*
G01X1908240Y241325D02*
X1908248Y241299D01*
G01X1908230Y241352D02*
X1908240Y241325D01*
G01X1908219Y241378D02*
X1908230Y241352D01*
G01X1908240Y246325D02*
X1908248Y246299D01*
G01X1908230Y246352D02*
X1908240Y246325D01*
G01X1908219Y246378D02*
X1908230Y246352D01*
G01X1908240Y251325D02*
X1908248Y251299D01*
G01X1908230Y251352D02*
X1908240Y251325D01*
G01X1908219Y251378D02*
X1908230Y251352D01*
G01X1908240Y256325D02*
X1908248Y256299D01*
G01X1908230Y256352D02*
X1908240Y256325D01*
G01X1908219Y256378D02*
X1908230Y256352D01*
G01X1908231Y221176D02*
X1908211Y221181D01*
G01X1908245Y221162D02*
X1908231Y221176D01*
G01X1908250Y221142D02*
X1908245Y221162D01*
G01X1908231Y226176D02*
X1908211Y226181D01*
G01X1908245Y226162D02*
X1908231Y226176D01*
G01X1908250Y226142D02*
X1908245Y226162D01*
G01X1908231Y231176D02*
X1908211Y231181D01*
G01X1908245Y231162D02*
X1908231Y231176D01*
G01X1908250Y231142D02*
X1908245Y231162D01*
G01X1908231Y236176D02*
X1908211Y236181D01*
G01X1908245Y236162D02*
X1908231Y236176D01*
G01X1908250Y236142D02*
X1908245Y236162D01*
G01X1908231Y241176D02*
X1908211Y241181D01*
G01X1908245Y241162D02*
X1908231Y241176D01*
G01X1908250Y241142D02*
X1908245Y241162D01*
G01X1908231Y246176D02*
X1908211Y246181D01*
G01X1908245Y246162D02*
X1908231Y246176D01*
G01X1908250Y246142D02*
X1908245Y246162D01*
G01X1908231Y251176D02*
X1908211Y251181D01*
G01X1908245Y251162D02*
X1908231Y251176D01*
G01X1908250Y251142D02*
X1908245Y251162D01*
G01X1908231Y256176D02*
X1908211Y256181D01*
G01X1908245Y256162D02*
X1908231Y256176D01*
G01X1908250Y256142D02*
X1908245Y256162D01*
G01X1908215Y221279D02*
X1908219Y221378D01*
G01X1908209Y221207D02*
X1908215Y221279D01*
G01X1908211Y221181D02*
X1908209Y221207D01*
G01X1908215Y226279D02*
X1908219Y226378D01*
G01X1908209Y226207D02*
X1908215Y226279D01*
G01X1908211Y226181D02*
X1908209Y226207D01*
G01X1908215Y231279D02*
X1908219Y231378D01*
G01X1908209Y231207D02*
X1908215Y231279D01*
G01X1908211Y231181D02*
X1908209Y231207D01*
G01X1908215Y236279D02*
X1908219Y236378D01*
G01X1908209Y236207D02*
X1908215Y236279D01*
G01X1908211Y236181D02*
X1908209Y236207D01*
G01X1908215Y241279D02*
X1908219Y241378D01*
G01X1908209Y241207D02*
X1908215Y241279D01*
G01X1908211Y241181D02*
X1908209Y241207D01*
G01X1908215Y246279D02*
X1908219Y246378D01*
G01X1908209Y246207D02*
X1908215Y246279D01*
G01X1908211Y246181D02*
X1908209Y246207D01*
G01X1908215Y251279D02*
X1908219Y251378D01*
G01X1908209Y251207D02*
X1908215Y251279D01*
G01X1908211Y251181D02*
X1908209Y251207D01*
G01X1908215Y256279D02*
X1908219Y256378D01*
G01X1908209Y256207D02*
X1908215Y256279D01*
G01X1908211Y256181D02*
X1908209Y256207D01*
G01X1894815Y214864D02*
X1894808Y214872D01*
G01X1894820Y214854D02*
X1894815Y214864D01*
G01X1894822Y214843D02*
X1894820Y214854D01*
G01X1894815Y218013D02*
X1894808Y218022D01*
G01X1894820Y218003D02*
X1894815Y218013D01*
G01X1894822Y217992D02*
X1894820Y218003D01*
G01X1893879Y218216D02*
X1893878Y218228D01*
G01X1893876Y218203D02*
X1893879Y218216D01*
G01X1893876Y218189D02*
Y218203D01*
G01X1893879Y215067D02*
X1893878Y215079D01*
G01X1893876Y215054D02*
X1893879Y215067D01*
G01X1893876Y215040D02*
Y215054D01*
G01X1907265Y259802D02*
Y259803D01*
G01X1907264Y259796D02*
X1907265Y259802D01*
G01X1907264Y259787D02*
Y259796D01*
G01X1907265Y254802D02*
Y254803D01*
G01X1907264Y254796D02*
X1907265Y254802D01*
G01X1907264Y254787D02*
Y254796D01*
G01X1907265Y249802D02*
Y249803D01*
G01X1907264Y249796D02*
X1907265Y249802D01*
G01X1907264Y249787D02*
Y249796D01*
G01X1907265Y244802D02*
Y244803D01*
G01X1907264Y244796D02*
X1907265Y244802D01*
G01X1907264Y244787D02*
Y244796D01*
G01X1907265Y239802D02*
Y239803D01*
G01X1907264Y239796D02*
X1907265Y239802D01*
G01X1907264Y239787D02*
Y239796D01*
G01X1907265Y234802D02*
Y234803D01*
G01X1907264Y234796D02*
X1907265Y234802D01*
G01X1907264Y234787D02*
Y234796D01*
G01X1907265Y229802D02*
Y229803D01*
G01X1907264Y229796D02*
X1907265Y229802D01*
G01X1907264Y229787D02*
Y229796D01*
G01X1907265Y224802D02*
Y224803D01*
G01X1907264Y224796D02*
X1907265Y224802D01*
G01X1907264Y224787D02*
Y224796D01*
G01X1907265Y219802D02*
Y219803D01*
G01X1907264Y219796D02*
X1907265Y219802D01*
G01X1907264Y219787D02*
Y219796D01*
G01X1893838Y216884D02*
X1893839Y216876D01*
G01X1893837Y216889D02*
X1893838Y216884D01*
G01X1893837Y216881D02*
Y216889D01*
G01X1893876Y216679D02*
X1893874Y216693D01*
G01X1893879Y216666D02*
X1893876Y216679D01*
G01X1893878Y216654D02*
X1893879Y216666D01*
G01X1893876Y213530D02*
X1893874Y213543D01*
G01X1893879Y213517D02*
X1893876Y213530D01*
G01X1893878Y213504D02*
X1893879Y213517D01*
G01X1894786Y218203D02*
X1894787Y218189D01*
G01X1894783Y218216D02*
X1894786Y218203D01*
G01X1894783Y218228D02*
Y218216D01*
G01X1894786Y215053D02*
X1894787Y215040D01*
G01X1894783Y215066D02*
X1894786Y215053D01*
G01X1894783Y215079D02*
Y215066D01*
G01X1893838Y213734D02*
X1893839Y213727D01*
G01X1893837Y213739D02*
X1893838Y213734D01*
G01X1893837Y213732D02*
Y213739D01*
G01X1894783Y216666D02*
Y216654D01*
G01X1894785Y216679D02*
X1894783Y216666D01*
G01X1894787Y216693D02*
X1894785Y216679D01*
G01X1894783Y213517D02*
Y213504D01*
G01X1894785Y213530D02*
X1894783Y213517D01*
G01X1894787Y213543D02*
X1894785Y213530D01*
G01X1893877Y218037D02*
Y218043D01*
G01Y218033D02*
Y218037D01*
G01X1893875Y218031D02*
X1893877Y218033D01*
G01Y214887D02*
Y214893D01*
G01Y214883D02*
Y214887D01*
G01X1893875Y214882D02*
X1893877Y214883D01*
G01X1893839Y218012D02*
Y218006D01*
G01X1893841Y218019D02*
X1893839Y218012D01*
G01X1893844Y218024D02*
X1893841Y218019D01*
G01X1893848Y218030D02*
X1893844Y218024D01*
G01X1893852Y218034D02*
X1893848Y218030D01*
G01X1893858Y218038D02*
X1893852Y218034D01*
G01X1893839Y214863D02*
Y214856D01*
G01X1893841Y214869D02*
X1893839Y214863D01*
G01X1893844Y214874D02*
X1893841Y214869D01*
G01X1893848Y214880D02*
X1893844Y214874D01*
G01X1893852Y214884D02*
X1893848Y214880D01*
G01X1893858Y214888D02*
X1893852Y214884D01*
G01X1894794Y216852D02*
X1894782Y216850D01*
G01X1894804Y216857D02*
X1894794Y216852D01*
G01Y213703D02*
X1894782Y213701D01*
G01X1894804Y213708D02*
X1894794Y213703D01*
G01X1893852Y218023D02*
X1893876Y218031D01*
G01X1893840Y218009D02*
X1893852Y218023D01*
G01X1893839Y218002D02*
X1893840Y218009D01*
G01X1893852Y214874D02*
X1893876Y214882D01*
G01X1893840Y214859D02*
X1893852Y214874D01*
G01X1893839Y214852D02*
X1893840Y214859D01*
G01X1894823Y217998D02*
Y218006D01*
G01X1894822Y217994D02*
X1894823Y217998D01*
G01X1894822Y217992D02*
Y217994D01*
G01X1894823Y214849D02*
Y214856D01*
G01X1894822Y214844D02*
X1894823Y214849D01*
G01X1894822Y214843D02*
Y214844D01*
G01X1894783Y218037D02*
Y218043D01*
G01Y218033D02*
Y218037D01*
G01X1894782Y218031D02*
X1894783Y218033D01*
G01Y214887D02*
Y214893D01*
G01Y214883D02*
Y214887D01*
G01X1894782Y214882D02*
X1894783Y214883D01*
G01X1908248Y259796D02*
Y259787D01*
G01X1908249Y259802D02*
X1908248Y259796D01*
G01X1908251Y259803D02*
X1908249Y259802D01*
G01X1908248Y254796D02*
Y254787D01*
G01X1908249Y254802D02*
X1908248Y254796D01*
G01X1908251Y254803D02*
X1908249Y254802D01*
G01X1908248Y249796D02*
Y249787D01*
G01X1908249Y249802D02*
X1908248Y249796D01*
G01X1908251Y249803D02*
X1908249Y249802D01*
G01X1908248Y244796D02*
Y244787D01*
G01X1908249Y244802D02*
X1908248Y244796D01*
G01X1908251Y244803D02*
X1908249Y244802D01*
G01X1908248Y239796D02*
Y239787D01*
G01X1908249Y239802D02*
X1908248Y239796D01*
G01X1908251Y239803D02*
X1908249Y239802D01*
G01X1908248Y234796D02*
Y234787D01*
G01X1908249Y234802D02*
X1908248Y234796D01*
G01X1908251Y234803D02*
X1908249Y234802D01*
G01X1908248Y229796D02*
Y229787D01*
G01X1908249Y229802D02*
X1908248Y229796D01*
G01X1908251Y229803D02*
X1908249Y229802D01*
G01X1908248Y224796D02*
Y224787D01*
G01X1908249Y224802D02*
X1908248Y224796D01*
G01X1908251Y224803D02*
X1908249Y224802D01*
G01X1908248Y219796D02*
Y219787D01*
G01X1908249Y219802D02*
X1908248Y219796D01*
G01X1908251Y219803D02*
X1908249Y219802D01*
G01X1893838Y217998D02*
X1893839Y218006D01*
G01X1893837Y217994D02*
X1893838Y217998D01*
G01X1893836Y217992D02*
X1893837Y217994D01*
G01X1893838Y214849D02*
X1893839Y214856D01*
G01X1893837Y214844D02*
X1893838Y214849D01*
G01X1893836Y214843D02*
X1893837Y214844D01*
G01X1894820Y216864D02*
X1894823Y216876D01*
G01X1894814Y216853D02*
X1894820Y216864D01*
G01X1894804Y216844D02*
X1894814Y216853D01*
G01X1907677Y217854D02*
X1908858Y219035D01*
G01X1903740Y217854D02*
X1904921Y219035D01*
G01X1894822Y214845D02*
X1894823Y214856D01*
G01X1894822Y217994D02*
X1894823Y218006D01*
G01X1908248Y221155D02*
Y221164D01*
G01Y226155D02*
Y226164D01*
G01Y231155D02*
Y231164D01*
G01Y236155D02*
Y236164D01*
G01Y241155D02*
Y241164D01*
G01Y246155D02*
Y246164D01*
G01Y251155D02*
Y251164D01*
G01Y256155D02*
Y256164D01*
G01X1909429Y221181D02*
Y219803D01*
G01Y226181D02*
Y224803D01*
G01Y231181D02*
Y229803D01*
G01Y236181D02*
Y234803D01*
G01Y241181D02*
Y239803D01*
G01Y246181D02*
Y244803D01*
G01Y251181D02*
Y249803D01*
G01Y256181D02*
Y254803D01*
G01Y261181D02*
Y259803D01*
G01X1908248Y226156D02*
Y226299D01*
G01Y221156D02*
Y221299D01*
G01Y236156D02*
Y236299D01*
G01Y231156D02*
Y231299D01*
G01Y246156D02*
Y246299D01*
G01Y241156D02*
Y241299D01*
G01Y256156D02*
Y256299D01*
G01Y251156D02*
Y251299D01*
G01Y259311D02*
Y261673D01*
G01Y254311D02*
Y256673D01*
G01Y249311D02*
Y251673D01*
G01Y244311D02*
Y246673D01*
G01Y239311D02*
Y241673D01*
G01Y234311D02*
Y236673D01*
G01Y229311D02*
Y231673D01*
G01Y224311D02*
Y226673D01*
G01Y219311D02*
Y221673D01*
G01X1907264D02*
Y219311D01*
G01Y226673D02*
Y224311D01*
G01Y231673D02*
Y229311D01*
G01Y236673D02*
Y234311D01*
G01Y241673D02*
Y239311D01*
G01Y246673D02*
Y244311D01*
G01Y251673D02*
Y249311D01*
G01Y256673D02*
Y254311D01*
G01Y261673D02*
Y259311D01*
G01X1904921Y295492D02*
Y219035D01*
G01X1903740Y294311D02*
Y217854D01*
G01X1895276Y299232D02*
Y220197D01*
G01X1894823Y216693D02*
Y218189D01*
G01Y213543D02*
Y215039D01*
G01X1894783Y216839D02*
Y216693D01*
G01Y213690D02*
Y213543D01*
G01Y215040D02*
Y214893D01*
G01Y218189D02*
Y218043D01*
G01X1893878D02*
Y218190D01*
G01Y216692D02*
Y216839D01*
G01Y213543D02*
Y213690D01*
G01Y214893D02*
Y215040D01*
G01X1893839Y215039D02*
Y213543D01*
G01Y218189D02*
Y216693D01*
G01X1892657Y218031D02*
Y216850D01*
G01Y214882D02*
Y213701D01*
G01X1888898Y216850D02*
Y218031D01*
G01Y213701D02*
Y214882D01*
G01X1894823Y216876D02*
X1894822Y216887D01*
G01X1894823Y213727D02*
X1894822Y213738D01*
G01X1894782Y213701D02*
X1894785Y213690D01*
G01X1893725Y216890D02*
X1893837Y216881D01*
G01X1912598Y259803D02*
X1907265D01*
G01X1907264Y259311D02*
X1908248D01*
G01Y256673D02*
X1907264D01*
G01X1908248Y259607D02*
X1907264Y259606D01*
G01X1907265Y256181D02*
X1912598D01*
G01Y256142D02*
X1908250D01*
G01X1912598Y254803D02*
X1907265D01*
G01X1907264Y254311D02*
X1908248D01*
G01Y251673D02*
X1907264D01*
G01X1907265Y251181D02*
X1912598D01*
G01Y251142D02*
X1908250D01*
G01X1912598Y249803D02*
X1907265D01*
G01X1907264Y249311D02*
X1908248D01*
G01Y246673D02*
X1907264D01*
G01X1907265Y246181D02*
X1912598D01*
G01Y246142D02*
X1908250D01*
G01X1912598Y244803D02*
X1907265D01*
G01X1907264Y244311D02*
X1908248D01*
G01Y241673D02*
X1907264D01*
G01X1907265Y241181D02*
X1912598D01*
G01Y241142D02*
X1908250D01*
G01X1912598Y239803D02*
X1907265D01*
G01X1907264Y239311D02*
X1908248D01*
G01Y236673D02*
X1907264D01*
G01X1907265Y236181D02*
X1912598D01*
G01Y236142D02*
X1908250D01*
G01X1912598Y234803D02*
X1907265D01*
G01X1907264Y234311D02*
X1908248D01*
G01Y231673D02*
X1907264D01*
G01X1907265Y231181D02*
X1912598D01*
G01Y231142D02*
X1908250D01*
G01X1912598Y229803D02*
X1907265D01*
G01X1907264Y229311D02*
X1908248D01*
G01Y226673D02*
X1907264D01*
G01X1907265Y226181D02*
X1912598D01*
G01Y226142D02*
X1908250D01*
G01X1912598Y224803D02*
X1907265D01*
G01X1907264Y224311D02*
X1908248D01*
G01Y221673D02*
X1907264D01*
G01X1907265Y221181D02*
X1912598D01*
G01Y221142D02*
X1908250D01*
G01X1895276Y220197D02*
X1891929D01*
G01X1912598Y219803D02*
X1907265D01*
G01X1907264Y219311D02*
X1908248D01*
G01X1904921Y219035D02*
X1908858D01*
G01X1894783Y218228D02*
X1893878D01*
G01X1894823Y218189D02*
X1893839D01*
G01X1894782Y218031D02*
X1888898D01*
G01Y217992D02*
X1894822D01*
G01X1903740Y217854D02*
X1907677D01*
G01X1894821Y216890D02*
X1888898D01*
G01X1894782Y216850D02*
X1888898D01*
G01X1893839Y216693D02*
X1894823D01*
G01X1893878Y216654D02*
X1894783D01*
G01Y215079D02*
X1893878D01*
G01X1894823Y215039D02*
X1893839D01*
G01X1894782Y214882D02*
X1888898D01*
G01Y214843D02*
X1894822D01*
G01X1894821Y213740D02*
X1888898D01*
G01X1894782Y213701D02*
X1888898D01*
G01X1893839Y213543D02*
X1894823D01*
G01X1893878Y213504D02*
X1894783D01*
G01X1907264Y256377D02*
X1908219Y256378D01*
G01X1908248Y254607D02*
X1907264Y254606D01*
G01Y251377D02*
X1908219Y251378D01*
G01X1908248Y249607D02*
X1907264Y249606D01*
G01Y246377D02*
X1908219Y246378D01*
G01X1908248Y244607D02*
X1907264Y244606D01*
G01Y241377D02*
X1908219Y241378D01*
G01X1908248Y239607D02*
X1907264Y239606D01*
G01Y236377D02*
X1908219Y236378D01*
G01X1908248Y234607D02*
X1907264Y234606D01*
G01Y231377D02*
X1908219Y231378D01*
G01X1908248Y229607D02*
X1907264Y229606D01*
G01Y226377D02*
X1908219Y226378D01*
G01X1908248Y224607D02*
X1907264Y224606D01*
G01Y221377D02*
X1908219Y221378D01*
G01X1908248Y219607D02*
X1907264Y219606D01*
G01X1908235Y261173D02*
X1908246Y261157D01*
G01X1908211Y261181D02*
X1908235Y261173D01*
G01Y266173D02*
X1908246Y266157D01*
G01X1908211Y266181D02*
X1908235Y266173D01*
G01Y271173D02*
X1908246Y271157D01*
G01X1908211Y271181D02*
X1908235Y271173D01*
G01Y276173D02*
X1908246Y276157D01*
G01X1908211Y276181D02*
X1908235Y276173D01*
G01Y281173D02*
X1908246Y281157D01*
G01X1908211Y281181D02*
X1908235Y281173D01*
G01Y286173D02*
X1908246Y286157D01*
G01X1908211Y286181D02*
X1908235Y286173D01*
G01Y291173D02*
X1908246Y291157D01*
G01X1908211Y291181D02*
X1908235Y291173D01*
G01X1908248Y261148D02*
Y261156D01*
G01X1908249Y261144D02*
X1908248Y261148D01*
G01X1908250Y261142D02*
X1908249Y261144D01*
G01X1908248Y266148D02*
Y266156D01*
G01X1908249Y266144D02*
X1908248Y266148D01*
G01X1908250Y266142D02*
X1908249Y266144D01*
G01X1908248Y271148D02*
Y271156D01*
G01X1908249Y271144D02*
X1908248Y271148D01*
G01X1908250Y271142D02*
X1908249Y271144D01*
G01X1908248Y276148D02*
Y276156D01*
G01X1908249Y276144D02*
X1908248Y276148D01*
G01X1908250Y276142D02*
X1908249Y276144D01*
G01X1908248Y281148D02*
Y281156D01*
G01X1908249Y281144D02*
X1908248Y281148D01*
G01X1908250Y281142D02*
X1908249Y281144D01*
G01X1908248Y286148D02*
Y286156D01*
G01X1908249Y286144D02*
X1908248Y286148D01*
G01X1908250Y286142D02*
X1908249Y286144D01*
G01X1908248Y291148D02*
Y291156D01*
G01X1908249Y291144D02*
X1908248Y291148D01*
G01X1908250Y291142D02*
X1908249Y291144D01*
G01X1907264Y261189D02*
Y261198D01*
G01X1907265Y261183D02*
X1907264Y261189D01*
G01X1907265Y261181D02*
Y261183D01*
G01X1907264Y266189D02*
Y266198D01*
G01X1907265Y266183D02*
X1907264Y266189D01*
G01X1907265Y266181D02*
Y266183D01*
G01X1907264Y271189D02*
Y271198D01*
G01X1907265Y271183D02*
X1907264Y271189D01*
G01X1907265Y271181D02*
Y271183D01*
G01X1907264Y276189D02*
Y276198D01*
G01X1907265Y276183D02*
X1907264Y276189D01*
G01X1907265Y276181D02*
Y276183D01*
G01X1907264Y281189D02*
Y281198D01*
G01X1907265Y281183D02*
X1907264Y281189D01*
G01X1907265Y281181D02*
Y281183D01*
G01X1907264Y286189D02*
Y286198D01*
G01X1907265Y286183D02*
X1907264Y286189D01*
G01X1907265Y286181D02*
Y286183D01*
G01X1907264Y291189D02*
Y291198D01*
G01X1907265Y291183D02*
X1907264Y291189D01*
G01X1907265Y291181D02*
Y291183D01*
G01X1908240Y261325D02*
X1908248Y261299D01*
G01X1908230Y261352D02*
X1908240Y261325D01*
G01X1908219Y261378D02*
X1908230Y261352D01*
G01X1908240Y266325D02*
X1908248Y266299D01*
G01X1908230Y266352D02*
X1908240Y266325D01*
G01X1908219Y266378D02*
X1908230Y266352D01*
G01X1908240Y271325D02*
X1908248Y271299D01*
G01X1908230Y271352D02*
X1908240Y271325D01*
G01X1908219Y271378D02*
X1908230Y271352D01*
G01X1908240Y276325D02*
X1908248Y276299D01*
G01X1908230Y276352D02*
X1908240Y276325D01*
G01X1908219Y276378D02*
X1908230Y276352D01*
G01X1908240Y281325D02*
X1908248Y281299D01*
G01X1908230Y281352D02*
X1908240Y281325D01*
G01X1908219Y281378D02*
X1908230Y281352D01*
G01X1908240Y286325D02*
X1908248Y286299D01*
G01X1908230Y286352D02*
X1908240Y286325D01*
G01X1908219Y286378D02*
X1908230Y286352D01*
G01X1908240Y291325D02*
X1908248Y291299D01*
G01X1908230Y291352D02*
X1908240Y291325D01*
G01X1908219Y291378D02*
X1908230Y291352D01*
G01X1908231Y261176D02*
X1908211Y261181D01*
G01X1908245Y261162D02*
X1908231Y261176D01*
G01X1908250Y261142D02*
X1908245Y261162D01*
G01X1908231Y266176D02*
X1908211Y266181D01*
G01X1908245Y266162D02*
X1908231Y266176D01*
G01X1908250Y266142D02*
X1908245Y266162D01*
G01X1908231Y271176D02*
X1908211Y271181D01*
G01X1908245Y271162D02*
X1908231Y271176D01*
G01X1908250Y271142D02*
X1908245Y271162D01*
G01X1908231Y276176D02*
X1908211Y276181D01*
G01X1908245Y276162D02*
X1908231Y276176D01*
G01X1908250Y276142D02*
X1908245Y276162D01*
G01X1908231Y281176D02*
X1908211Y281181D01*
G01X1908245Y281162D02*
X1908231Y281176D01*
G01X1908250Y281142D02*
X1908245Y281162D01*
G01X1908231Y286176D02*
X1908211Y286181D01*
G01X1908245Y286162D02*
X1908231Y286176D01*
G01X1908250Y286142D02*
X1908245Y286162D01*
G01X1908231Y291176D02*
X1908211Y291181D01*
G01X1908245Y291162D02*
X1908231Y291176D01*
G01X1908250Y291142D02*
X1908245Y291162D01*
G01X1908215Y261279D02*
X1908219Y261378D01*
G01X1908209Y261207D02*
X1908215Y261279D01*
G01X1908211Y261181D02*
X1908209Y261207D01*
G01X1908215Y266279D02*
X1908219Y266378D01*
G01X1908209Y266207D02*
X1908215Y266279D01*
G01X1908211Y266181D02*
X1908209Y266207D01*
G01X1908215Y271279D02*
X1908219Y271378D01*
G01X1908209Y271207D02*
X1908215Y271279D01*
G01X1908211Y271181D02*
X1908209Y271207D01*
G01X1908215Y276279D02*
X1908219Y276378D01*
G01X1908209Y276207D02*
X1908215Y276279D01*
G01X1908211Y276181D02*
X1908209Y276207D01*
G01X1908215Y281279D02*
X1908219Y281378D01*
G01X1908209Y281207D02*
X1908215Y281279D01*
G01X1908211Y281181D02*
X1908209Y281207D01*
G01X1908215Y286279D02*
X1908219Y286378D01*
G01X1908209Y286207D02*
X1908215Y286279D01*
G01X1908211Y286181D02*
X1908209Y286207D01*
G01X1908215Y291279D02*
X1908219Y291378D01*
G01X1908209Y291207D02*
X1908215Y291279D01*
G01X1908211Y291181D02*
X1908209Y291207D01*
G01X1907265Y289802D02*
Y289803D01*
G01X1907264Y289796D02*
X1907265Y289802D01*
G01X1907264Y289787D02*
Y289796D01*
G01X1907265Y284802D02*
Y284803D01*
G01X1907264Y284796D02*
X1907265Y284802D01*
G01X1907264Y284787D02*
Y284796D01*
G01X1907265Y279802D02*
Y279803D01*
G01X1907264Y279796D02*
X1907265Y279802D01*
G01X1907264Y279787D02*
Y279796D01*
G01X1907265Y274802D02*
Y274803D01*
G01X1907264Y274796D02*
X1907265Y274802D01*
G01X1907264Y274787D02*
Y274796D01*
G01X1907265Y269802D02*
Y269803D01*
G01X1907264Y269796D02*
X1907265Y269802D01*
G01X1907264Y269787D02*
Y269796D01*
G01X1907265Y264802D02*
Y264803D01*
G01X1907264Y264796D02*
X1907265Y264802D01*
G01X1907264Y264787D02*
Y264796D01*
G01X1908248Y289796D02*
Y289787D01*
G01X1908249Y289802D02*
X1908248Y289796D01*
G01X1908251Y289803D02*
X1908249Y289802D01*
G01X1908248Y284796D02*
Y284787D01*
G01X1908249Y284802D02*
X1908248Y284796D01*
G01X1908251Y284803D02*
X1908249Y284802D01*
G01X1908248Y279796D02*
Y279787D01*
G01X1908249Y279802D02*
X1908248Y279796D01*
G01X1908251Y279803D02*
X1908249Y279802D01*
G01X1908248Y274796D02*
Y274787D01*
G01X1908249Y274802D02*
X1908248Y274796D01*
G01X1908251Y274803D02*
X1908249Y274802D01*
G01X1908248Y269796D02*
Y269787D01*
G01X1908249Y269802D02*
X1908248Y269796D01*
G01X1908251Y269803D02*
X1908249Y269802D01*
G01X1908248Y264796D02*
Y264787D01*
G01X1908249Y264802D02*
X1908248Y264796D01*
G01X1908251Y264803D02*
X1908249Y264802D01*
G01X1900197Y307579D02*
G03X1899016Y306398I0J-1181D01*
G01X1906496D02*
G03X1905315Y307579I-1181J0D01*
G01X1904646Y302303D02*
G03I-1890J0D01*
G01X1905118D02*
G03I-2362J0D01*
G01X1903740Y294311D02*
X1904921Y295492D01*
G01X1900271Y299232D02*
X1901575Y301201D01*
G01X1906247Y307123D02*
X1903937Y302894D01*
G01X1908248Y261155D02*
Y261164D01*
G01Y266155D02*
Y266164D01*
G01Y271155D02*
Y271164D01*
G01Y276155D02*
Y276164D01*
G01Y281155D02*
Y281164D01*
G01Y286155D02*
Y286164D01*
G01Y291155D02*
Y291164D01*
G01X1909429Y266181D02*
Y264803D01*
G01Y271181D02*
Y269803D01*
G01Y276181D02*
Y274803D01*
G01Y281181D02*
Y279803D01*
G01Y286181D02*
Y284803D01*
G01Y291181D02*
Y289803D01*
G01X1908248Y266156D02*
Y266299D01*
G01Y261156D02*
Y261299D01*
G01Y276156D02*
Y276299D01*
G01Y271156D02*
Y271299D01*
G01Y286156D02*
Y286299D01*
G01Y281156D02*
Y281299D01*
G01Y291156D02*
Y291299D01*
G01Y289311D02*
Y291673D01*
G01Y284311D02*
Y286673D01*
G01Y279311D02*
Y281673D01*
G01Y274311D02*
Y276673D01*
G01Y269311D02*
Y271673D01*
G01Y264311D02*
Y266673D01*
G01X1907264D02*
Y264311D01*
G01Y271673D02*
Y269311D01*
G01Y276673D02*
Y274311D01*
G01Y281673D02*
Y279311D01*
G01Y286673D02*
Y284311D01*
G01Y291673D02*
Y289311D01*
G01X1906496Y306398D02*
Y297854D01*
G01X1903937Y302894D02*
Y301201D01*
G01X1901575D02*
Y302894D01*
G01X1899016Y297854D02*
Y306398D01*
G01X1891929Y316083D02*
Y300335D01*
G01X1901575Y302894D02*
X1899265Y307123D01*
G01X1903937Y301201D02*
X1905241Y299232D01*
G01X1897047Y295492D02*
X1898228Y294311D01*
G01X1895276Y296988D02*
X1891929Y300335D01*
G01X1913583Y307618D02*
X1891929D01*
G01X1900197Y307579D02*
X1905315D01*
G01X1901575Y302894D02*
X1903937D01*
G01X1901575Y301201D02*
X1903937D01*
G01X1895276Y299232D02*
X1909646D01*
G01X1895276Y297854D02*
X1899016D01*
G01X1909646D02*
X1906496D01*
G01X1895276Y296988D02*
X1910236D01*
G01X1897047Y295492D02*
X1904921D01*
G01X1898228Y294311D02*
X1903740D01*
G01X1908248Y291673D02*
X1907264D01*
G01X1907265Y291181D02*
X1912598D01*
G01Y291142D02*
X1908250D01*
G01X1912598Y289803D02*
X1907265D01*
G01X1907264Y289311D02*
X1908248D01*
G01Y286673D02*
X1907264D01*
G01X1907265Y286181D02*
X1912598D01*
G01Y286142D02*
X1908250D01*
G01X1912598Y284803D02*
X1907265D01*
G01X1907264Y284311D02*
X1908248D01*
G01Y281673D02*
X1907264D01*
G01X1907265Y281181D02*
X1912598D01*
G01Y281142D02*
X1908250D01*
G01X1912598Y279803D02*
X1907265D01*
G01X1907264Y279311D02*
X1908248D01*
G01Y276673D02*
X1907264D01*
G01X1907265Y276181D02*
X1912598D01*
G01Y276142D02*
X1908250D01*
G01X1912598Y274803D02*
X1907265D01*
G01X1907264Y274311D02*
X1908248D01*
G01Y271673D02*
X1907264D01*
G01X1907265Y271181D02*
X1912598D01*
G01Y271142D02*
X1908250D01*
G01X1912598Y269803D02*
X1907265D01*
G01X1907264Y269311D02*
X1908248D01*
G01Y266673D02*
X1907264D01*
G01X1907265Y266181D02*
X1912598D01*
G01Y266142D02*
X1908250D01*
G01X1912598Y264803D02*
X1907265D01*
G01X1907264Y264311D02*
X1908248D01*
G01Y261673D02*
X1907264D01*
G01X1907265Y261181D02*
X1912598D01*
G01Y261142D02*
X1908250D01*
G01X1907264Y291377D02*
X1908219Y291378D01*
G01X1908248Y289607D02*
X1907264Y289606D01*
G01Y286377D02*
X1908219Y286378D01*
G01X1908248Y284607D02*
X1907264Y284606D01*
G01Y281377D02*
X1908219Y281378D01*
G01X1908248Y279607D02*
X1907264Y279606D01*
G01Y276377D02*
X1908219Y276378D01*
G01X1908248Y274607D02*
X1907264Y274606D01*
G01Y271377D02*
X1908219Y271378D01*
G01X1908248Y269607D02*
X1907264Y269606D01*
G01Y266377D02*
X1908219Y266378D01*
G01X1908248Y264607D02*
X1907264Y264606D01*
G01Y261377D02*
X1908219Y261378D01*
G01X1906693Y316673D02*
G03X1906102Y317264I-591J0D01*
G01X1899409D02*
G03X1898819Y316673I1J-591D01*
G01X1901575Y315492D02*
G03Y313524I0J-984D01*
G01X1903937D02*
G03Y315492I0J984D01*
G01X1893898Y318051D02*
G03X1891929Y316083I-1J-1968D01*
G01X1906693Y310571D02*
Y316673D01*
G01X1898819Y310571D02*
Y316673D01*
G01X1911614Y318051D02*
X1893898D01*
G01X1906102Y317264D02*
X1899409D01*
G01X1903937Y315492D02*
X1901575D01*
G01Y313524D02*
X1903937D01*
G01X1906693Y312146D02*
X1898819D01*
G01Y310571D02*
X1906693D01*
G01X1862795Y374803D02*
G03X1863976I590J0D01*
G01Y368504D02*
G03X1862795I-590J0D01*
G01Y374803D02*
G03X1863976I590J0D01*
G01Y368504D02*
G03X1862795I-590J0D01*
G01X1864764D02*
Y374803D01*
G01Y368504D02*
Y374803D01*
G01D02*
X1863976D01*
G01X1864764D02*
X1863976D01*
G01Y368504D02*
X1864764D01*
G01X1863976D02*
X1864764D01*
G01X1902953Y478346D02*
G03X1886417I-8268J0D01*
G01Y470472D02*
Y478346D01*
G01Y470472D02*
G03X1902953I8268J0D01*
G01Y478346D02*
Y470472D01*
G01X1886417D02*
G03X1902953I8268J0D01*
G01Y478346D02*
G03X1886417I-8268J0D01*
G01X1902953D02*
Y470472D01*
G01X1886417Y478346D02*
Y470472D01*
G01X1898819Y592067D02*
G03X1899409Y591476I591J0D01*
G01X1906102D02*
G03X1906693Y592067I0J591D01*
G01X1903937Y593248D02*
G03Y595217I0J985D01*
G01X1901575D02*
G03Y593248I0J-985D01*
G01X1891929Y592657D02*
G03X1893898Y590689I1969J1D01*
G01X1906693Y598169D02*
Y592067D01*
G01X1898819Y598169D02*
Y592067D01*
G01X1891929Y608406D02*
Y592657D01*
G01X1906693Y598169D02*
X1898819D01*
G01Y596594D02*
X1906693D01*
G01X1903937Y595217D02*
X1901575D01*
G01Y593248D02*
X1903937D01*
G01X1906102Y591476D02*
X1899409D01*
G01X1911614Y590689D02*
X1893898D01*
G01X1908235Y618929D02*
X1908246Y618913D01*
G01X1908211Y618937D02*
X1908235Y618929D01*
G01Y623929D02*
X1908246Y623913D01*
G01X1908211Y623937D02*
X1908235Y623929D01*
G01Y628929D02*
X1908246Y628913D01*
G01X1908211Y628937D02*
X1908235Y628929D01*
G01Y633929D02*
X1908246Y633913D01*
G01X1908211Y633937D02*
X1908235Y633929D01*
G01Y638929D02*
X1908246Y638913D01*
G01X1908211Y638937D02*
X1908235Y638929D01*
G01Y643929D02*
X1908246Y643913D01*
G01X1908211Y643937D02*
X1908235Y643929D01*
G01X1908248Y618904D02*
Y618911D01*
G01X1908249Y618900D02*
X1908248Y618904D01*
G01X1908250Y618898D02*
X1908249Y618900D01*
G01X1908248Y623904D02*
Y623911D01*
G01X1908249Y623900D02*
X1908248Y623904D01*
G01X1908250Y623898D02*
X1908249Y623900D01*
G01X1908248Y628904D02*
Y628911D01*
G01X1908249Y628900D02*
X1908248Y628904D01*
G01X1908250Y628898D02*
X1908249Y628900D01*
G01X1908248Y633904D02*
Y633911D01*
G01X1908249Y633900D02*
X1908248Y633904D01*
G01X1908250Y633898D02*
X1908249Y633900D01*
G01X1908248Y638904D02*
Y638911D01*
G01X1908249Y638900D02*
X1908248Y638904D01*
G01X1908250Y638898D02*
X1908249Y638900D01*
G01X1908248Y643904D02*
Y643911D01*
G01X1908249Y643900D02*
X1908248Y643904D01*
G01X1908250Y643898D02*
X1908249Y643900D01*
G01X1908248Y647552D02*
Y647543D01*
G01X1908249Y647557D02*
X1908248Y647552D01*
G01X1908251Y647559D02*
X1908249Y647557D01*
G01X1907264Y618944D02*
Y618954D01*
G01X1907265Y618939D02*
X1907264Y618944D01*
G01X1907265Y618937D02*
Y618939D01*
G01X1907264Y623944D02*
Y623954D01*
G01X1907265Y623939D02*
X1907264Y623944D01*
G01X1907265Y623937D02*
Y623939D01*
G01X1907264Y628944D02*
Y628954D01*
G01X1907265Y628939D02*
X1907264Y628944D01*
G01X1907265Y628937D02*
Y628939D01*
G01X1907264Y633944D02*
Y633954D01*
G01X1907265Y633939D02*
X1907264Y633944D01*
G01X1907265Y633937D02*
Y633939D01*
G01X1907264Y638944D02*
Y638954D01*
G01X1907265Y638939D02*
X1907264Y638944D01*
G01X1907265Y638937D02*
Y638939D01*
G01X1907264Y643944D02*
Y643954D01*
G01X1907265Y643939D02*
X1907264Y643944D01*
G01X1907265Y643937D02*
Y643939D01*
G01X1908240Y619081D02*
X1908248Y619055D01*
G01X1908230Y619107D02*
X1908240Y619081D01*
G01X1908219Y619134D02*
X1908230Y619107D01*
G01X1908240Y624081D02*
X1908248Y624055D01*
G01X1908230Y624107D02*
X1908240Y624081D01*
G01X1908219Y624134D02*
X1908230Y624107D01*
G01X1908240Y629081D02*
X1908248Y629055D01*
G01X1908230Y629107D02*
X1908240Y629081D01*
G01X1908219Y629134D02*
X1908230Y629107D01*
G01X1908240Y634081D02*
X1908248Y634055D01*
G01X1908230Y634107D02*
X1908240Y634081D01*
G01X1908219Y634134D02*
X1908230Y634107D01*
G01X1908240Y639081D02*
X1908248Y639055D01*
G01X1908230Y639107D02*
X1908240Y639081D01*
G01X1908219Y639134D02*
X1908230Y639107D01*
G01X1908240Y644081D02*
X1908248Y644055D01*
G01X1908230Y644107D02*
X1908240Y644081D01*
G01X1908219Y644134D02*
X1908230Y644107D01*
G01X1908248Y642552D02*
Y642543D01*
G01X1908249Y642557D02*
X1908248Y642552D01*
G01X1908251Y642559D02*
X1908249Y642557D01*
G01X1908248Y637552D02*
Y637543D01*
G01X1908249Y637557D02*
X1908248Y637552D01*
G01X1908251Y637559D02*
X1908249Y637557D01*
G01X1908248Y632552D02*
Y632543D01*
G01X1908249Y632557D02*
X1908248Y632552D01*
G01X1908251Y632559D02*
X1908249Y632557D01*
G01X1908248Y627552D02*
Y627543D01*
G01X1908249Y627557D02*
X1908248Y627552D01*
G01X1908251Y627559D02*
X1908249Y627557D01*
G01X1908248Y622552D02*
Y622543D01*
G01X1908249Y622557D02*
X1908248Y622552D01*
G01X1908251Y622559D02*
X1908249Y622557D01*
G01X1908248Y617552D02*
Y617543D01*
G01X1908249Y617557D02*
X1908248Y617552D01*
G01X1908251Y617559D02*
X1908249Y617557D01*
G01X1908231Y618932D02*
X1908211Y618937D01*
G01X1908245Y618918D02*
X1908231Y618932D01*
G01X1908250Y618898D02*
X1908245Y618918D01*
G01X1908231Y623932D02*
X1908211Y623937D01*
G01X1908245Y623918D02*
X1908231Y623932D01*
G01X1908250Y623898D02*
X1908245Y623918D01*
G01X1908231Y628932D02*
X1908211Y628937D01*
G01X1908245Y628918D02*
X1908231Y628932D01*
G01X1908250Y628898D02*
X1908245Y628918D01*
G01X1908231Y633932D02*
X1908211Y633937D01*
G01X1908245Y633918D02*
X1908231Y633932D01*
G01X1908250Y633898D02*
X1908245Y633918D01*
G01X1908231Y638932D02*
X1908211Y638937D01*
G01X1908245Y638918D02*
X1908231Y638932D01*
G01X1908250Y638898D02*
X1908245Y638918D01*
G01X1908231Y643932D02*
X1908211Y643937D01*
G01X1908245Y643918D02*
X1908231Y643932D01*
G01X1908250Y643898D02*
X1908245Y643918D01*
G01X1908215Y619035D02*
X1908219Y619134D01*
G01X1908209Y618963D02*
X1908215Y619035D01*
G01X1908211Y618937D02*
X1908209Y618963D01*
G01X1908215Y624035D02*
X1908219Y624134D01*
G01X1908209Y623963D02*
X1908215Y624035D01*
G01X1908211Y623937D02*
X1908209Y623963D01*
G01X1908215Y629035D02*
X1908219Y629134D01*
G01X1908209Y628963D02*
X1908215Y629035D01*
G01X1908211Y628937D02*
X1908209Y628963D01*
G01X1908215Y634035D02*
X1908219Y634134D01*
G01X1908209Y633963D02*
X1908215Y634035D01*
G01X1908211Y633937D02*
X1908209Y633963D01*
G01X1908215Y639035D02*
X1908219Y639134D01*
G01X1908209Y638963D02*
X1908215Y639035D01*
G01X1908211Y638937D02*
X1908209Y638963D01*
G01X1908215Y644035D02*
X1908219Y644134D01*
G01X1908209Y643963D02*
X1908215Y644035D01*
G01X1908211Y643937D02*
X1908209Y643963D01*
G01X1907265Y647557D02*
Y647559D01*
G01X1907264Y647552D02*
X1907265Y647557D01*
G01X1907264Y647543D02*
Y647552D01*
G01X1907265Y642557D02*
Y642559D01*
G01X1907264Y642552D02*
X1907265Y642557D01*
G01X1907264Y642543D02*
Y642552D01*
G01X1907265Y637557D02*
Y637559D01*
G01X1907264Y637552D02*
X1907265Y637557D01*
G01X1907264Y637543D02*
Y637552D01*
G01X1907265Y632557D02*
Y632559D01*
G01X1907264Y632552D02*
X1907265Y632557D01*
G01X1907264Y632543D02*
Y632552D01*
G01X1907265Y627557D02*
Y627559D01*
G01X1907264Y627552D02*
X1907265Y627557D01*
G01X1907264Y627543D02*
Y627552D01*
G01X1907265Y622557D02*
Y622559D01*
G01X1907264Y622552D02*
X1907265Y622557D01*
G01X1907264Y622543D02*
Y622552D01*
G01X1907265Y617557D02*
Y617559D01*
G01X1907264Y617552D02*
X1907265Y617557D01*
G01X1907264Y617543D02*
Y617552D01*
G01X1903858Y606437D02*
G03I-1102J0D01*
G01X1905315Y601161D02*
G03X1906496Y602343I0J1181D01*
G01X1899016D02*
G03X1900197Y601161I1181J-1D01*
G01X1904331Y606437D02*
G03I-1575J0D01*
G01X1908248Y618911D02*
Y618920D01*
G01Y623911D02*
Y623920D01*
G01Y628911D02*
Y628920D01*
G01Y633911D02*
Y633920D01*
G01Y638911D02*
Y638920D01*
G01Y643911D02*
Y643920D01*
G01X1909646Y751988D02*
Y609508D01*
G01X1909429Y618937D02*
Y617559D01*
G01Y623937D02*
Y622559D01*
G01Y628937D02*
Y627559D01*
G01Y633937D02*
Y632559D01*
G01Y638937D02*
Y637559D01*
G01Y643937D02*
Y642559D01*
G01Y648937D02*
Y647559D01*
G01X1908248Y647067D02*
Y649429D01*
G01Y642067D02*
Y644429D01*
G01Y637067D02*
Y639429D01*
G01Y632067D02*
Y634429D01*
G01Y627067D02*
Y629429D01*
G01Y622067D02*
Y624429D01*
G01Y617067D02*
Y619429D01*
G01X1907264D02*
Y617067D01*
G01Y624429D02*
Y622067D01*
G01Y629429D02*
Y627067D01*
G01Y634429D02*
Y632067D01*
G01Y639429D02*
Y637067D01*
G01Y644429D02*
Y642067D01*
G01Y649429D02*
Y647067D01*
G01X1906496Y610886D02*
Y602343D01*
G01X1904921Y649705D02*
Y613248D01*
G01X1903937Y607539D02*
Y605846D01*
G01X1903740Y650886D02*
Y614429D01*
G01X1901575Y605846D02*
Y607539D01*
G01X1899016Y602343D02*
Y610886D01*
G01X1898228Y614429D02*
Y747067D01*
G01X1897047Y613248D02*
Y748248D01*
G01X1895276Y648543D02*
Y609508D01*
G01X1905241D02*
X1903937Y607539D01*
G01X1899265Y601617D02*
X1901575Y605846D01*
G01X1903937D02*
X1906247Y601617D01*
G01X1898228Y614429D02*
X1897047Y613248D01*
G01X1895276Y611752D02*
X1891929Y608406D01*
G01X1901575Y607539D02*
X1900271Y609508D01*
G01X1903740Y614429D02*
X1904921Y613248D01*
G01X1912598Y647559D02*
X1907265D01*
G01X1907264Y647067D02*
X1908248D01*
G01Y644429D02*
X1907264D01*
G01X1907265Y643937D02*
X1912598D01*
G01Y643898D02*
X1908250D01*
G01X1912598Y642559D02*
X1907265D01*
G01X1907264Y642067D02*
X1908248D01*
G01Y639429D02*
X1907264D01*
G01X1907265Y638937D02*
X1912598D01*
G01Y638898D02*
X1908250D01*
G01X1912598Y637559D02*
X1907265D01*
G01X1907264Y637067D02*
X1908248D01*
G01Y634429D02*
X1907264D01*
G01X1907265Y633937D02*
X1912598D01*
G01Y633898D02*
X1908250D01*
G01X1912598Y632559D02*
X1907265D01*
G01X1907264Y632067D02*
X1908248D01*
G01Y629429D02*
X1907264D01*
G01X1907265Y628937D02*
X1912598D01*
G01Y628898D02*
X1908250D01*
G01X1912598Y627559D02*
X1907265D01*
G01X1907264Y627067D02*
X1908248D01*
G01Y624429D02*
X1907264D01*
G01X1907265Y623937D02*
X1912598D01*
G01Y623898D02*
X1908250D01*
G01X1912598Y622559D02*
X1907265D01*
G01X1907264Y622067D02*
X1908248D01*
G01Y619429D02*
X1907264D01*
G01X1907265Y618937D02*
X1912598D01*
G01Y618898D02*
X1908250D01*
G01X1912598Y617559D02*
X1907265D01*
G01X1907264Y617067D02*
X1908248D01*
G01Y647363D02*
X1907264Y647362D01*
G01Y644133D02*
X1908219Y644134D01*
G01X1908248Y642363D02*
X1907264Y642362D01*
G01Y639133D02*
X1908219Y639134D01*
G01X1908248Y637363D02*
X1907264Y637362D01*
G01Y634133D02*
X1908219Y634134D01*
G01X1908248Y632363D02*
X1907264Y632362D01*
G01Y629133D02*
X1908219Y629134D01*
G01X1908248Y627363D02*
X1907264Y627362D01*
G01Y624133D02*
X1908219Y624134D01*
G01X1908248Y622363D02*
X1907264Y622362D01*
G01Y619133D02*
X1908219Y619134D01*
G01X1908248Y617363D02*
X1907264Y617362D01*
G01X1903740Y614429D02*
X1898228D01*
G01X1904921Y613248D02*
X1897047D01*
G01X1910236Y611752D02*
X1895276D01*
G01X1906496Y610886D02*
X1909646D01*
G01X1899016D02*
X1895276D01*
G01Y609508D02*
X1909646D01*
G01X1903937Y607539D02*
X1901575D01*
G01X1903937Y605846D02*
X1901575D01*
G01X1905315Y601161D02*
X1900197D01*
G01X1913583Y601122D02*
X1891929D01*
G01X1893841Y651870D02*
X1893836Y651850D01*
G01X1893856Y651885D02*
X1893841Y651870D01*
G01X1893876Y651890D02*
X1893856Y651885D01*
G01X1893841Y655020D02*
X1893836Y655000D01*
G01X1893856Y655034D02*
X1893841Y655020D01*
G01X1893876Y655039D02*
X1893856Y655034D01*
G01X1893841Y658169D02*
X1893836Y658150D01*
G01X1893856Y658184D02*
X1893841Y658169D01*
G01X1893876Y658189D02*
X1893856Y658184D01*
G01X1893841Y661319D02*
X1893836Y661299D01*
G01X1893856Y661333D02*
X1893841Y661319D01*
G01X1893876Y661339D02*
X1893856Y661333D01*
G01X1893841Y664469D02*
X1893836Y664449D01*
G01X1893856Y664483D02*
X1893841Y664469D01*
G01X1893876Y664488D02*
X1893856Y664483D01*
G01X1893841Y667618D02*
X1893836Y667598D01*
G01X1893856Y667633D02*
X1893841Y667618D01*
G01X1893876Y667638D02*
X1893856Y667633D01*
G01X1893841Y670768D02*
X1893836Y670748D01*
G01X1893856Y670782D02*
X1893841Y670768D01*
G01X1893876Y670787D02*
X1893856Y670782D01*
G01X1894816Y650728D02*
X1894821Y650748D01*
G01X1894802Y650714D02*
X1894816Y650728D01*
G01X1894782Y650709D02*
X1894802Y650714D01*
G01X1894816Y653878D02*
X1894821Y653898D01*
G01X1894802Y653864D02*
X1894816Y653878D01*
G01X1894782Y653858D02*
X1894802Y653864D01*
G01X1894816Y657028D02*
X1894821Y657047D01*
G01X1894802Y657013D02*
X1894816Y657028D01*
G01X1894782Y657008D02*
X1894802Y657013D01*
G01X1894816Y660177D02*
X1894821Y660197D01*
G01X1894802Y660163D02*
X1894816Y660177D01*
G01X1894782Y660157D02*
X1894802Y660163D01*
G01X1894816Y663327D02*
X1894821Y663346D01*
G01X1894802Y663313D02*
X1894816Y663327D01*
G01X1894782Y663307D02*
X1894802Y663313D01*
G01X1894816Y666476D02*
X1894821Y666496D01*
G01X1894802Y666462D02*
X1894816Y666476D01*
G01X1894782Y666457D02*
X1894802Y666462D01*
G01X1894816Y669626D02*
X1894821Y669646D01*
G01X1894802Y669612D02*
X1894816Y669626D01*
G01X1894782Y669606D02*
X1894802Y669612D01*
G01X1894822Y666475D02*
X1894823Y666483D01*
G01X1894820Y666469D02*
X1894822Y666475D01*
G01X1894816Y666462D02*
X1894820Y666469D01*
G01X1894811Y666456D02*
X1894816Y666462D01*
G01X1894805Y666452D02*
X1894811Y666456D01*
G01X1894798Y666448D02*
X1894805Y666452D01*
G01X1894791Y666446D02*
X1894798Y666448D01*
G01X1894783Y666446D02*
X1894791D01*
G01X1894800Y650701D02*
X1894804Y650703D01*
G01X1894797Y650700D02*
X1894800Y650701D01*
G01X1894794Y650699D02*
X1894797Y650700D01*
G01X1894791Y650698D02*
X1894794Y650699D01*
G01X1894787Y650698D02*
X1894791D01*
G01X1894783D02*
X1894787D01*
G01X1893861Y651898D02*
X1893858Y651896D01*
G01X1893864Y651899D02*
X1893861Y651898D01*
G01X1893867Y651900D02*
X1893864Y651899D01*
G01X1893871Y651900D02*
X1893867D01*
G01X1893874Y651901D02*
X1893871Y651900D01*
G01X1893878Y651901D02*
X1893874D01*
G01X1894800Y653851D02*
X1894804Y653852D01*
G01X1894797Y653850D02*
X1894800Y653851D01*
G01X1894794Y653848D02*
X1894797Y653850D01*
G01X1894791Y653848D02*
X1894794D01*
G01X1894787Y653847D02*
X1894791Y653848D01*
G01X1894783Y653847D02*
X1894787D01*
G01X1893861Y655047D02*
X1893858Y655046D01*
G01X1893864Y655048D02*
X1893861Y655047D01*
G01X1893867Y655050D02*
X1893864Y655048D01*
G01X1893871Y655050D02*
X1893867D01*
G01X1893874Y655051D02*
X1893871Y655050D01*
G01X1893878Y655051D02*
X1893874D01*
G01X1894800Y657000D02*
X1894804Y657002D01*
G01X1894797Y656999D02*
X1894800Y657000D01*
G01X1894794Y656998D02*
X1894797Y656999D01*
G01X1894791Y656997D02*
X1894794Y656998D01*
G01X1894787Y656997D02*
X1894791D01*
G01X1894783D02*
X1894787D01*
G01X1893861Y658197D02*
X1893858Y658195D01*
G01X1893864Y658198D02*
X1893861Y658197D01*
G01X1893867Y658199D02*
X1893864Y658198D01*
G01X1893871Y658200D02*
X1893867Y658199D01*
G01X1893874Y658200D02*
X1893871D01*
G01X1893878D02*
X1893874D01*
G01X1894800Y660150D02*
X1894804Y660152D01*
G01X1894797Y660149D02*
X1894800Y660150D01*
G01X1894794Y660148D02*
X1894797Y660149D01*
G01X1894791Y660147D02*
X1894794Y660148D01*
G01X1894787Y660146D02*
X1894791Y660147D01*
G01X1894783Y660146D02*
X1894787D01*
G01X1893861Y661346D02*
X1893858Y661345D01*
G01X1893864Y661348D02*
X1893861Y661346D01*
G01X1893867Y661349D02*
X1893864Y661348D01*
G01X1893871Y661349D02*
X1893867D01*
G01X1893874Y661350D02*
X1893871Y661349D01*
G01X1893878Y661350D02*
X1893874D01*
G01X1894800Y663300D02*
X1894804Y663301D01*
G01X1894797Y663298D02*
X1894800Y663300D01*
G01X1894794Y663297D02*
X1894797Y663298D01*
G01X1894791Y663296D02*
X1894794Y663297D01*
G01X1894787Y663296D02*
X1894791D01*
G01X1894783D02*
X1894787D01*
G01X1893861Y664496D02*
X1893858Y664494D01*
G01X1893864Y664497D02*
X1893861Y664496D01*
G01X1893867Y664498D02*
X1893864Y664497D01*
G01X1893871Y664499D02*
X1893867Y664498D01*
G01X1893874Y664500D02*
X1893871Y664499D01*
G01X1893878Y664500D02*
X1893874D01*
G01X1893861Y667646D02*
X1893858Y667644D01*
G01X1893864Y667647D02*
X1893861Y667646D01*
G01X1893867Y667648D02*
X1893864Y667647D01*
G01X1893871Y667648D02*
X1893867D01*
G01X1893874Y667649D02*
X1893871Y667648D01*
G01X1893878Y667649D02*
X1893874D01*
G01X1894800Y669599D02*
X1894804Y669600D01*
G01X1894797Y669598D02*
X1894800Y669599D01*
G01X1894794Y669596D02*
X1894797Y669598D01*
G01X1894791Y669596D02*
X1894794D01*
G01X1894787Y669595D02*
X1894791Y669596D01*
G01X1894783Y669595D02*
X1894787D01*
G01X1893861Y670795D02*
X1893858Y670794D01*
G01X1893864Y670796D02*
X1893861Y670795D01*
G01X1893867Y670798D02*
X1893864Y670796D01*
G01X1893871Y670798D02*
X1893867D01*
G01X1893874Y670799D02*
X1893871Y670798D01*
G01X1893878Y670799D02*
X1893874D01*
G01X1894813Y651888D02*
X1894817Y651883D01*
G01X1894809Y651893D02*
X1894813Y651888D01*
G01X1894803Y651896D02*
X1894809Y651893D01*
G01X1894797Y651899D02*
X1894803Y651896D01*
G01X1894790Y651901D02*
X1894797Y651899D01*
G01X1894783Y651901D02*
X1894790D01*
G01X1894813Y655038D02*
X1894817Y655033D01*
G01X1894809Y655042D02*
X1894813Y655038D01*
G01X1894803Y655046D02*
X1894809Y655042D01*
G01X1894797Y655048D02*
X1894803Y655046D01*
G01X1894790Y655050D02*
X1894797Y655048D01*
G01X1894783Y655051D02*
X1894790Y655050D01*
G01X1894813Y658187D02*
X1894817Y658182D01*
G01X1894809Y658192D02*
X1894813Y658187D01*
G01X1894803Y658196D02*
X1894809Y658192D01*
G01X1894797Y658198D02*
X1894803Y658196D01*
G01X1894790Y658200D02*
X1894797Y658198D01*
G01X1894783Y658200D02*
X1894790D01*
G01X1894813Y661337D02*
X1894817Y661332D01*
G01X1894809Y661341D02*
X1894813Y661337D01*
G01X1894803Y661345D02*
X1894809Y661341D01*
G01X1894797Y661348D02*
X1894803Y661345D01*
G01X1894790Y661350D02*
X1894797Y661348D01*
G01X1894783Y661350D02*
X1894790D01*
G01X1894813Y664487D02*
X1894817Y664481D01*
G01X1894809Y664491D02*
X1894813Y664487D01*
G01X1894803Y664495D02*
X1894809Y664491D01*
G01X1894797Y664497D02*
X1894803Y664495D01*
G01X1894790Y664499D02*
X1894797Y664497D01*
G01X1894783Y664500D02*
X1894790Y664499D01*
G01X1894813Y667636D02*
X1894817Y667631D01*
G01X1894809Y667641D02*
X1894813Y667636D01*
G01X1894803Y667644D02*
X1894809Y667641D01*
G01X1894797Y667647D02*
X1894803Y667644D01*
G01X1894790Y667649D02*
X1894797Y667647D01*
G01X1894783Y667649D02*
X1894790D01*
G01X1894813Y670786D02*
X1894817Y670781D01*
G01X1894809Y670790D02*
X1894813Y670786D01*
G01X1894803Y670794D02*
X1894809Y670790D01*
G01X1894797Y670796D02*
X1894803Y670794D01*
G01X1894790Y670798D02*
X1894797Y670796D01*
G01X1894783Y670799D02*
X1894790Y670798D01*
G01X1893839Y650727D02*
Y650735D01*
G01X1893842Y650720D02*
X1893839Y650727D01*
G01X1893845Y650714D02*
X1893842Y650720D01*
G01X1893850Y650708D02*
X1893845Y650714D01*
G01X1893856Y650704D02*
X1893850Y650708D01*
G01X1893863Y650700D02*
X1893856Y650704D01*
G01X1893870Y650698D02*
X1893863Y650700D01*
G01X1893878Y650698D02*
X1893870D01*
G01X1893839Y653877D02*
Y653884D01*
G01X1893842Y653870D02*
X1893839Y653877D01*
G01X1893845Y653864D02*
X1893842Y653870D01*
G01X1893850Y653858D02*
X1893845Y653864D01*
G01X1893856Y653853D02*
X1893850Y653858D01*
G01X1893863Y653850D02*
X1893856Y653853D01*
G01X1893870Y653848D02*
X1893863Y653850D01*
G01X1893878Y653847D02*
X1893870Y653848D01*
G01X1893839Y657026D02*
Y657034D01*
G01X1893842Y657020D02*
X1893839Y657026D01*
G01X1893845Y657013D02*
X1893842Y657020D01*
G01X1893850Y657007D02*
X1893845Y657013D01*
G01X1893856Y657003D02*
X1893850Y657007D01*
G01X1893863Y657000D02*
X1893856Y657003D01*
G01X1893870Y656998D02*
X1893863Y657000D01*
G01X1893878Y656997D02*
X1893870Y656998D01*
G01X1893839Y660176D02*
Y660183D01*
G01X1893842Y660169D02*
X1893839Y660176D01*
G01X1893845Y660163D02*
X1893842Y660169D01*
G01X1893850Y660157D02*
X1893845Y660163D01*
G01X1893856Y660152D02*
X1893850Y660157D01*
G01X1893863Y660149D02*
X1893856Y660152D01*
G01X1893870Y660147D02*
X1893863Y660149D01*
G01X1893878Y660146D02*
X1893870Y660147D01*
G01X1893839Y663326D02*
Y663333D01*
G01X1893842Y663319D02*
X1893839Y663326D01*
G01X1893845Y663313D02*
X1893842Y663319D01*
G01X1893850Y663307D02*
X1893845Y663313D01*
G01X1893856Y663302D02*
X1893850Y663307D01*
G01X1893863Y663299D02*
X1893856Y663302D01*
G01X1893870Y663297D02*
X1893863Y663299D01*
G01X1893878Y663296D02*
X1893870Y663297D01*
G01X1893839Y666475D02*
Y666483D01*
G01X1893842Y666469D02*
X1893839Y666475D01*
G01X1893845Y666462D02*
X1893842Y666469D01*
G01X1893850Y666456D02*
X1893845Y666462D01*
G01X1893856Y666452D02*
X1893850Y666456D01*
G01X1893863Y666448D02*
X1893856Y666452D01*
G01X1893870Y666446D02*
X1893863Y666448D01*
G01X1893878Y666446D02*
X1893870D01*
G01X1893839Y669625D02*
Y669632D01*
G01X1893842Y669618D02*
X1893839Y669625D01*
G01X1893845Y669612D02*
X1893842Y669618D01*
G01X1893850Y669606D02*
X1893845Y669612D01*
G01X1893856Y669601D02*
X1893850Y669606D01*
G01X1893863Y669598D02*
X1893856Y669601D01*
G01X1893870Y669596D02*
X1893863Y669598D01*
G01X1893878Y669595D02*
X1893870Y669596D01*
G01X1894793Y651889D02*
X1894802Y651884D01*
G01X1894782Y651890D02*
X1894793Y651889D01*
G01Y655038D02*
X1894802Y655034D01*
G01X1894782Y655039D02*
X1894793Y655038D01*
G01Y658188D02*
X1894802Y658183D01*
G01X1894782Y658189D02*
X1894793Y658188D01*
G01Y661337D02*
X1894802Y661333D01*
G01X1894782Y661339D02*
X1894793Y661337D01*
G01Y664487D02*
X1894802Y664483D01*
G01X1894782Y664488D02*
X1894793Y664487D01*
G01Y667637D02*
X1894802Y667632D01*
G01X1894782Y667638D02*
X1894793Y667637D01*
G01Y670786D02*
X1894802Y670782D01*
G01X1894782Y670787D02*
X1894793Y670786D01*
G01X1893839Y653888D02*
Y653884D01*
G01X1893840Y653882D02*
X1893839Y653888D01*
G01X1893852Y653867D02*
X1893840Y653882D01*
G01X1893877Y653858D02*
X1893852Y653867D01*
G01X1893839Y657038D02*
Y657034D01*
G01X1893840Y657031D02*
X1893839Y657038D01*
G01X1893852Y657016D02*
X1893840Y657031D01*
G01X1893876Y657008D02*
X1893852Y657016D01*
G01X1893839Y663337D02*
Y663333D01*
G01X1893840Y663331D02*
X1893839Y663337D01*
G01X1893852Y663315D02*
X1893840Y663331D01*
G01X1893876Y663307D02*
X1893852Y663315D01*
G01X1893839Y666487D02*
Y666483D01*
G01X1893840Y666480D02*
X1893839Y666487D01*
G01X1893852Y666465D02*
X1893840Y666480D01*
G01X1893876Y666457D02*
X1893852Y666465D01*
G01X1893839Y650739D02*
Y650735D01*
G01X1893840Y650732D02*
X1893839Y650739D01*
G01X1893852Y650717D02*
X1893840Y650732D01*
G01X1893876Y650709D02*
X1893852Y650717D01*
G01X1893839Y669636D02*
Y669632D01*
G01X1893840Y669630D02*
X1893839Y669636D01*
G01X1893852Y669615D02*
X1893840Y669630D01*
G01X1893876Y669606D02*
X1893852Y669615D01*
G01X1908235Y648929D02*
X1908246Y648913D01*
G01X1908211Y648937D02*
X1908235Y648929D01*
G01Y673929D02*
X1908246Y673913D01*
G01X1908211Y673937D02*
X1908235Y673929D01*
G01Y678929D02*
X1908246Y678913D01*
G01X1908211Y678937D02*
X1908235Y678929D01*
G01Y683929D02*
X1908246Y683913D01*
G01X1908211Y683937D02*
X1908235Y683929D01*
G01Y688929D02*
X1908246Y688913D01*
G01X1908211Y688937D02*
X1908235Y688929D01*
G01Y693929D02*
X1908246Y693913D01*
G01X1908211Y693937D02*
X1908235Y693929D01*
G01X1893839Y660187D02*
Y660183D01*
G01X1893840Y660182D02*
X1893839Y660187D01*
G01X1893850Y660167D02*
X1893840Y660182D01*
G01X1893873Y660158D02*
X1893850Y660167D01*
G01X1894791Y658188D02*
X1894782Y658189D01*
G01X1894800Y658185D02*
X1894791Y658188D01*
G01X1894808Y658180D02*
X1894800Y658185D01*
G01X1894791Y651889D02*
X1894782Y651890D01*
G01X1894800Y651885D02*
X1894791Y651889D01*
G01X1894808Y651880D02*
X1894800Y651885D01*
G01X1894791Y655038D02*
X1894782Y655039D01*
G01X1894800Y655035D02*
X1894791Y655038D01*
G01X1894808Y655030D02*
X1894800Y655035D01*
G01X1894791Y661337D02*
X1894782Y661339D01*
G01X1894800Y661334D02*
X1894791Y661337D01*
G01X1894808Y661329D02*
X1894800Y661334D01*
G01X1894791Y664487D02*
X1894782Y664488D01*
G01X1894800Y664484D02*
X1894791Y664487D01*
G01X1894808Y664479D02*
X1894800Y664484D01*
G01X1894791Y667637D02*
X1894782Y667638D01*
G01X1894800Y667633D02*
X1894791Y667637D01*
G01X1894808Y667628D02*
X1894800Y667633D01*
G01X1894791Y670786D02*
X1894782Y670787D01*
G01X1894800Y670783D02*
X1894791Y670786D01*
G01X1894808Y670778D02*
X1894800Y670783D01*
G01X1894794Y669608D02*
X1894782Y669606D01*
G01X1894804Y669613D02*
X1894794Y669608D01*
G01Y666459D02*
X1894782Y666457D01*
G01X1894804Y666464D02*
X1894794Y666459D01*
G01Y663309D02*
X1894782Y663307D01*
G01X1894804Y663314D02*
X1894794Y663309D01*
G01Y660159D02*
X1894782Y660157D01*
G01X1894804Y660165D02*
X1894794Y660159D01*
G01Y657010D02*
X1894782Y657008D01*
G01X1894804Y657015D02*
X1894794Y657010D01*
G01Y653860D02*
X1894782Y653858D01*
G01X1894804Y653865D02*
X1894794Y653860D01*
G01Y650711D02*
X1894782Y650709D01*
G01X1894804Y650716D02*
X1894794Y650711D01*
G01X1893878Y650704D02*
Y650698D01*
G01X1893877Y650707D02*
X1893878Y650704D01*
G01X1893876Y650709D02*
X1893877Y650707D01*
G01X1893878Y653854D02*
Y653847D01*
G01X1893877Y653857D02*
X1893878Y653854D01*
G01X1893876Y653858D02*
X1893877Y653857D01*
G01X1893878Y657003D02*
Y656997D01*
G01X1893877Y657007D02*
X1893878Y657003D01*
G01X1893876Y657008D02*
X1893877Y657007D01*
G01X1893878Y660153D02*
Y660146D01*
G01X1893877Y660156D02*
X1893878Y660153D01*
G01X1893876Y660157D02*
X1893877Y660156D01*
G01X1893878Y663302D02*
Y663296D01*
G01X1893877Y663306D02*
X1893878Y663302D01*
G01X1893876Y663307D02*
X1893877Y663306D01*
G01X1893878Y666452D02*
Y666446D01*
G01X1893877Y666456D02*
X1893878Y666452D01*
G01X1893876Y666457D02*
X1893877Y666456D01*
G01X1893878Y669602D02*
Y669595D01*
G01X1893877Y669605D02*
X1893878Y669602D01*
G01X1893876Y669606D02*
X1893877Y669605D01*
G01Y670793D02*
Y670799D01*
G01Y670789D02*
Y670793D01*
G01X1893875Y670787D02*
X1893877Y670789D01*
G01Y667643D02*
Y667649D01*
G01Y667639D02*
Y667643D01*
G01X1893875Y667638D02*
X1893877Y667639D01*
G01Y664493D02*
Y664500D01*
G01Y664489D02*
Y664493D01*
G01X1893875Y664488D02*
X1893877Y664489D01*
G01Y661344D02*
Y661350D01*
G01Y661340D02*
Y661344D01*
G01X1893875Y661339D02*
X1893877Y661340D01*
G01Y658194D02*
Y658200D01*
G01Y658190D02*
Y658194D01*
G01X1893875Y658189D02*
X1893877Y658190D01*
G01Y655044D02*
Y655051D01*
G01Y655041D02*
Y655044D01*
G01X1893875Y655039D02*
X1893877Y655041D01*
G01X1893839Y670768D02*
Y670762D01*
G01X1893841Y670774D02*
X1893839Y670768D01*
G01X1893844Y670780D02*
X1893841Y670774D01*
G01X1893848Y670785D02*
X1893844Y670780D01*
G01X1893852Y670790D02*
X1893848Y670785D01*
G01X1893858Y670794D02*
X1893852Y670790D01*
G01X1893839Y667619D02*
Y667612D01*
G01X1893841Y667625D02*
X1893839Y667619D01*
G01X1893844Y667630D02*
X1893841Y667625D01*
G01X1893848Y667636D02*
X1893844Y667630D01*
G01X1893852Y667640D02*
X1893848Y667636D01*
G01X1893858Y667644D02*
X1893852Y667640D01*
G01X1893839Y664469D02*
Y664463D01*
G01X1893841Y664475D02*
X1893839Y664469D01*
G01X1893844Y664481D02*
X1893841Y664475D01*
G01X1893848Y664486D02*
X1893844Y664481D01*
G01X1893852Y664491D02*
X1893848Y664486D01*
G01X1893858Y664494D02*
X1893852Y664491D01*
G01X1893839Y661319D02*
Y661313D01*
G01X1893841Y661326D02*
X1893839Y661319D01*
G01X1893844Y661331D02*
X1893841Y661326D01*
G01X1893848Y661337D02*
X1893844Y661331D01*
G01X1893852Y661341D02*
X1893848Y661337D01*
G01X1893858Y661345D02*
X1893852Y661341D01*
G01X1893839Y658170D02*
Y658163D01*
G01X1893841Y658176D02*
X1893839Y658170D01*
G01X1893844Y658181D02*
X1893841Y658176D01*
G01X1893848Y658187D02*
X1893844Y658181D01*
G01X1893852Y658191D02*
X1893848Y658187D01*
G01X1893858Y658195D02*
X1893852Y658191D01*
G01X1893839Y655020D02*
Y655014D01*
G01X1893841Y655026D02*
X1893839Y655020D01*
G01X1893844Y655032D02*
X1893841Y655026D01*
G01X1893848Y655037D02*
X1893844Y655032D01*
G01X1893852Y655042D02*
X1893848Y655037D01*
G01X1893858Y655046D02*
X1893852Y655042D01*
G01X1893839Y651870D02*
Y651864D01*
G01X1893841Y651877D02*
X1893839Y651870D01*
G01X1893844Y651882D02*
X1893841Y651877D01*
G01X1893848Y651888D02*
X1893844Y651882D01*
G01X1893852Y651892D02*
X1893848Y651888D01*
G01X1893858Y651896D02*
X1893852Y651892D01*
G01X1894820Y669620D02*
X1894823Y669632D01*
G01X1894814Y669609D02*
X1894820Y669620D01*
G01X1894804Y669600D02*
X1894814Y669609D01*
G01X1894820Y663320D02*
X1894823Y663333D01*
G01X1894814Y663309D02*
X1894820Y663320D01*
G01X1894804Y663301D02*
X1894814Y663309D01*
G01X1894820Y660171D02*
X1894823Y660183D01*
G01X1894814Y660160D02*
X1894820Y660171D01*
G01X1894804Y660152D02*
X1894814Y660160D01*
G01X1894820Y657021D02*
X1894823Y657034D01*
G01X1894814Y657010D02*
X1894820Y657021D01*
G01X1894804Y657002D02*
X1894814Y657010D01*
G01X1894820Y653872D02*
X1894823Y653884D01*
G01X1894814Y653861D02*
X1894820Y653872D01*
G01X1894804Y653852D02*
X1894814Y653861D01*
G01X1894820Y650722D02*
X1894823Y650735D01*
G01X1894814Y650711D02*
X1894820Y650722D01*
G01X1894804Y650703D02*
X1894814Y650711D01*
G01X1893877Y651895D02*
Y651901D01*
G01Y651891D02*
Y651895D01*
G01X1893875Y651890D02*
X1893877Y651891D01*
G01X1908248Y648904D02*
Y648911D01*
G01X1908249Y648900D02*
X1908248Y648904D01*
G01X1908250Y648898D02*
X1908249Y648900D01*
G01X1908248Y673904D02*
Y673911D01*
G01X1908249Y673900D02*
X1908248Y673904D01*
G01X1908250Y673898D02*
X1908249Y673900D01*
G01X1908248Y678904D02*
Y678911D01*
G01X1908249Y678900D02*
X1908248Y678904D01*
G01X1908250Y678898D02*
X1908249Y678900D01*
G01X1908248Y683904D02*
Y683911D01*
G01X1908249Y683900D02*
X1908248Y683904D01*
G01X1908250Y683898D02*
X1908249Y683900D01*
G01X1908248Y688904D02*
Y688911D01*
G01X1908249Y688900D02*
X1908248Y688904D01*
G01X1908250Y688898D02*
X1908249Y688900D01*
G01X1908248Y693904D02*
Y693911D01*
G01X1908249Y693900D02*
X1908248Y693904D01*
G01X1908250Y693898D02*
X1908249Y693900D01*
G01X1893861Y653861D02*
X1893876Y653858D01*
G01X1893850Y653868D02*
X1893861Y653861D01*
G01X1893838Y653887D02*
X1893850Y653868D01*
G01X1893861Y663310D02*
X1893876Y663307D01*
G01X1893850Y663317D02*
X1893861Y663310D01*
G01X1893838Y663335D02*
X1893850Y663317D01*
G01X1908248Y692552D02*
Y692543D01*
G01X1908249Y692557D02*
X1908248Y692552D01*
G01X1908251Y692559D02*
X1908249Y692557D01*
G01X1908248Y687552D02*
Y687543D01*
G01X1908249Y687557D02*
X1908248Y687552D01*
G01X1908251Y687559D02*
X1908249Y687557D01*
G01X1908248Y682552D02*
Y682543D01*
G01X1908249Y682557D02*
X1908248Y682552D01*
G01X1908251Y682559D02*
X1908249Y682557D01*
G01X1908248Y677552D02*
Y677543D01*
G01X1908249Y677557D02*
X1908248Y677552D01*
G01X1908251Y677559D02*
X1908249Y677557D01*
G01X1908248Y672552D02*
Y672543D01*
G01X1908249Y672557D02*
X1908248Y672552D01*
G01X1908251Y672559D02*
X1908249Y672557D01*
G01X1893838Y670754D02*
X1893839Y670762D01*
G01X1893837Y670750D02*
X1893838Y670754D01*
G01X1893836Y670748D02*
X1893837Y670750D01*
G01X1893838Y667605D02*
X1893839Y667612D01*
G01X1893837Y667600D02*
X1893838Y667605D01*
G01X1893836Y667598D02*
X1893837Y667600D01*
G01X1893838Y664455D02*
X1893839Y664463D01*
G01X1893837Y664450D02*
X1893838Y664455D01*
G01X1893836Y664449D02*
X1893837Y664450D01*
G01X1893838Y661306D02*
X1893839Y661313D01*
G01X1893837Y661301D02*
X1893838Y661306D01*
G01X1893836Y661299D02*
X1893837Y661301D01*
G01X1893838Y658156D02*
X1893839Y658163D01*
G01X1893837Y658151D02*
X1893838Y658156D01*
G01X1893836Y658150D02*
X1893837Y658151D01*
G01X1893838Y655006D02*
X1893839Y655014D01*
G01X1893837Y655002D02*
X1893838Y655006D01*
G01X1893836Y655000D02*
X1893837Y655002D01*
G01X1893838Y651857D02*
X1893839Y651864D01*
G01X1893837Y651852D02*
X1893838Y651857D01*
G01X1893836Y651850D02*
X1893837Y651852D01*
G01X1893861Y657011D02*
X1893876Y657008D01*
G01X1893849Y657019D02*
X1893861Y657011D01*
G01X1893837Y657039D02*
X1893849Y657019D01*
G01X1893861Y666459D02*
X1893876Y666457D01*
G01X1893849Y666467D02*
X1893861Y666459D01*
G01X1893837Y666487D02*
X1893849Y666467D01*
G01X1894823Y650742D02*
Y650735D01*
G01X1894822Y650747D02*
X1894823Y650742D01*
G01X1894821Y650748D02*
X1894822Y650747D01*
G01X1894823Y653892D02*
Y653884D01*
G01X1894822Y653896D02*
X1894823Y653892D01*
G01X1894821Y653898D02*
X1894822Y653896D01*
G01X1894823Y657041D02*
Y657034D01*
G01X1894822Y657046D02*
X1894823Y657041D01*
G01X1894821Y657047D02*
X1894822Y657046D01*
G01X1894823Y660191D02*
Y660183D01*
G01X1894822Y660196D02*
X1894823Y660191D01*
G01X1894821Y660197D02*
X1894822Y660196D01*
G01X1894823Y663341D02*
Y663333D01*
G01X1894822Y663345D02*
X1894823Y663341D01*
G01X1894821Y663346D02*
X1894822Y663345D01*
G01X1894823Y666490D02*
Y666483D01*
G01X1894822Y666495D02*
X1894823Y666490D01*
G01X1894821Y666496D02*
X1894822Y666495D01*
G01X1894823Y669640D02*
Y669632D01*
G01X1894822Y669644D02*
X1894823Y669640D01*
G01X1894821Y669646D02*
X1894822Y669644D01*
G01X1893861Y669609D02*
X1893876Y669606D01*
G01X1893848Y669617D02*
X1893861Y669609D01*
G01X1893837Y669637D02*
X1893848Y669617D01*
G01X1893861Y650712D02*
X1893876Y650709D01*
G01X1893848Y650720D02*
X1893861Y650712D01*
G01X1893837Y650741D02*
X1893848Y650720D01*
G01X1894822Y651871D02*
X1894823Y651864D01*
G01X1894820Y651877D02*
X1894822Y651871D01*
G01X1894817Y651883D02*
X1894820Y651877D01*
G01X1894822Y655020D02*
X1894823Y655014D01*
G01X1894820Y655027D02*
X1894822Y655020D01*
G01X1894817Y655033D02*
X1894820Y655027D01*
G01X1894822Y658170D02*
X1894823Y658163D01*
G01X1894820Y658176D02*
X1894822Y658170D01*
G01X1894817Y658182D02*
X1894820Y658176D01*
G01X1894822Y661320D02*
X1894823Y661313D01*
G01X1894820Y661326D02*
X1894822Y661320D01*
G01X1894817Y661332D02*
X1894820Y661326D01*
G01X1894822Y664469D02*
X1894823Y664463D01*
G01X1894820Y664476D02*
X1894822Y664469D01*
G01X1894817Y664481D02*
X1894820Y664476D01*
G01X1894822Y667619D02*
X1894823Y667612D01*
G01X1894820Y667625D02*
X1894822Y667619D01*
G01X1894817Y667631D02*
X1894820Y667625D01*
G01X1894822Y670769D02*
X1894823Y670762D01*
G01X1894820Y670775D02*
X1894822Y670769D01*
G01X1894817Y670781D02*
X1894820Y670775D01*
G01X1894784Y650704D02*
Y650698D01*
G01X1894783Y650707D02*
X1894784Y650704D01*
G01X1894782Y650709D02*
X1894783Y650707D01*
G01X1894784Y653853D02*
Y653847D01*
G01X1894783Y653857D02*
X1894784Y653853D01*
G01X1894782Y653858D02*
X1894783Y653857D01*
G01X1894784Y657003D02*
Y656997D01*
G01X1894783Y657007D02*
X1894784Y657003D01*
G01X1894782Y657008D02*
X1894783Y657007D01*
G01X1894784Y660152D02*
Y660146D01*
G01X1894783Y660156D02*
X1894784Y660152D01*
G01X1894782Y660157D02*
X1894783Y660156D01*
G01X1894784Y663302D02*
Y663296D01*
G01X1894783Y663306D02*
X1894784Y663302D01*
G01X1894782Y663307D02*
X1894783Y663306D01*
G01X1894784Y669601D02*
Y669595D01*
G01X1894783Y669605D02*
X1894784Y669601D01*
G01X1894782Y669606D02*
X1894783Y669605D01*
G01X1907264Y648944D02*
Y648954D01*
G01X1907265Y648939D02*
X1907264Y648944D01*
G01X1907265Y648937D02*
Y648939D01*
G01X1907264Y673944D02*
Y673954D01*
G01X1907265Y673939D02*
X1907264Y673944D01*
G01X1907265Y673937D02*
Y673939D01*
G01X1907264Y678944D02*
Y678954D01*
G01X1907265Y678939D02*
X1907264Y678944D01*
G01X1907265Y678937D02*
Y678939D01*
G01X1908240Y649081D02*
X1908248Y649055D01*
G01X1908230Y649107D02*
X1908240Y649081D01*
G01X1908219Y649134D02*
X1908230Y649107D01*
G01X1894823Y670754D02*
Y670761D01*
G01X1894822Y670750D02*
X1894823Y670754D01*
G01X1894822Y670748D02*
Y670750D01*
G01X1894823Y667605D02*
Y667612D01*
G01X1894822Y667600D02*
X1894823Y667605D01*
G01X1894822Y667598D02*
Y667600D01*
G01X1894823Y664455D02*
Y664462D01*
G01X1894822Y664451D02*
X1894823Y664455D01*
G01X1894822Y664449D02*
Y664451D01*
G01X1894823Y661306D02*
Y661313D01*
G01X1894822Y661301D02*
X1894823Y661306D01*
G01X1894822Y661299D02*
Y661301D01*
G01X1894823Y658156D02*
Y658163D01*
G01X1894822Y658152D02*
X1894823Y658156D01*
G01X1894822Y658150D02*
Y658152D01*
G01X1894823Y655006D02*
Y655013D01*
G01X1894822Y655002D02*
X1894823Y655006D01*
G01X1894822Y655000D02*
Y655002D01*
G01X1894823Y651857D02*
Y651864D01*
G01X1894822Y651852D02*
X1894823Y651857D01*
G01X1894822Y651850D02*
Y651852D01*
G01X1893838Y660191D02*
X1893839Y660183D01*
G01X1893837Y660196D02*
X1893838Y660191D01*
G01X1893836Y660193D02*
X1893837Y660196D01*
G01X1893838Y653892D02*
X1893839Y653884D01*
G01X1893837Y653896D02*
X1893838Y653892D01*
G01X1893836Y653894D02*
X1893837Y653896D01*
G01X1894783Y670793D02*
Y670799D01*
G01Y670789D02*
Y670793D01*
G01X1894782Y670787D02*
X1894783Y670789D01*
G01Y667643D02*
Y667649D01*
G01Y667639D02*
Y667643D01*
G01X1894782Y667638D02*
X1894783Y667639D01*
G01Y664493D02*
Y664500D01*
G01Y664490D02*
Y664493D01*
G01X1894782Y664488D02*
X1894783Y664490D01*
G01Y661344D02*
Y661350D01*
G01Y661340D02*
Y661344D01*
G01X1894782Y661339D02*
X1894783Y661340D01*
G01Y658194D02*
Y658200D01*
G01Y658191D02*
Y658194D01*
G01X1894782Y658189D02*
X1894783Y658191D01*
G01Y655044D02*
Y655051D01*
G01Y655041D02*
Y655044D01*
G01X1894782Y655039D02*
X1894783Y655041D01*
G01Y651895D02*
Y651901D01*
G01Y651891D02*
Y651895D01*
G01X1894782Y651890D02*
X1894783Y651891D01*
G01X1907264Y683944D02*
Y683954D01*
G01X1907265Y683939D02*
X1907264Y683944D01*
G01X1907265Y683937D02*
Y683939D01*
G01X1907264Y688944D02*
Y688954D01*
G01X1907265Y688939D02*
X1907264Y688944D01*
G01X1907265Y688937D02*
Y688939D01*
G01X1907264Y693944D02*
Y693954D01*
G01X1907265Y693939D02*
X1907264Y693944D01*
G01X1907265Y693937D02*
Y693939D01*
G01X1908240Y674081D02*
X1908248Y674055D01*
G01X1908230Y674107D02*
X1908240Y674081D01*
G01X1908219Y674134D02*
X1908230Y674107D01*
G01X1908240Y679081D02*
X1908248Y679055D01*
G01X1908230Y679107D02*
X1908240Y679081D01*
G01X1908219Y679134D02*
X1908230Y679107D01*
G01X1908240Y684081D02*
X1908248Y684055D01*
G01X1908230Y684107D02*
X1908240Y684081D01*
G01X1908219Y684134D02*
X1908230Y684107D01*
G01X1908240Y689081D02*
X1908248Y689055D01*
G01X1908230Y689107D02*
X1908240Y689081D01*
G01X1908219Y689134D02*
X1908230Y689107D01*
G01X1908240Y694081D02*
X1908248Y694055D01*
G01X1908230Y694107D02*
X1908240Y694081D01*
G01X1908219Y694134D02*
X1908230Y694107D01*
G01X1893856Y660163D02*
X1893876Y660157D01*
G01X1893843Y660175D02*
X1893856Y660163D01*
G01X1893836Y660193D02*
X1893843Y660175D01*
G01X1908231Y648932D02*
X1908211Y648937D01*
G01X1908245Y648918D02*
X1908231Y648932D01*
G01X1908250Y648898D02*
X1908245Y648918D01*
G01X1908231Y673932D02*
X1908211Y673937D01*
G01X1908245Y673918D02*
X1908231Y673932D01*
G01X1908250Y673898D02*
X1908245Y673918D01*
G01X1908231Y678932D02*
X1908211Y678937D01*
G01X1908245Y678918D02*
X1908231Y678932D01*
G01X1908250Y678898D02*
X1908245Y678918D01*
G01X1908231Y683932D02*
X1908211Y683937D01*
G01X1908245Y683918D02*
X1908231Y683932D01*
G01X1908250Y683898D02*
X1908245Y683918D01*
G01X1908231Y688932D02*
X1908211Y688937D01*
G01X1908245Y688918D02*
X1908231Y688932D01*
G01X1908250Y688898D02*
X1908245Y688918D01*
G01X1908231Y693932D02*
X1908211Y693937D01*
G01X1908245Y693918D02*
X1908231Y693932D01*
G01X1908250Y693898D02*
X1908245Y693918D01*
G01X1894815Y658171D02*
X1894808Y658180D01*
G01X1894820Y658161D02*
X1894815Y658171D01*
G01X1894822Y658150D02*
X1894820Y658161D01*
G01X1894815Y651872D02*
X1894808Y651880D01*
G01X1894820Y651861D02*
X1894815Y651872D01*
G01X1894822Y651850D02*
X1894820Y651861D01*
G01X1894815Y655021D02*
X1894808Y655030D01*
G01X1894820Y655011D02*
X1894815Y655021D01*
G01X1894822Y655000D02*
X1894820Y655011D01*
G01X1894815Y661320D02*
X1894808Y661329D01*
G01X1894820Y661310D02*
X1894815Y661320D01*
G01X1894822Y661299D02*
X1894820Y661310D01*
G01X1894815Y664470D02*
X1894808Y664479D01*
G01X1894820Y664460D02*
X1894815Y664470D01*
G01X1894822Y664449D02*
X1894820Y664460D01*
G01X1894815Y667620D02*
X1894808Y667628D01*
G01X1894820Y667609D02*
X1894815Y667620D01*
G01X1894822Y667598D02*
X1894820Y667609D01*
G01X1894815Y670769D02*
X1894808Y670778D01*
G01X1894820Y670759D02*
X1894815Y670769D01*
G01X1894822Y670748D02*
X1894820Y670759D01*
G01X1908215Y649035D02*
X1908219Y649134D01*
G01X1908209Y648963D02*
X1908215Y649035D01*
G01X1908211Y648937D02*
X1908209Y648963D01*
G01X1908215Y674035D02*
X1908219Y674134D01*
G01X1908209Y673963D02*
X1908215Y674035D01*
G01X1908211Y673937D02*
X1908209Y673963D01*
G01X1908215Y679035D02*
X1908219Y679134D01*
G01X1908209Y678963D02*
X1908215Y679035D01*
G01X1908211Y678937D02*
X1908209Y678963D01*
G01X1908215Y684035D02*
X1908219Y684134D01*
G01X1908209Y683963D02*
X1908215Y684035D01*
G01X1908211Y683937D02*
X1908209Y683963D01*
G01X1908215Y689035D02*
X1908219Y689134D01*
G01X1908209Y688963D02*
X1908215Y689035D01*
G01X1908211Y688937D02*
X1908209Y688963D01*
G01X1908215Y694035D02*
X1908219Y694134D01*
G01X1908209Y693963D02*
X1908215Y694035D01*
G01X1908211Y693937D02*
X1908209Y693963D01*
G01X1893838Y663341D02*
X1893839Y663333D01*
G01X1893837Y663345D02*
X1893838Y663341D01*
G01Y663336D02*
X1893837Y663345D01*
G01X1893879Y670972D02*
X1893878Y670984D01*
G01X1893876Y670959D02*
X1893879Y670972D01*
G01X1893876Y670945D02*
Y670959D01*
G01X1893879Y667822D02*
X1893878Y667835D01*
G01X1893876Y667809D02*
X1893879Y667822D01*
G01X1893876Y667796D02*
Y667809D01*
G01X1893879Y664673D02*
X1893878Y664685D01*
G01X1893876Y664660D02*
X1893879Y664673D01*
G01X1893876Y664646D02*
Y664660D01*
G01X1893879Y661523D02*
X1893878Y661535D01*
G01X1893876Y661510D02*
X1893879Y661523D01*
G01X1893876Y661496D02*
Y661510D01*
G01X1893879Y658374D02*
X1893878Y658386D01*
G01X1893876Y658361D02*
X1893879Y658374D01*
G01X1893876Y658347D02*
Y658361D01*
G01X1893879Y655224D02*
X1893878Y655236D01*
G01X1893876Y655211D02*
X1893879Y655224D01*
G01X1893876Y655197D02*
Y655211D01*
G01X1893879Y652074D02*
X1893878Y652087D01*
G01X1893876Y652061D02*
X1893879Y652074D01*
G01X1893876Y652048D02*
Y652061D01*
G01X1907265Y692557D02*
Y692559D01*
G01X1907264Y692552D02*
X1907265Y692557D01*
G01X1907264Y692543D02*
Y692552D01*
G01X1907265Y687557D02*
Y687559D01*
G01X1907264Y687552D02*
X1907265Y687557D01*
G01X1907264Y687543D02*
Y687552D01*
G01X1907265Y682557D02*
Y682559D01*
G01X1907264Y682552D02*
X1907265Y682557D01*
G01X1907264Y682543D02*
Y682552D01*
G01X1907265Y677557D02*
Y677559D01*
G01X1907264Y677552D02*
X1907265Y677557D01*
G01X1907264Y677543D02*
Y677552D01*
G01X1907265Y672557D02*
Y672559D01*
G01X1907264Y672552D02*
X1907265Y672557D01*
G01X1907264Y672543D02*
Y672552D01*
G01X1893838Y669640D02*
X1893839Y669632D01*
G01X1893837Y669644D02*
X1893838Y669640D01*
G01X1893837Y669637D02*
Y669644D01*
G01X1893876Y669435D02*
X1893874Y669448D01*
G01X1893879Y669422D02*
X1893876Y669435D01*
G01X1893878Y669409D02*
X1893879Y669422D01*
G01X1893876Y666285D02*
X1893874Y666299D01*
G01X1893879Y666272D02*
X1893876Y666285D01*
G01X1893878Y666260D02*
X1893879Y666272D01*
G01X1893876Y663136D02*
X1893874Y663149D01*
G01X1893879Y663123D02*
X1893876Y663136D01*
G01X1893878Y663110D02*
X1893879Y663123D01*
G01X1893876Y659986D02*
X1893874Y660000D01*
G01X1893879Y659973D02*
X1893876Y659986D01*
G01X1893878Y659961D02*
X1893879Y659973D01*
G01X1893876Y656837D02*
X1893874Y656850D01*
G01X1893879Y656824D02*
X1893876Y656837D01*
G01X1893878Y656811D02*
X1893879Y656824D01*
G01X1893876Y653687D02*
X1893874Y653700D01*
G01X1893879Y653674D02*
X1893876Y653687D01*
G01X1893878Y653661D02*
X1893879Y653674D01*
G01X1893876Y650537D02*
X1893874Y650551D01*
G01X1893879Y650524D02*
X1893876Y650537D01*
G01X1893878Y650512D02*
X1893879Y650524D01*
G01X1894786Y670959D02*
X1894787Y670945D01*
G01X1894783Y670972D02*
X1894786Y670959D01*
G01X1894783Y670984D02*
Y670972D01*
G01X1894786Y667809D02*
X1894787Y667796D01*
G01X1894783Y667822D02*
X1894786Y667809D01*
G01X1894783Y667835D02*
Y667822D01*
G01X1894786Y664659D02*
X1894787Y664646D01*
G01X1894783Y664672D02*
X1894786Y664659D01*
G01X1894783Y664685D02*
Y664672D01*
G01X1894786Y661510D02*
X1894787Y661496D01*
G01X1894783Y661523D02*
X1894786Y661510D01*
G01X1894783Y661535D02*
Y661523D01*
G01X1894786Y658360D02*
X1894787Y658347D01*
G01X1894783Y658373D02*
X1894786Y658360D01*
G01X1894783Y658386D02*
Y658373D01*
G01X1894786Y655211D02*
X1894787Y655197D01*
G01X1894783Y655224D02*
X1894786Y655211D01*
G01X1894783Y655236D02*
Y655224D01*
G01X1894786Y652061D02*
X1894787Y652048D01*
G01X1894783Y652074D02*
X1894786Y652061D01*
G01X1894783Y652087D02*
Y652074D01*
G01X1893838Y657041D02*
X1893839Y657034D01*
G01X1893837Y657046D02*
X1893838Y657041D01*
G01X1893837Y657039D02*
Y657046D01*
G01X1893838Y666490D02*
X1893839Y666483D01*
G01X1893837Y666495D02*
X1893838Y666490D01*
G01X1893837Y666488D02*
Y666495D01*
G01X1894783Y669422D02*
Y669409D01*
G01X1894785Y669435D02*
X1894783Y669422D01*
G01X1894787Y669448D02*
X1894785Y669435D01*
G01X1894783Y666272D02*
Y666260D01*
G01X1894785Y666285D02*
X1894783Y666272D01*
G01X1894787Y666299D02*
X1894785Y666285D01*
G01X1894783Y663123D02*
Y663110D01*
G01X1894785Y663136D02*
X1894783Y663123D01*
G01X1894787Y663149D02*
X1894785Y663136D01*
G01X1894783Y659973D02*
Y659961D01*
G01X1894785Y659986D02*
X1894783Y659973D01*
G01X1894787Y660000D02*
X1894785Y659986D01*
G01X1894783Y656824D02*
Y656811D01*
G01X1894785Y656837D02*
X1894783Y656824D01*
G01X1894787Y656850D02*
X1894785Y656837D01*
G01X1894783Y653674D02*
Y653661D01*
G01X1894785Y653687D02*
X1894783Y653674D01*
G01X1894787Y653700D02*
X1894785Y653687D01*
G01X1894783Y650524D02*
Y650512D01*
G01X1894785Y650537D02*
X1894783Y650524D01*
G01X1894787Y650551D02*
X1894785Y650537D01*
G01X1893838Y650743D02*
X1893839Y650735D01*
G01X1893837Y650747D02*
X1893838Y650743D01*
G01X1893837Y650741D02*
Y650747D01*
G01X1893852Y670779D02*
X1893876Y670787D01*
G01X1893840Y670765D02*
X1893852Y670779D01*
G01X1893839Y670758D02*
X1893840Y670765D01*
G01X1893852Y667630D02*
X1893876Y667638D01*
G01X1893840Y667615D02*
X1893852Y667630D01*
G01X1893839Y667608D02*
X1893840Y667615D01*
G01X1893852Y664480D02*
X1893876Y664488D01*
G01X1893840Y664465D02*
X1893852Y664480D01*
G01X1893839Y664459D02*
X1893840Y664465D01*
G01X1893852Y661330D02*
X1893876Y661339D01*
G01X1893840Y661316D02*
X1893852Y661330D01*
G01X1893839Y661309D02*
X1893840Y661316D01*
G01X1893852Y658181D02*
X1893876Y658189D01*
G01X1893840Y658166D02*
X1893852Y658181D01*
G01X1893839Y658159D02*
X1893840Y658166D01*
G01X1893852Y655031D02*
X1893876Y655039D01*
G01X1893840Y655017D02*
X1893852Y655031D01*
G01X1893839Y655010D02*
X1893840Y655017D01*
G01X1893852Y651881D02*
X1893876Y651890D01*
G01X1893840Y651867D02*
X1893852Y651881D01*
G01X1893839Y651860D02*
X1893840Y651867D01*
G01X1894822Y651853D02*
X1894823Y651864D01*
G01X1894822Y655002D02*
X1894823Y655013D01*
G01X1894822Y658152D02*
X1894823Y658163D01*
G01X1894822Y661302D02*
X1894823Y661313D01*
G01X1894822Y664451D02*
X1894823Y664462D01*
G01X1894822Y667601D02*
X1894823Y667612D01*
G01X1894822Y670750D02*
X1894823Y670761D01*
G01X1908248Y648911D02*
Y648920D01*
G01Y673911D02*
Y673920D01*
G01Y678911D02*
Y678920D01*
G01Y683911D02*
Y683920D01*
G01Y688911D02*
Y688920D01*
G01Y693911D02*
Y693920D01*
G01X1909429Y673937D02*
Y672559D01*
G01Y678937D02*
Y677559D01*
G01Y683937D02*
Y682559D01*
G01Y688937D02*
Y687559D01*
G01Y693937D02*
Y692559D01*
G01X1908858Y671791D02*
Y649705D01*
G01X1908248Y692067D02*
Y694429D01*
G01Y687067D02*
Y689429D01*
G01Y682067D02*
Y684429D01*
G01Y677067D02*
Y679429D01*
G01Y672067D02*
Y674429D01*
G01X1907677Y670610D02*
Y650886D01*
G01X1907264Y674429D02*
Y672067D01*
G01Y679429D02*
Y677067D01*
G01Y684429D02*
Y682067D01*
G01Y689429D02*
Y687067D01*
G01Y694429D02*
Y692067D01*
G01X1904921Y748248D02*
Y671791D01*
G01X1903740Y747067D02*
Y670610D01*
G01X1895276Y751988D02*
Y672953D01*
G01X1894823Y669449D02*
Y670945D01*
G01Y666299D02*
Y667795D01*
G01Y663150D02*
Y664646D01*
G01Y660000D02*
Y661496D01*
G01Y656850D02*
Y658346D01*
G01Y653701D02*
Y655197D01*
G01Y650551D02*
Y652047D01*
G01X1894783Y650698D02*
Y650551D01*
G01Y652048D02*
Y651901D01*
G01Y656997D02*
Y656850D01*
G01Y653847D02*
Y653700D01*
G01Y655197D02*
Y655051D01*
G01Y660146D02*
Y660000D01*
G01Y661496D02*
Y661350D01*
G01Y658347D02*
Y658200D01*
G01Y666446D02*
Y666299D01*
G01Y663296D02*
Y663149D01*
G01Y664646D02*
Y664500D01*
G01Y669595D02*
Y669448D01*
G01Y670945D02*
Y670799D01*
G01Y667796D02*
Y667649D01*
G01X1893878Y669448D02*
Y669595D01*
G01Y670799D02*
Y670946D01*
G01Y667649D02*
Y667796D01*
G01Y666298D02*
Y666446D01*
G01Y663149D02*
Y663296D01*
G01Y664500D02*
Y664646D01*
G01Y659999D02*
Y660146D01*
G01Y661350D02*
Y661497D01*
G01Y658200D02*
Y658347D01*
G01Y656850D02*
Y656997D01*
G01Y653700D02*
Y653847D01*
G01Y655051D02*
Y655198D01*
G01Y650550D02*
Y650698D01*
G01Y651901D02*
Y652048D01*
G01X1893839Y652047D02*
Y650551D01*
G01Y655197D02*
Y653701D01*
G01Y661496D02*
Y660000D01*
G01Y658346D02*
Y656850D01*
G01Y664646D02*
Y663150D01*
G01Y670945D02*
Y669449D01*
G01Y667795D02*
Y666299D01*
G01X1892657Y651890D02*
Y650709D01*
G01Y658189D02*
Y657008D01*
G01Y655039D02*
Y653858D01*
G01Y661339D02*
Y660157D01*
G01Y667638D02*
Y666457D01*
G01Y664488D02*
Y663307D01*
G01Y670787D02*
Y669606D01*
G01X1892323Y672953D02*
Y648543D01*
G01X1891929D02*
Y672953D01*
G01X1888898Y669606D02*
Y670787D01*
G01Y666457D02*
Y667638D01*
G01Y663307D02*
Y664488D01*
G01Y660157D02*
Y661339D01*
G01Y657008D02*
Y658189D01*
G01Y653858D02*
Y655039D01*
G01Y650709D02*
Y651890D01*
G01X1894823Y669632D02*
X1894822Y669643D01*
G01X1894823Y666483D02*
X1894822Y666494D01*
G01X1894823Y663333D02*
X1894822Y663344D01*
G01X1894823Y660183D02*
X1894822Y660194D01*
G01X1894823Y657034D02*
X1894822Y657045D01*
G01X1894823Y653884D02*
X1894822Y653895D01*
G01X1894823Y650735D02*
X1894822Y650746D01*
G01X1894782Y666457D02*
X1894785Y666446D01*
G01X1907677Y670610D02*
X1908858Y671791D01*
G01X1903740Y670610D02*
X1904921Y671791D01*
G01X1907677Y650886D02*
X1908858Y649705D01*
G01X1903740Y650886D02*
X1904921Y649705D01*
G01X1893725Y669646D02*
X1893837Y669637D01*
G01X1893836Y660193D02*
X1893725Y660197D01*
G01X1893836Y653894D02*
X1893725Y653898D01*
G01X1893836Y663343D02*
X1893725Y663346D01*
G01X1908248Y694429D02*
X1907264D01*
G01X1907265Y693937D02*
X1912598D01*
G01Y693898D02*
X1908250D01*
G01X1912598Y692559D02*
X1907265D01*
G01X1907264Y692067D02*
X1908248D01*
G01Y689429D02*
X1907264D01*
G01X1907265Y688937D02*
X1912598D01*
G01Y688898D02*
X1908250D01*
G01X1912598Y687559D02*
X1907265D01*
G01X1907264Y687067D02*
X1908248D01*
G01Y684429D02*
X1907264D01*
G01X1907265Y683937D02*
X1912598D01*
G01Y683898D02*
X1908250D01*
G01X1912598Y682559D02*
X1907265D01*
G01X1907264Y682067D02*
X1908248D01*
G01Y679429D02*
X1907264D01*
G01X1907265Y678937D02*
X1912598D01*
G01Y678898D02*
X1908250D01*
G01X1912598Y677559D02*
X1907265D01*
G01X1907264Y677067D02*
X1908248D01*
G01Y674429D02*
X1907264D01*
G01X1907265Y673937D02*
X1912598D01*
G01Y673898D02*
X1908250D01*
G01X1895276Y672953D02*
X1891929D01*
G01X1912598Y672559D02*
X1907265D01*
G01X1907264Y672067D02*
X1908248D01*
G01X1904921Y671791D02*
X1908858D01*
G01X1894783Y670984D02*
X1893878D01*
G01X1894823Y670945D02*
X1893839D01*
G01X1894782Y670787D02*
X1888898D01*
G01Y670748D02*
X1894822D01*
G01X1903740Y670610D02*
X1907677D01*
G01X1894821Y669646D02*
X1888898D01*
G01X1894782Y669606D02*
X1888898D01*
G01X1893839Y669449D02*
X1894823D01*
G01X1893878Y669409D02*
X1894783D01*
G01Y667835D02*
X1893878D01*
G01X1894823Y667795D02*
X1893839D01*
G01X1894782Y667638D02*
X1888898D01*
G01Y667598D02*
X1894822D01*
G01X1894821Y666496D02*
X1888898D01*
G01X1894782Y666457D02*
X1888898D01*
G01X1893839Y666299D02*
X1894823D01*
G01X1893878Y666260D02*
X1894783D01*
G01Y664685D02*
X1893878D01*
G01X1894823Y664646D02*
X1893839D01*
G01X1894782Y664488D02*
X1888898D01*
G01Y664449D02*
X1894822D01*
G01X1893091Y663346D02*
X1892657D01*
G01X1894821D02*
X1888898D01*
G01X1894782Y663307D02*
X1888898D01*
G01X1893839Y663150D02*
X1894823D01*
G01X1893878Y663110D02*
X1894783D01*
G01Y661535D02*
X1893878D01*
G01X1894823Y661496D02*
X1893839D01*
G01X1894782Y661339D02*
X1888898D01*
G01Y661299D02*
X1894822D01*
G01X1893091Y660197D02*
X1892657D01*
G01X1894821D02*
X1888898D01*
G01X1894782Y660157D02*
X1888898D01*
G01X1893839Y660000D02*
X1894823D01*
G01X1893878Y659961D02*
X1894783D01*
G01Y658386D02*
X1893878D01*
G01X1894823Y658346D02*
X1893839D01*
G01X1894782Y658189D02*
X1888898D01*
G01Y658150D02*
X1894822D01*
G01X1894821Y657047D02*
X1888898D01*
G01X1894782Y657008D02*
X1888898D01*
G01X1893839Y656850D02*
X1894823D01*
G01X1893878Y656811D02*
X1894783D01*
G01Y655236D02*
X1893878D01*
G01X1894823Y655197D02*
X1893839D01*
G01X1894782Y655039D02*
X1888898D01*
G01Y655000D02*
X1894822D01*
G01X1893091Y653898D02*
X1892657D01*
G01X1894821D02*
X1888898D01*
G01X1894782Y653858D02*
X1888898D01*
G01X1893839Y653701D02*
X1894823D01*
G01X1893878Y653661D02*
X1894783D01*
G01Y652087D02*
X1893878D01*
G01X1894823Y652047D02*
X1893839D01*
G01X1894782Y651890D02*
X1888898D01*
G01Y651850D02*
X1894822D01*
G01X1907677Y650886D02*
X1903740D01*
G01X1894821Y650748D02*
X1888898D01*
G01X1894782Y650709D02*
X1888898D01*
G01X1893839Y650551D02*
X1894823D01*
G01X1893878Y650512D02*
X1894783D01*
G01X1908858Y649705D02*
X1904921D01*
G01X1908248Y649429D02*
X1907264D01*
G01X1907265Y648937D02*
X1912598D01*
G01Y648898D02*
X1908250D01*
G01X1895276Y648543D02*
X1891929D01*
G01X1907264Y694133D02*
X1908219Y694134D01*
G01X1908248Y692363D02*
X1907264Y692362D01*
G01Y689133D02*
X1908219Y689134D01*
G01X1908248Y687363D02*
X1907264Y687362D01*
G01Y684133D02*
X1908219Y684134D01*
G01X1908248Y682363D02*
X1907264Y682362D01*
G01Y679133D02*
X1908219Y679134D01*
G01X1908248Y677363D02*
X1907264Y677362D01*
G01Y674133D02*
X1908219Y674134D01*
G01X1908248Y672363D02*
X1907264Y672362D01*
G01Y649133D02*
X1908219Y649134D01*
G01X1908235Y698929D02*
X1908246Y698913D01*
G01X1908211Y698937D02*
X1908235Y698929D01*
G01Y703929D02*
X1908246Y703913D01*
G01X1908211Y703937D02*
X1908235Y703929D01*
G01Y708929D02*
X1908246Y708913D01*
G01X1908211Y708937D02*
X1908235Y708929D01*
G01Y713929D02*
X1908246Y713913D01*
G01X1908211Y713937D02*
X1908235Y713929D01*
G01Y718929D02*
X1908246Y718913D01*
G01X1908211Y718937D02*
X1908235Y718929D01*
G01Y723929D02*
X1908246Y723913D01*
G01X1908211Y723937D02*
X1908235Y723929D01*
G01Y728929D02*
X1908246Y728913D01*
G01X1908211Y728937D02*
X1908235Y728929D01*
G01Y733929D02*
X1908246Y733913D01*
G01X1908211Y733937D02*
X1908235Y733929D01*
G01Y738929D02*
X1908246Y738913D01*
G01X1908211Y738937D02*
X1908235Y738929D01*
G01Y743929D02*
X1908246Y743913D01*
G01X1908211Y743937D02*
X1908235Y743929D01*
G01X1908248Y698904D02*
Y698911D01*
G01X1908249Y698900D02*
X1908248Y698904D01*
G01X1908250Y698898D02*
X1908249Y698900D01*
G01X1908248Y703904D02*
Y703911D01*
G01X1908249Y703900D02*
X1908248Y703904D01*
G01X1908250Y703898D02*
X1908249Y703900D01*
G01X1908248Y708904D02*
Y708911D01*
G01X1908249Y708900D02*
X1908248Y708904D01*
G01X1908250Y708898D02*
X1908249Y708900D01*
G01X1908248Y713904D02*
Y713911D01*
G01X1908249Y713900D02*
X1908248Y713904D01*
G01X1908250Y713898D02*
X1908249Y713900D01*
G01X1908248Y718904D02*
Y718911D01*
G01X1908249Y718900D02*
X1908248Y718904D01*
G01X1908250Y718898D02*
X1908249Y718900D01*
G01X1908248Y723904D02*
Y723911D01*
G01X1908249Y723900D02*
X1908248Y723904D01*
G01X1908250Y723898D02*
X1908249Y723900D01*
G01X1908248Y728904D02*
Y728911D01*
G01X1908249Y728900D02*
X1908248Y728904D01*
G01X1908250Y728898D02*
X1908249Y728900D01*
G01X1908248Y733904D02*
Y733911D01*
G01X1908249Y733900D02*
X1908248Y733904D01*
G01X1908250Y733898D02*
X1908249Y733900D01*
G01X1908248Y738904D02*
Y738911D01*
G01X1908249Y738900D02*
X1908248Y738904D01*
G01X1908250Y738898D02*
X1908249Y738900D01*
G01X1908248Y743904D02*
Y743911D01*
G01X1908249Y743900D02*
X1908248Y743904D01*
G01X1908250Y743898D02*
X1908249Y743900D01*
G01X1908248Y742552D02*
Y742543D01*
G01X1908249Y742557D02*
X1908248Y742552D01*
G01X1908251Y742559D02*
X1908249Y742557D01*
G01X1908248Y737552D02*
Y737543D01*
G01X1908249Y737557D02*
X1908248Y737552D01*
G01X1908251Y737559D02*
X1908249Y737557D01*
G01X1908248Y732552D02*
Y732543D01*
G01X1908249Y732557D02*
X1908248Y732552D01*
G01X1908251Y732559D02*
X1908249Y732557D01*
G01X1908248Y727552D02*
Y727543D01*
G01X1908249Y727557D02*
X1908248Y727552D01*
G01X1908251Y727559D02*
X1908249Y727557D01*
G01X1908248Y722552D02*
Y722543D01*
G01X1908249Y722557D02*
X1908248Y722552D01*
G01X1908251Y722559D02*
X1908249Y722557D01*
G01X1908248Y717552D02*
Y717543D01*
G01X1908249Y717557D02*
X1908248Y717552D01*
G01X1908251Y717559D02*
X1908249Y717557D01*
G01X1908248Y712552D02*
Y712543D01*
G01X1908249Y712557D02*
X1908248Y712552D01*
G01X1908251Y712559D02*
X1908249Y712557D01*
G01X1908248Y707552D02*
Y707543D01*
G01X1908249Y707557D02*
X1908248Y707552D01*
G01X1908251Y707559D02*
X1908249Y707557D01*
G01X1908248Y702552D02*
Y702543D01*
G01X1908249Y702557D02*
X1908248Y702552D01*
G01X1908251Y702559D02*
X1908249Y702557D01*
G01X1908248Y697552D02*
Y697543D01*
G01X1908249Y697557D02*
X1908248Y697552D01*
G01X1908251Y697559D02*
X1908249Y697557D01*
G01X1907264Y698944D02*
Y698954D01*
G01X1907265Y698939D02*
X1907264Y698944D01*
G01X1907265Y698937D02*
Y698939D01*
G01X1907264Y703944D02*
Y703954D01*
G01X1907265Y703939D02*
X1907264Y703944D01*
G01X1907265Y703937D02*
Y703939D01*
G01X1907264Y708944D02*
Y708954D01*
G01X1907265Y708939D02*
X1907264Y708944D01*
G01X1907265Y708937D02*
Y708939D01*
G01X1907264Y713944D02*
Y713954D01*
G01X1907265Y713939D02*
X1907264Y713944D01*
G01X1907265Y713937D02*
Y713939D01*
G01X1907264Y718944D02*
Y718954D01*
G01X1907265Y718939D02*
X1907264Y718944D01*
G01X1907265Y718937D02*
Y718939D01*
G01X1907264Y723944D02*
Y723954D01*
G01X1907265Y723939D02*
X1907264Y723944D01*
G01X1907265Y723937D02*
Y723939D01*
G01X1907264Y728944D02*
Y728954D01*
G01X1907265Y728939D02*
X1907264Y728944D01*
G01X1907265Y728937D02*
Y728939D01*
G01X1907264Y733944D02*
Y733954D01*
G01X1907265Y733939D02*
X1907264Y733944D01*
G01X1907265Y733937D02*
Y733939D01*
G01X1907264Y738944D02*
Y738954D01*
G01X1907265Y738939D02*
X1907264Y738944D01*
G01X1907265Y738937D02*
Y738939D01*
G01X1907264Y743944D02*
Y743954D01*
G01X1907265Y743939D02*
X1907264Y743944D01*
G01X1907265Y743937D02*
Y743939D01*
G01X1908240Y699081D02*
X1908248Y699055D01*
G01X1908230Y699107D02*
X1908240Y699081D01*
G01X1908219Y699134D02*
X1908230Y699107D01*
G01X1908240Y704081D02*
X1908248Y704055D01*
G01X1908230Y704107D02*
X1908240Y704081D01*
G01X1908219Y704134D02*
X1908230Y704107D01*
G01X1908240Y709081D02*
X1908248Y709055D01*
G01X1908230Y709107D02*
X1908240Y709081D01*
G01X1908219Y709134D02*
X1908230Y709107D01*
G01X1908240Y714081D02*
X1908248Y714055D01*
G01X1908230Y714107D02*
X1908240Y714081D01*
G01X1908219Y714134D02*
X1908230Y714107D01*
G01X1908240Y719081D02*
X1908248Y719055D01*
G01X1908230Y719107D02*
X1908240Y719081D01*
G01X1908219Y719134D02*
X1908230Y719107D01*
G01X1908240Y724081D02*
X1908248Y724055D01*
G01X1908230Y724107D02*
X1908240Y724081D01*
G01X1908219Y724134D02*
X1908230Y724107D01*
G01X1908240Y729081D02*
X1908248Y729055D01*
G01X1908230Y729107D02*
X1908240Y729081D01*
G01X1908219Y729134D02*
X1908230Y729107D01*
G01X1908240Y734081D02*
X1908248Y734055D01*
G01X1908230Y734107D02*
X1908240Y734081D01*
G01X1908219Y734134D02*
X1908230Y734107D01*
G01X1908240Y739081D02*
X1908248Y739055D01*
G01X1908230Y739107D02*
X1908240Y739081D01*
G01X1908219Y739134D02*
X1908230Y739107D01*
G01X1908240Y744081D02*
X1908248Y744055D01*
G01X1908230Y744107D02*
X1908240Y744081D01*
G01X1908219Y744134D02*
X1908230Y744107D01*
G01X1908231Y698932D02*
X1908211Y698937D01*
G01X1908245Y698918D02*
X1908231Y698932D01*
G01X1908250Y698898D02*
X1908245Y698918D01*
G01X1908231Y703932D02*
X1908211Y703937D01*
G01X1908245Y703918D02*
X1908231Y703932D01*
G01X1908250Y703898D02*
X1908245Y703918D01*
G01X1908231Y708932D02*
X1908211Y708937D01*
G01X1908245Y708918D02*
X1908231Y708932D01*
G01X1908250Y708898D02*
X1908245Y708918D01*
G01X1908231Y713932D02*
X1908211Y713937D01*
G01X1908245Y713918D02*
X1908231Y713932D01*
G01X1908250Y713898D02*
X1908245Y713918D01*
G01X1908231Y718932D02*
X1908211Y718937D01*
G01X1908245Y718918D02*
X1908231Y718932D01*
G01X1908250Y718898D02*
X1908245Y718918D01*
G01X1908231Y723932D02*
X1908211Y723937D01*
G01X1908245Y723918D02*
X1908231Y723932D01*
G01X1908250Y723898D02*
X1908245Y723918D01*
G01X1908231Y728932D02*
X1908211Y728937D01*
G01X1908245Y728918D02*
X1908231Y728932D01*
G01X1908250Y728898D02*
X1908245Y728918D01*
G01X1908231Y733932D02*
X1908211Y733937D01*
G01X1908245Y733918D02*
X1908231Y733932D01*
G01X1908250Y733898D02*
X1908245Y733918D01*
G01X1908231Y738932D02*
X1908211Y738937D01*
G01X1908245Y738918D02*
X1908231Y738932D01*
G01X1908250Y738898D02*
X1908245Y738918D01*
G01X1908231Y743932D02*
X1908211Y743937D01*
G01X1908245Y743918D02*
X1908231Y743932D01*
G01X1908250Y743898D02*
X1908245Y743918D01*
G01X1908215Y699035D02*
X1908219Y699134D01*
G01X1908209Y698963D02*
X1908215Y699035D01*
G01X1908211Y698937D02*
X1908209Y698963D01*
G01X1908215Y704035D02*
X1908219Y704134D01*
G01X1908209Y703963D02*
X1908215Y704035D01*
G01X1908211Y703937D02*
X1908209Y703963D01*
G01X1908215Y709035D02*
X1908219Y709134D01*
G01X1908209Y708963D02*
X1908215Y709035D01*
G01X1908211Y708937D02*
X1908209Y708963D01*
G01X1908215Y714035D02*
X1908219Y714134D01*
G01X1908209Y713963D02*
X1908215Y714035D01*
G01X1908211Y713937D02*
X1908209Y713963D01*
G01X1908215Y719035D02*
X1908219Y719134D01*
G01X1908209Y718963D02*
X1908215Y719035D01*
G01X1908211Y718937D02*
X1908209Y718963D01*
G01X1908215Y724035D02*
X1908219Y724134D01*
G01X1908209Y723963D02*
X1908215Y724035D01*
G01X1908211Y723937D02*
X1908209Y723963D01*
G01X1908215Y729035D02*
X1908219Y729134D01*
G01X1908209Y728963D02*
X1908215Y729035D01*
G01X1908211Y728937D02*
X1908209Y728963D01*
G01X1908215Y734035D02*
X1908219Y734134D01*
G01X1908209Y733963D02*
X1908215Y734035D01*
G01X1908211Y733937D02*
X1908209Y733963D01*
G01X1908215Y739035D02*
X1908219Y739134D01*
G01X1908209Y738963D02*
X1908215Y739035D01*
G01X1908211Y738937D02*
X1908209Y738963D01*
G01X1908215Y744035D02*
X1908219Y744134D01*
G01X1908209Y743963D02*
X1908215Y744035D01*
G01X1908211Y743937D02*
X1908209Y743963D01*
G01X1907265Y742557D02*
Y742559D01*
G01X1907264Y742552D02*
X1907265Y742557D01*
G01X1907264Y742543D02*
Y742552D01*
G01X1907265Y737557D02*
Y737559D01*
G01X1907264Y737552D02*
X1907265Y737557D01*
G01X1907264Y737543D02*
Y737552D01*
G01X1907265Y732557D02*
Y732559D01*
G01X1907264Y732552D02*
X1907265Y732557D01*
G01X1907264Y732543D02*
Y732552D01*
G01X1907265Y727557D02*
Y727559D01*
G01X1907264Y727552D02*
X1907265Y727557D01*
G01X1907264Y727543D02*
Y727552D01*
G01X1907265Y722557D02*
Y722559D01*
G01X1907264Y722552D02*
X1907265Y722557D01*
G01X1907264Y722543D02*
Y722552D01*
G01X1907265Y717557D02*
Y717559D01*
G01X1907264Y717552D02*
X1907265Y717557D01*
G01X1907264Y717543D02*
Y717552D01*
G01X1907265Y712557D02*
Y712559D01*
G01X1907264Y712552D02*
X1907265Y712557D01*
G01X1907264Y712543D02*
Y712552D01*
G01X1907265Y707557D02*
Y707559D01*
G01X1907264Y707552D02*
X1907265Y707557D01*
G01X1907264Y707543D02*
Y707552D01*
G01X1907265Y702557D02*
Y702559D01*
G01X1907264Y702552D02*
X1907265Y702557D01*
G01X1907264Y702543D02*
Y702552D01*
G01X1907265Y697557D02*
Y697559D01*
G01X1907264Y697552D02*
X1907265Y697557D01*
G01X1907264Y697543D02*
Y697552D01*
G01X1908248Y698911D02*
Y698920D01*
G01Y703911D02*
Y703920D01*
G01Y708911D02*
Y708920D01*
G01Y713911D02*
Y713920D01*
G01Y718911D02*
Y718920D01*
G01Y723911D02*
Y723920D01*
G01Y728911D02*
Y728920D01*
G01Y733911D02*
Y733920D01*
G01Y738911D02*
Y738920D01*
G01Y743911D02*
Y743920D01*
G01X1909429Y698937D02*
Y697559D01*
G01Y703937D02*
Y702559D01*
G01Y708937D02*
Y707559D01*
G01Y713937D02*
Y712559D01*
G01Y718937D02*
Y717559D01*
G01Y723937D02*
Y722559D01*
G01Y728937D02*
Y727559D01*
G01Y733937D02*
Y732559D01*
G01Y738937D02*
Y737559D01*
G01Y743937D02*
Y742559D01*
G01X1908248Y742067D02*
Y744429D01*
G01Y737067D02*
Y739429D01*
G01Y732067D02*
Y734429D01*
G01Y727067D02*
Y729429D01*
G01Y722067D02*
Y724429D01*
G01Y717067D02*
Y719429D01*
G01Y712067D02*
Y714429D01*
G01Y707067D02*
Y709429D01*
G01Y702067D02*
Y704429D01*
G01Y697067D02*
Y699429D01*
G01X1907264D02*
Y697067D01*
G01Y704429D02*
Y702067D01*
G01Y709429D02*
Y707067D01*
G01Y714429D02*
Y712067D01*
G01Y719429D02*
Y717067D01*
G01Y724429D02*
Y722067D01*
G01Y729429D02*
Y727067D01*
G01Y734429D02*
Y732067D01*
G01Y739429D02*
Y737067D01*
G01Y744429D02*
Y742067D01*
G01X1908248Y744429D02*
X1907264D01*
G01X1907265Y743937D02*
X1912598D01*
G01Y743898D02*
X1908250D01*
G01X1912598Y742559D02*
X1907265D01*
G01X1907264Y742067D02*
X1908248D01*
G01Y739429D02*
X1907264D01*
G01X1907265Y738937D02*
X1912598D01*
G01Y738898D02*
X1908250D01*
G01X1912598Y737559D02*
X1907265D01*
G01X1907264Y737067D02*
X1908248D01*
G01Y734429D02*
X1907264D01*
G01X1907265Y733937D02*
X1912598D01*
G01Y733898D02*
X1908250D01*
G01X1912598Y732559D02*
X1907265D01*
G01X1907264Y732067D02*
X1908248D01*
G01Y729429D02*
X1907264D01*
G01X1907265Y728937D02*
X1912598D01*
G01Y728898D02*
X1908250D01*
G01X1912598Y727559D02*
X1907265D01*
G01X1907264Y727067D02*
X1908248D01*
G01Y724429D02*
X1907264D01*
G01X1907265Y723937D02*
X1912598D01*
G01Y723898D02*
X1908250D01*
G01X1912598Y722559D02*
X1907265D01*
G01X1907264Y722067D02*
X1908248D01*
G01Y719429D02*
X1907264D01*
G01X1907265Y718937D02*
X1912598D01*
G01Y718898D02*
X1908250D01*
G01X1912598Y717559D02*
X1907265D01*
G01X1907264Y717067D02*
X1908248D01*
G01Y714429D02*
X1907264D01*
G01X1907265Y713937D02*
X1912598D01*
G01Y713898D02*
X1908250D01*
G01X1912598Y712559D02*
X1907265D01*
G01X1907264Y712067D02*
X1908248D01*
G01Y709429D02*
X1907264D01*
G01X1907265Y708937D02*
X1912598D01*
G01Y708898D02*
X1908250D01*
G01X1912598Y707559D02*
X1907265D01*
G01X1907264Y707067D02*
X1908248D01*
G01X1907264Y744133D02*
X1908219Y744134D01*
G01X1908248Y742363D02*
X1907264Y742362D01*
G01Y739133D02*
X1908219Y739134D01*
G01X1908248Y737363D02*
X1907264Y737362D01*
G01Y734133D02*
X1908219Y734134D01*
G01X1908248Y732363D02*
X1907264Y732362D01*
G01Y729133D02*
X1908219Y729134D01*
G01X1908248Y727363D02*
X1907264Y727362D01*
G01Y724133D02*
X1908219Y724134D01*
G01X1908248Y722363D02*
X1907264Y722362D01*
G01Y719133D02*
X1908219Y719134D01*
G01X1908248Y717363D02*
X1907264Y717362D01*
G01Y714133D02*
X1908219Y714134D01*
G01X1908248Y712363D02*
X1907264Y712362D01*
G01Y709133D02*
X1908219Y709134D01*
G01X1908248Y707363D02*
X1907264Y707362D01*
G01X1908248Y704429D02*
X1907264D01*
G01X1907265Y703937D02*
X1912598D01*
G01Y703898D02*
X1908250D01*
G01X1912598Y702559D02*
X1907265D01*
G01X1907264Y702067D02*
X1908248D01*
G01Y699429D02*
X1907264D01*
G01X1907265Y698937D02*
X1912598D01*
G01Y698898D02*
X1908250D01*
G01X1912598Y697559D02*
X1907265D01*
G01X1907264Y697067D02*
X1908248D01*
G01X1907264Y704133D02*
X1908219Y704134D01*
G01X1908248Y702363D02*
X1907264Y702362D01*
G01Y699133D02*
X1908219Y699134D01*
G01X1908248Y697363D02*
X1907264Y697362D01*
G01X1906693Y769429D02*
G03X1906102Y770020I-591J0D01*
G01X1899409D02*
G03X1898819Y769429I1J-591D01*
G01X1901575Y768248D02*
G03Y766280I0J-984D01*
G01X1903937D02*
G03Y768248I0J984D01*
G01X1893898Y770807D02*
G03X1891929Y768839I-1J-1968D01*
G01X1900197Y760335D02*
G03X1899016Y759154I0J-1181D01*
G01X1906496D02*
G03X1905315Y760335I-1181J0D01*
G01X1904646Y755059D02*
G03I-1890J0D01*
G01X1905118D02*
G03I-2362J0D01*
G01X1906693Y763327D02*
Y769429D01*
G01X1906496Y759154D02*
Y750610D01*
G01X1903937Y755650D02*
Y753957D01*
G01X1901575D02*
Y755650D01*
G01X1899016Y750610D02*
Y759154D01*
G01X1898819Y763327D02*
Y769429D01*
G01X1891929Y768839D02*
Y753091D01*
G01X1906247Y759879D02*
X1903937Y755650D01*
G01X1901575D02*
X1899265Y759879D01*
G01X1903937Y753957D02*
X1905241Y751988D01*
G01X1900271D02*
X1901575Y753957D01*
G01X1903740Y747067D02*
X1904921Y748248D01*
G01X1897047D02*
X1898228Y747067D01*
G01X1891929Y753091D02*
X1895276Y749744D01*
G01X1911614Y770807D02*
X1893898D01*
G01X1906102Y770020D02*
X1899409D01*
G01X1903937Y768248D02*
X1901575D01*
G01Y766280D02*
X1903937D01*
G01X1906693Y764902D02*
X1898819D01*
G01Y763327D02*
X1906693D01*
G01X1913583Y760374D02*
X1891929D01*
G01X1900197Y760335D02*
X1905315D01*
G01X1901575Y755650D02*
X1903937D01*
G01X1901575Y753957D02*
X1903937D01*
G01X1895276Y751988D02*
X1909646D01*
G01X1895276Y750610D02*
X1899016D01*
G01X1909646D02*
X1906496D01*
G01X1895276Y749744D02*
X1910236D01*
G01X1897047Y748248D02*
X1904921D01*
G01X1898228Y747067D02*
X1903740D01*
G01X1911614Y803937D02*
G03I-8268J0D01*
G01X1862795Y827559D02*
G03X1863976I590J0D01*
G01Y821260D02*
G03X1862795I-590J0D01*
G01Y827559D02*
G03X1863976I590J0D01*
G01Y821260D02*
G03X1862795I-590J0D01*
G01X1864764D02*
Y827559D01*
G01Y821260D02*
Y827559D01*
G01D02*
X1863976D01*
G01X1864764D02*
X1863976D01*
G01Y821260D02*
X1864764D01*
G01X1863976D02*
X1864764D01*
G01X1908248Y1080308D02*
Y1080299D01*
G01X1908249Y1080313D02*
X1908248Y1080308D01*
G01X1908251Y1080315D02*
X1908249Y1080313D01*
G01X1908248Y1075308D02*
Y1075299D01*
G01X1908249Y1075313D02*
X1908248Y1075308D01*
G01X1908251Y1075315D02*
X1908249Y1075313D01*
G01X1908248Y1070308D02*
Y1070299D01*
G01X1908249Y1070313D02*
X1908248Y1070308D01*
G01X1908251Y1070315D02*
X1908249Y1070313D01*
G01X1908235Y1071685D02*
X1908246Y1071669D01*
G01X1908211Y1071693D02*
X1908235Y1071685D01*
G01Y1076685D02*
X1908246Y1076669D01*
G01X1908211Y1076693D02*
X1908235Y1076685D01*
G01Y1081685D02*
X1908246Y1081669D01*
G01X1908211Y1081693D02*
X1908235Y1081685D01*
G01X1908215Y1071791D02*
X1908219Y1071890D01*
G01X1908209Y1071719D02*
X1908215Y1071791D01*
G01X1908211Y1071693D02*
X1908209Y1071719D01*
G01X1908215Y1076791D02*
X1908219Y1076890D01*
G01X1908209Y1076719D02*
X1908215Y1076791D01*
G01X1908211Y1076693D02*
X1908209Y1076719D01*
G01X1908215Y1081791D02*
X1908219Y1081890D01*
G01X1908209Y1081719D02*
X1908215Y1081791D01*
G01X1908211Y1081693D02*
X1908209Y1081719D01*
G01X1907265Y1080313D02*
Y1080315D01*
G01X1907264Y1080308D02*
X1907265Y1080313D01*
G01X1907264Y1080299D02*
Y1080308D01*
G01X1907265Y1075313D02*
Y1075315D01*
G01X1907264Y1075308D02*
X1907265Y1075313D01*
G01X1907264Y1075299D02*
Y1075308D01*
G01X1907265Y1070313D02*
Y1070315D01*
G01X1907264Y1070308D02*
X1907265Y1070313D01*
G01X1907264Y1070299D02*
Y1070308D01*
G01X1908248Y1071660D02*
Y1071667D01*
G01X1908249Y1071656D02*
X1908248Y1071660D01*
G01X1908250Y1071654D02*
X1908249Y1071656D01*
G01X1908248Y1076660D02*
Y1076667D01*
G01X1908249Y1076656D02*
X1908248Y1076660D01*
G01X1908250Y1076654D02*
X1908249Y1076656D01*
G01X1908248Y1081660D02*
Y1081667D01*
G01X1908249Y1081656D02*
X1908248Y1081660D01*
G01X1908250Y1081654D02*
X1908249Y1081656D01*
G01X1907264Y1071700D02*
Y1071709D01*
G01X1907265Y1071695D02*
X1907264Y1071700D01*
G01X1907265Y1071693D02*
Y1071695D01*
G01X1907264Y1076700D02*
Y1076709D01*
G01X1907265Y1076695D02*
X1907264Y1076700D01*
G01X1907265Y1076693D02*
Y1076695D01*
G01X1907264Y1081700D02*
Y1081709D01*
G01X1907265Y1081695D02*
X1907264Y1081700D01*
G01X1907265Y1081693D02*
Y1081695D01*
G01X1908240Y1071837D02*
X1908248Y1071811D01*
G01X1908230Y1071863D02*
X1908240Y1071837D01*
G01X1908219Y1071890D02*
X1908230Y1071863D01*
G01X1908240Y1076837D02*
X1908248Y1076811D01*
G01X1908230Y1076863D02*
X1908240Y1076837D01*
G01X1908219Y1076890D02*
X1908230Y1076863D01*
G01X1908240Y1081837D02*
X1908248Y1081811D01*
G01X1908230Y1081863D02*
X1908240Y1081837D01*
G01X1908219Y1081890D02*
X1908230Y1081863D01*
G01X1908231Y1071688D02*
X1908211Y1071693D01*
G01X1908245Y1071674D02*
X1908231Y1071688D01*
G01X1908250Y1071654D02*
X1908245Y1071674D01*
G01X1908231Y1076688D02*
X1908211Y1076693D01*
G01X1908245Y1076674D02*
X1908231Y1076688D01*
G01X1908250Y1076654D02*
X1908245Y1076674D01*
G01X1908231Y1081688D02*
X1908211Y1081693D01*
G01X1908245Y1081674D02*
X1908231Y1081688D01*
G01X1908250Y1081654D02*
X1908245Y1081674D01*
G01X1898819Y1044823D02*
G03X1899409Y1044232I591J0D01*
G01X1906102D02*
G03X1906693Y1044823I0J591D01*
G01X1903937Y1046004D02*
G03Y1047972I0J984D01*
G01X1901575D02*
G03Y1046004I0J-984D01*
G01X1903858Y1059193D02*
G03I-1102J0D01*
G01X1905315Y1053917D02*
G03X1906496Y1055098I0J1181D01*
G01X1899016D02*
G03X1900197Y1053917I1181J0D01*
G01X1904331Y1059193D02*
G03I-1575J0D01*
G01X1891929Y1045413D02*
G03X1893898Y1043445I1969J1D01*
G01X1903937Y1058602D02*
X1906247Y1054373D01*
G01X1901575Y1060295D02*
X1900271Y1062264D01*
G01X1908248Y1071667D02*
Y1071676D01*
G01Y1076667D02*
Y1076676D01*
G01Y1081667D02*
Y1081676D01*
G01X1909646Y1204744D02*
Y1062264D01*
G01X1909429Y1071693D02*
Y1070315D01*
G01Y1076693D02*
Y1075315D01*
G01Y1081693D02*
Y1080315D01*
G01X1908248Y1079823D02*
Y1082185D01*
G01Y1074823D02*
Y1077185D01*
G01Y1069823D02*
Y1072185D01*
G01Y1071667D02*
Y1071811D01*
G01Y1081667D02*
Y1081811D01*
G01Y1076667D02*
Y1076811D01*
G01X1907264Y1072185D02*
Y1069823D01*
G01Y1077185D02*
Y1074823D01*
G01Y1082185D02*
Y1079823D01*
G01X1906693Y1050925D02*
Y1044823D01*
G01X1906496Y1063642D02*
Y1055098D01*
G01X1904921Y1102461D02*
Y1066004D01*
G01X1903937Y1060295D02*
Y1058602D01*
G01X1903740Y1103642D02*
Y1067185D01*
G01X1901575Y1058602D02*
Y1060295D01*
G01X1899016Y1055098D02*
Y1063642D01*
G01X1898819Y1050925D02*
Y1044823D01*
G01X1898228Y1067185D02*
Y1199823D01*
G01X1897047Y1066004D02*
Y1201004D01*
G01X1895276Y1101299D02*
Y1062264D01*
G01X1891929Y1061161D02*
Y1045413D01*
G01X1903740Y1067185D02*
X1904921Y1066004D01*
G01X1899265Y1054373D02*
X1901575Y1058602D01*
G01X1905241Y1062264D02*
X1903937Y1060295D01*
G01X1898228Y1067185D02*
X1897047Y1066004D01*
G01X1895276Y1064508D02*
X1891929Y1061161D01*
G01X1908248Y1082185D02*
X1907264D01*
G01X1907265Y1081693D02*
X1912598D01*
G01Y1081654D02*
X1908250D01*
G01X1912598Y1080315D02*
X1907265D01*
G01X1907264Y1079823D02*
X1908248D01*
G01Y1077185D02*
X1907264D01*
G01X1907265Y1076693D02*
X1912598D01*
G01Y1076654D02*
X1908250D01*
G01X1912598Y1075315D02*
X1907265D01*
G01X1907264Y1074823D02*
X1908248D01*
G01Y1072185D02*
X1907264D01*
G01X1907265Y1071693D02*
X1912598D01*
G01Y1071654D02*
X1908250D01*
G01X1912598Y1070315D02*
X1907265D01*
G01X1907264Y1069823D02*
X1908248D01*
G01X1903740Y1067185D02*
X1898228D01*
G01X1904921Y1066004D02*
X1897047D01*
G01X1910236Y1064508D02*
X1895276D01*
G01X1907264Y1081889D02*
X1908219Y1081890D01*
G01X1908248Y1080119D02*
X1907264Y1080118D01*
G01Y1076889D02*
X1908219Y1076890D01*
G01X1908248Y1075119D02*
X1907264Y1075118D01*
G01Y1071889D02*
X1908219Y1071890D01*
G01X1908248Y1070119D02*
X1907264Y1070118D01*
G01X1906496Y1063642D02*
X1909646D01*
G01X1899016D02*
X1895276D01*
G01Y1062264D02*
X1909646D01*
G01X1903937Y1060295D02*
X1901575D01*
G01X1903937Y1058602D02*
X1901575D01*
G01X1905315Y1053917D02*
X1900197D01*
G01X1913583Y1053878D02*
X1891929D01*
G01X1906693Y1050925D02*
X1898819D01*
G01Y1049350D02*
X1906693D01*
G01X1903937Y1047972D02*
X1901575D01*
G01Y1046004D02*
X1903937D01*
G01X1906102Y1044232D02*
X1899409D01*
G01X1911614Y1043445D02*
X1893898D01*
G01X1893841Y1104626D02*
X1893836Y1104606D01*
G01X1893856Y1104641D02*
X1893841Y1104626D01*
G01X1893876Y1104646D02*
X1893856Y1104641D01*
G01X1893841Y1107776D02*
X1893836Y1107756D01*
G01X1893856Y1107790D02*
X1893841Y1107776D01*
G01X1893876Y1107795D02*
X1893856Y1107790D01*
G01X1893841Y1110925D02*
X1893836Y1110906D01*
G01X1893856Y1110940D02*
X1893841Y1110925D01*
G01X1893876Y1110945D02*
X1893856Y1110940D01*
G01X1893841Y1114075D02*
X1893836Y1114055D01*
G01X1893856Y1114089D02*
X1893841Y1114075D01*
G01X1893876Y1114094D02*
X1893856Y1114089D01*
G01X1893841Y1117224D02*
X1893836Y1117205D01*
G01X1893856Y1117239D02*
X1893841Y1117224D01*
G01X1893876Y1117244D02*
X1893856Y1117239D01*
G01X1893841Y1120374D02*
X1893836Y1120354D01*
G01X1893856Y1120389D02*
X1893841Y1120374D01*
G01X1893876Y1120394D02*
X1893856Y1120389D01*
G01X1893841Y1123524D02*
X1893836Y1123504D01*
G01X1893856Y1123538D02*
X1893841Y1123524D01*
G01X1893876Y1123543D02*
X1893856Y1123538D01*
G01X1894816Y1103484D02*
X1894821Y1103504D01*
G01X1894802Y1103470D02*
X1894816Y1103484D01*
G01X1894782Y1103465D02*
X1894802Y1103470D01*
G01X1894816Y1106634D02*
X1894821Y1106654D01*
G01X1894802Y1106620D02*
X1894816Y1106634D01*
G01X1894782Y1106614D02*
X1894802Y1106620D01*
G01X1894816Y1109783D02*
X1894821Y1109803D01*
G01X1894802Y1109769D02*
X1894816Y1109783D01*
G01X1894782Y1109764D02*
X1894802Y1109769D01*
G01X1894816Y1112933D02*
X1894821Y1112953D01*
G01X1894802Y1112919D02*
X1894816Y1112933D01*
G01X1894782Y1112913D02*
X1894802Y1112919D01*
G01X1894816Y1116083D02*
X1894821Y1116102D01*
G01X1894802Y1116069D02*
X1894816Y1116083D01*
G01X1894782Y1116063D02*
X1894802Y1116069D01*
G01X1894816Y1119232D02*
X1894821Y1119252D01*
G01X1894802Y1119218D02*
X1894816Y1119232D01*
G01X1894782Y1119213D02*
X1894802Y1119218D01*
G01X1894816Y1122382D02*
X1894821Y1122402D01*
G01X1894802Y1122368D02*
X1894816Y1122382D01*
G01X1894782Y1122362D02*
X1894802Y1122368D01*
G01X1894794Y1122364D02*
X1894782Y1122362D01*
G01X1894804Y1122369D02*
X1894794Y1122364D01*
G01Y1119215D02*
X1894782Y1119213D01*
G01X1894804Y1119220D02*
X1894794Y1119215D01*
G01Y1116065D02*
X1894782Y1116063D01*
G01X1894804Y1116070D02*
X1894794Y1116065D01*
G01Y1112915D02*
X1894782Y1112913D01*
G01X1894804Y1112920D02*
X1894794Y1112915D01*
G01Y1109766D02*
X1894782Y1109764D01*
G01X1894804Y1109771D02*
X1894794Y1109766D01*
G01Y1106616D02*
X1894782Y1106614D01*
G01X1894804Y1106621D02*
X1894794Y1106616D01*
G01Y1103467D02*
X1894782Y1103465D01*
G01X1894804Y1103472D02*
X1894794Y1103467D01*
G01X1893877Y1123548D02*
Y1123555D01*
G01Y1123544D02*
Y1123548D01*
G01X1893875Y1123543D02*
X1893877Y1123544D01*
G01Y1120399D02*
Y1120405D01*
G01Y1120395D02*
Y1120399D01*
G01X1893875Y1120394D02*
X1893877Y1120395D01*
G01Y1117249D02*
Y1117256D01*
G01Y1117245D02*
Y1117249D01*
G01X1893875Y1117244D02*
X1893877Y1117245D01*
G01Y1114100D02*
Y1114106D01*
G01Y1114096D02*
Y1114100D01*
G01X1893875Y1114094D02*
X1893877Y1114096D01*
G01Y1110950D02*
Y1110956D01*
G01Y1110946D02*
Y1110950D01*
G01X1893875Y1110945D02*
X1893877Y1110946D01*
G01Y1107800D02*
Y1107807D01*
G01Y1107796D02*
Y1107800D01*
G01X1893875Y1107795D02*
X1893877Y1107796D01*
G01Y1104651D02*
Y1104657D01*
G01Y1104647D02*
Y1104651D01*
G01X1893875Y1104646D02*
X1893877Y1104647D01*
G01X1893839Y1123524D02*
Y1123518D01*
G01X1893841Y1123530D02*
X1893839Y1123524D01*
G01X1893844Y1123536D02*
X1893841Y1123530D01*
G01X1893848Y1123541D02*
X1893844Y1123536D01*
G01X1893852Y1123546D02*
X1893848Y1123541D01*
G01X1893858Y1123550D02*
X1893852Y1123546D01*
G01X1893839Y1120374D02*
Y1120368D01*
G01X1893841Y1120381D02*
X1893839Y1120374D01*
G01X1893844Y1120386D02*
X1893841Y1120381D01*
G01X1893848Y1120392D02*
X1893844Y1120386D01*
G01X1893852Y1120396D02*
X1893848Y1120392D01*
G01X1893858Y1120400D02*
X1893852Y1120396D01*
G01X1893839Y1117225D02*
Y1117219D01*
G01X1893841Y1117231D02*
X1893839Y1117225D01*
G01X1893844Y1117237D02*
X1893841Y1117231D01*
G01X1893848Y1117242D02*
X1893844Y1117237D01*
G01X1893852Y1117246D02*
X1893848Y1117242D01*
G01X1893858Y1117250D02*
X1893852Y1117246D01*
G01X1893839Y1114075D02*
Y1114069D01*
G01X1893841Y1114081D02*
X1893839Y1114075D01*
G01X1893844Y1114087D02*
X1893841Y1114081D01*
G01X1893848Y1114093D02*
X1893844Y1114087D01*
G01X1893852Y1114097D02*
X1893848Y1114093D01*
G01X1893858Y1114101D02*
X1893852Y1114097D01*
G01X1893839Y1110926D02*
Y1110919D01*
G01X1893841Y1110932D02*
X1893839Y1110926D01*
G01X1893844Y1110937D02*
X1893841Y1110932D01*
G01X1893848Y1110943D02*
X1893844Y1110937D01*
G01X1893852Y1110947D02*
X1893848Y1110943D01*
G01X1893858Y1110951D02*
X1893852Y1110947D01*
G01X1893839Y1107776D02*
Y1107770D01*
G01X1893841Y1107782D02*
X1893839Y1107776D01*
G01X1893844Y1107788D02*
X1893841Y1107782D01*
G01X1893848Y1107793D02*
X1893844Y1107788D01*
G01X1893852Y1107798D02*
X1893848Y1107793D01*
G01X1893858Y1107802D02*
X1893852Y1107798D01*
G01X1893839Y1104626D02*
Y1104620D01*
G01X1893841Y1104633D02*
X1893839Y1104626D01*
G01X1893844Y1104638D02*
X1893841Y1104633D01*
G01X1893848Y1104644D02*
X1893844Y1104638D01*
G01X1893852Y1104648D02*
X1893848Y1104644D01*
G01X1893858Y1104652D02*
X1893852Y1104648D01*
G01X1894822Y1119231D02*
X1894823Y1119239D01*
G01X1894820Y1119224D02*
X1894822Y1119231D01*
G01X1894816Y1119218D02*
X1894820Y1119224D01*
G01X1894811Y1119212D02*
X1894816Y1119218D01*
G01X1894805Y1119207D02*
X1894811Y1119212D01*
G01X1894798Y1119204D02*
X1894805Y1119207D01*
G01X1894791Y1119202D02*
X1894798Y1119204D01*
G01X1894783Y1119202D02*
X1894791D01*
G01X1894820Y1122376D02*
X1894823Y1122388D01*
G01X1894814Y1122365D02*
X1894820Y1122376D01*
G01X1894804Y1122356D02*
X1894814Y1122365D01*
G01X1894820Y1116076D02*
X1894823Y1116089D01*
G01X1894814Y1116065D02*
X1894820Y1116076D01*
G01X1894804Y1116057D02*
X1894814Y1116065D01*
G01X1894820Y1112927D02*
X1894823Y1112939D01*
G01X1894814Y1112916D02*
X1894820Y1112927D01*
G01X1894804Y1112907D02*
X1894814Y1112916D01*
G01X1894820Y1109777D02*
X1894823Y1109790D01*
G01X1894814Y1109766D02*
X1894820Y1109777D01*
G01X1894804Y1109758D02*
X1894814Y1109766D01*
G01X1894820Y1106628D02*
X1894823Y1106640D01*
G01X1894814Y1106617D02*
X1894820Y1106628D01*
G01X1894804Y1106608D02*
X1894814Y1106617D01*
G01X1894820Y1103478D02*
X1894823Y1103491D01*
G01X1894814Y1103467D02*
X1894820Y1103478D01*
G01X1894804Y1103459D02*
X1894814Y1103467D01*
G01X1894800Y1103457D02*
X1894804Y1103459D01*
G01X1894797Y1103456D02*
X1894800Y1103457D01*
G01X1894794Y1103455D02*
X1894797Y1103456D01*
G01X1894791Y1103454D02*
X1894794Y1103455D01*
G01X1894787Y1103454D02*
X1894791D01*
G01X1894783D02*
X1894787D01*
G01X1893861Y1104654D02*
X1893858Y1104652D01*
G01X1893864Y1104655D02*
X1893861Y1104654D01*
G01X1893867Y1104656D02*
X1893864Y1104655D01*
G01X1893871Y1104656D02*
X1893867D01*
G01X1893874Y1104657D02*
X1893871Y1104656D01*
G01X1893878Y1104657D02*
X1893874D01*
G01X1894800Y1106607D02*
X1894804Y1106608D01*
G01X1894797Y1106606D02*
X1894800Y1106607D01*
G01X1894794Y1106604D02*
X1894797Y1106606D01*
G01X1894791Y1106604D02*
X1894794D01*
G01X1894787Y1106603D02*
X1894791Y1106604D01*
G01X1894783Y1106603D02*
X1894787D01*
G01X1893861Y1107803D02*
X1893858Y1107802D01*
G01X1893864Y1107804D02*
X1893861Y1107803D01*
G01X1893867Y1107806D02*
X1893864Y1107804D01*
G01X1893871Y1107806D02*
X1893867D01*
G01X1893874Y1107807D02*
X1893871Y1107806D01*
G01X1893878Y1107807D02*
X1893874D01*
G01X1894800Y1109756D02*
X1894804Y1109758D01*
G01X1894797Y1109755D02*
X1894800Y1109756D01*
G01X1894794Y1109754D02*
X1894797Y1109755D01*
G01X1894791Y1109753D02*
X1894794Y1109754D01*
G01X1894787Y1109753D02*
X1894791D01*
G01X1894783D02*
X1894787D01*
G01X1893861Y1110953D02*
X1893858Y1110951D01*
G01X1893864Y1110954D02*
X1893861Y1110953D01*
G01X1893867Y1110955D02*
X1893864Y1110954D01*
G01X1893871Y1110956D02*
X1893867Y1110955D01*
G01X1893874Y1110956D02*
X1893871D01*
G01X1893878D02*
X1893874D01*
G01X1894800Y1112906D02*
X1894804Y1112907D01*
G01X1894797Y1112905D02*
X1894800Y1112906D01*
G01X1894794Y1112904D02*
X1894797Y1112905D01*
G01X1894791Y1112903D02*
X1894794Y1112904D01*
G01X1894787Y1112902D02*
X1894791Y1112903D01*
G01X1894783Y1112902D02*
X1894787D01*
G01X1893861Y1114102D02*
X1893858Y1114101D01*
G01X1893864Y1114104D02*
X1893861Y1114102D01*
G01X1893867Y1114105D02*
X1893864Y1114104D01*
G01X1893871Y1114105D02*
X1893867D01*
G01X1893874Y1114106D02*
X1893871Y1114105D01*
G01X1893878Y1114106D02*
X1893874D01*
G01X1894800Y1116056D02*
X1894804Y1116057D01*
G01X1894797Y1116054D02*
X1894800Y1116056D01*
G01X1894794Y1116053D02*
X1894797Y1116054D01*
G01X1894791Y1116052D02*
X1894794Y1116053D01*
G01X1894787Y1116052D02*
X1894791D01*
G01X1894783D02*
X1894787D01*
G01X1893861Y1117252D02*
X1893858Y1117250D01*
G01X1893864Y1117253D02*
X1893861Y1117252D01*
G01X1893867Y1117254D02*
X1893864Y1117253D01*
G01X1893871Y1117255D02*
X1893867Y1117254D01*
G01X1893874Y1117256D02*
X1893871Y1117255D01*
G01X1893878Y1117256D02*
X1893874D01*
G01X1893861Y1120402D02*
X1893858Y1120400D01*
G01X1893864Y1120403D02*
X1893861Y1120402D01*
G01X1893867Y1120404D02*
X1893864Y1120403D01*
G01X1893871Y1120404D02*
X1893867D01*
G01X1893874Y1120405D02*
X1893871Y1120404D01*
G01X1893878Y1120405D02*
X1893874D01*
G01X1894800Y1122355D02*
X1894804Y1122356D01*
G01X1894797Y1122354D02*
X1894800Y1122355D01*
G01X1894794Y1122352D02*
X1894797Y1122354D01*
G01X1894791Y1122352D02*
X1894794D01*
G01X1894787Y1122351D02*
X1894791Y1122352D01*
G01X1894783Y1122351D02*
X1894787D01*
G01X1893861Y1123551D02*
X1893858Y1123550D01*
G01X1893864Y1123552D02*
X1893861Y1123551D01*
G01X1893867Y1123554D02*
X1893864Y1123552D01*
G01X1893871Y1123554D02*
X1893867D01*
G01X1893874Y1123555D02*
X1893871Y1123554D01*
G01X1893878Y1123555D02*
X1893874D01*
G01X1893838Y1123510D02*
X1893839Y1123518D01*
G01X1893837Y1123506D02*
X1893838Y1123510D01*
G01X1893836Y1123504D02*
X1893837Y1123506D01*
G01X1893838Y1120361D02*
X1893839Y1120368D01*
G01X1893837Y1120356D02*
X1893838Y1120361D01*
G01X1893836Y1120354D02*
X1893837Y1120356D01*
G01X1893838Y1117211D02*
X1893839Y1117219D01*
G01X1893837Y1117206D02*
X1893838Y1117211D01*
G01X1893836Y1117205D02*
X1893837Y1117206D01*
G01X1893838Y1114061D02*
X1893839Y1114069D01*
G01X1893837Y1114057D02*
X1893838Y1114061D01*
G01X1893836Y1114055D02*
X1893837Y1114057D01*
G01X1894813Y1104644D02*
X1894817Y1104639D01*
G01X1894809Y1104648D02*
X1894813Y1104644D01*
G01X1894803Y1104652D02*
X1894809Y1104648D01*
G01X1894797Y1104655D02*
X1894803Y1104652D01*
G01X1894790Y1104657D02*
X1894797Y1104655D01*
G01X1894783Y1104657D02*
X1894790D01*
G01X1894813Y1107794D02*
X1894817Y1107789D01*
G01X1894809Y1107798D02*
X1894813Y1107794D01*
G01X1894803Y1107802D02*
X1894809Y1107798D01*
G01X1894797Y1107804D02*
X1894803Y1107802D01*
G01X1894790Y1107806D02*
X1894797Y1107804D01*
G01X1894783Y1107807D02*
X1894790Y1107806D01*
G01X1894813Y1110943D02*
X1894817Y1110938D01*
G01X1894809Y1110948D02*
X1894813Y1110943D01*
G01X1894803Y1110952D02*
X1894809Y1110948D01*
G01X1894797Y1110954D02*
X1894803Y1110952D01*
G01X1894790Y1110956D02*
X1894797Y1110954D01*
G01X1894783Y1110956D02*
X1894790D01*
G01X1894813Y1114093D02*
X1894817Y1114088D01*
G01X1894809Y1114097D02*
X1894813Y1114093D01*
G01X1894803Y1114101D02*
X1894809Y1114097D01*
G01X1894797Y1114104D02*
X1894803Y1114101D01*
G01X1894790Y1114106D02*
X1894797Y1114104D01*
G01X1894783Y1114106D02*
X1894790D01*
G01X1894813Y1117243D02*
X1894817Y1117237D01*
G01X1894809Y1117247D02*
X1894813Y1117243D01*
G01X1894803Y1117251D02*
X1894809Y1117247D01*
G01X1894797Y1117253D02*
X1894803Y1117251D01*
G01X1894790Y1117255D02*
X1894797Y1117253D01*
G01X1894783Y1117256D02*
X1894790Y1117255D01*
G01X1894813Y1120392D02*
X1894817Y1120387D01*
G01X1894809Y1120396D02*
X1894813Y1120392D01*
G01X1894803Y1120400D02*
X1894809Y1120396D01*
G01X1894797Y1120403D02*
X1894803Y1120400D01*
G01X1894790Y1120405D02*
X1894797Y1120403D01*
G01X1894783Y1120405D02*
X1894790D01*
G01X1894813Y1123542D02*
X1894817Y1123537D01*
G01X1894809Y1123546D02*
X1894813Y1123542D01*
G01X1894803Y1123550D02*
X1894809Y1123546D01*
G01X1894797Y1123552D02*
X1894803Y1123550D01*
G01X1894790Y1123554D02*
X1894797Y1123552D01*
G01X1894783Y1123555D02*
X1894790Y1123554D01*
G01X1893839Y1103483D02*
Y1103491D01*
G01X1893842Y1103476D02*
X1893839Y1103483D01*
G01X1893845Y1103470D02*
X1893842Y1103476D01*
G01X1893850Y1103464D02*
X1893845Y1103470D01*
G01X1893856Y1103459D02*
X1893850Y1103464D01*
G01X1893863Y1103456D02*
X1893856Y1103459D01*
G01X1893870Y1103454D02*
X1893863Y1103456D01*
G01X1893878Y1103454D02*
X1893870D01*
G01X1893839Y1106633D02*
Y1106640D01*
G01X1893842Y1106626D02*
X1893839Y1106633D01*
G01X1893845Y1106620D02*
X1893842Y1106626D01*
G01X1893850Y1106614D02*
X1893845Y1106620D01*
G01X1893856Y1106609D02*
X1893850Y1106614D01*
G01X1893863Y1106606D02*
X1893856Y1106609D01*
G01X1893870Y1106604D02*
X1893863Y1106606D01*
G01X1893878Y1106603D02*
X1893870Y1106604D01*
G01X1893839Y1109782D02*
Y1109790D01*
G01X1893842Y1109776D02*
X1893839Y1109782D01*
G01X1893845Y1109769D02*
X1893842Y1109776D01*
G01X1893850Y1109763D02*
X1893845Y1109769D01*
G01X1893856Y1109759D02*
X1893850Y1109763D01*
G01X1893863Y1109756D02*
X1893856Y1109759D01*
G01X1893870Y1109754D02*
X1893863Y1109756D01*
G01X1893878Y1109753D02*
X1893870Y1109754D01*
G01X1893839Y1112932D02*
Y1112939D01*
G01X1893842Y1112925D02*
X1893839Y1112932D01*
G01X1893845Y1112919D02*
X1893842Y1112925D01*
G01X1893850Y1112913D02*
X1893845Y1112919D01*
G01X1893856Y1112908D02*
X1893850Y1112913D01*
G01X1893863Y1112905D02*
X1893856Y1112908D01*
G01X1893870Y1112903D02*
X1893863Y1112905D01*
G01X1893878Y1112902D02*
X1893870Y1112903D01*
G01X1893839Y1116081D02*
Y1116089D01*
G01X1893842Y1116075D02*
X1893839Y1116081D01*
G01X1893845Y1116069D02*
X1893842Y1116075D01*
G01X1893850Y1116063D02*
X1893845Y1116069D01*
G01X1893856Y1116058D02*
X1893850Y1116063D01*
G01X1893863Y1116055D02*
X1893856Y1116058D01*
G01X1893870Y1116053D02*
X1893863Y1116055D01*
G01X1893878Y1116052D02*
X1893870Y1116053D01*
G01X1893839Y1119231D02*
Y1119239D01*
G01X1893842Y1119224D02*
X1893839Y1119231D01*
G01X1893845Y1119218D02*
X1893842Y1119224D01*
G01X1893850Y1119212D02*
X1893845Y1119218D01*
G01X1893856Y1119207D02*
X1893850Y1119212D01*
G01X1893863Y1119204D02*
X1893856Y1119207D01*
G01X1893870Y1119202D02*
X1893863Y1119204D01*
G01X1893878Y1119202D02*
X1893870D01*
G01X1893839Y1122381D02*
Y1122388D01*
G01X1893842Y1122374D02*
X1893839Y1122381D01*
G01X1893845Y1122368D02*
X1893842Y1122374D01*
G01X1893850Y1122362D02*
X1893845Y1122368D01*
G01X1893856Y1122357D02*
X1893850Y1122362D01*
G01X1893863Y1122354D02*
X1893856Y1122357D01*
G01X1893870Y1122352D02*
X1893863Y1122354D01*
G01X1893878Y1122351D02*
X1893870Y1122352D01*
G01X1894793Y1104644D02*
X1894802Y1104640D01*
G01X1894782Y1104646D02*
X1894793Y1104644D01*
G01Y1107794D02*
X1894802Y1107790D01*
G01X1894782Y1107795D02*
X1894793Y1107794D01*
G01Y1110944D02*
X1894802Y1110939D01*
G01X1894782Y1110945D02*
X1894793Y1110944D01*
G01Y1114093D02*
X1894802Y1114089D01*
G01X1894782Y1114094D02*
X1894793Y1114093D01*
G01Y1117243D02*
X1894802Y1117239D01*
G01X1894782Y1117244D02*
X1894793Y1117243D01*
G01X1908248Y1130308D02*
Y1130299D01*
G01X1908249Y1130313D02*
X1908248Y1130308D01*
G01X1908251Y1130315D02*
X1908249Y1130313D01*
G01X1908248Y1125308D02*
Y1125299D01*
G01X1908249Y1125313D02*
X1908248Y1125308D01*
G01X1908251Y1125315D02*
X1908249Y1125313D01*
G01X1908248Y1100308D02*
Y1100299D01*
G01X1908249Y1100313D02*
X1908248Y1100308D01*
G01X1908251Y1100315D02*
X1908249Y1100313D01*
G01X1908248Y1095308D02*
Y1095299D01*
G01X1908249Y1095313D02*
X1908248Y1095308D01*
G01X1908251Y1095315D02*
X1908249Y1095313D01*
G01X1908248Y1090308D02*
Y1090299D01*
G01X1908249Y1090313D02*
X1908248Y1090308D01*
G01X1908251Y1090315D02*
X1908249Y1090313D01*
G01X1908248Y1085308D02*
Y1085299D01*
G01X1908249Y1085313D02*
X1908248Y1085308D01*
G01X1908251Y1085315D02*
X1908249Y1085313D01*
G01X1893838Y1110912D02*
X1893839Y1110919D01*
G01X1893837Y1110907D02*
X1893838Y1110912D01*
G01X1893836Y1110906D02*
X1893837Y1110907D01*
G01X1893838Y1107762D02*
X1893839Y1107770D01*
G01X1893837Y1107757D02*
X1893838Y1107762D01*
G01X1893836Y1107756D02*
X1893837Y1107757D01*
G01X1893838Y1104613D02*
X1893839Y1104620D01*
G01X1893837Y1104608D02*
X1893838Y1104613D01*
G01X1893836Y1104606D02*
X1893837Y1104608D01*
G01X1894793Y1120393D02*
X1894802Y1120388D01*
G01X1894782Y1120394D02*
X1894793Y1120393D01*
G01Y1123542D02*
X1894802Y1123538D01*
G01X1894782Y1123543D02*
X1894793Y1123542D01*
G01X1894783Y1123548D02*
Y1123555D01*
G01Y1123545D02*
Y1123548D01*
G01X1894782Y1123543D02*
X1894783Y1123545D01*
G01Y1120399D02*
Y1120405D01*
G01Y1120395D02*
Y1120399D01*
G01X1894782Y1120394D02*
X1894783Y1120395D01*
G01Y1117249D02*
Y1117256D01*
G01Y1117246D02*
Y1117249D01*
G01X1894782Y1117244D02*
X1894783Y1117246D01*
G01Y1114100D02*
Y1114106D01*
G01Y1114096D02*
Y1114100D01*
G01X1894782Y1114094D02*
X1894783Y1114096D01*
G01Y1110950D02*
Y1110956D01*
G01Y1110946D02*
Y1110950D01*
G01X1894782Y1110945D02*
X1894783Y1110946D01*
G01Y1107800D02*
Y1107807D01*
G01Y1107797D02*
Y1107800D01*
G01X1894782Y1107795D02*
X1894783Y1107797D01*
G01Y1104651D02*
Y1104657D01*
G01Y1104647D02*
Y1104651D01*
G01X1894782Y1104646D02*
X1894783Y1104647D01*
G01X1893839Y1106644D02*
Y1106640D01*
G01X1893840Y1106638D02*
X1893839Y1106644D01*
G01X1893852Y1106622D02*
X1893840Y1106638D01*
G01X1893877Y1106614D02*
X1893852Y1106622D01*
G01X1893839Y1109794D02*
Y1109790D01*
G01X1893840Y1109787D02*
X1893839Y1109794D01*
G01X1893852Y1109772D02*
X1893840Y1109787D01*
G01X1893876Y1109764D02*
X1893852Y1109772D01*
G01X1893839Y1116093D02*
Y1116089D01*
G01X1893840Y1116087D02*
X1893839Y1116093D01*
G01X1893852Y1116071D02*
X1893840Y1116087D01*
G01X1893876Y1116063D02*
X1893852Y1116071D01*
G01X1893839Y1119243D02*
Y1119239D01*
G01X1893840Y1119236D02*
X1893839Y1119243D01*
G01X1893852Y1119221D02*
X1893840Y1119236D01*
G01X1893876Y1119213D02*
X1893852Y1119221D01*
G01X1893839Y1103494D02*
Y1103491D01*
G01X1893840Y1103488D02*
X1893839Y1103494D01*
G01X1893852Y1103473D02*
X1893840Y1103488D01*
G01X1893876Y1103465D02*
X1893852Y1103473D01*
G01X1893839Y1122392D02*
Y1122388D01*
G01X1893840Y1122386D02*
X1893839Y1122392D01*
G01X1893852Y1122370D02*
X1893840Y1122386D01*
G01X1893876Y1122362D02*
X1893852Y1122370D01*
G01X1908235Y1086685D02*
X1908246Y1086669D01*
G01X1908211Y1086693D02*
X1908235Y1086685D01*
G01Y1091685D02*
X1908246Y1091669D01*
G01X1908211Y1091693D02*
X1908235Y1091685D01*
G01Y1096685D02*
X1908246Y1096669D01*
G01X1908211Y1096693D02*
X1908235Y1096685D01*
G01Y1101685D02*
X1908246Y1101669D01*
G01X1908211Y1101693D02*
X1908235Y1101685D01*
G01Y1126685D02*
X1908246Y1126669D01*
G01X1908211Y1126693D02*
X1908235Y1126685D01*
G01X1894823Y1123510D02*
Y1123517D01*
G01X1894822Y1123506D02*
X1894823Y1123510D01*
G01X1894822Y1123504D02*
Y1123506D01*
G01X1894823Y1120361D02*
Y1120368D01*
G01X1894822Y1120356D02*
X1894823Y1120361D01*
G01X1894822Y1120354D02*
Y1120356D01*
G01X1894823Y1117211D02*
Y1117218D01*
G01X1894822Y1117207D02*
X1894823Y1117211D01*
G01X1894822Y1117205D02*
Y1117207D01*
G01X1894823Y1114061D02*
Y1114069D01*
G01X1894822Y1114057D02*
X1894823Y1114061D01*
G01X1894822Y1114055D02*
Y1114057D01*
G01X1894823Y1110912D02*
Y1110919D01*
G01X1894822Y1110907D02*
X1894823Y1110912D01*
G01X1894822Y1110906D02*
Y1110907D01*
G01X1894823Y1107762D02*
Y1107769D01*
G01X1894822Y1107758D02*
X1894823Y1107762D01*
G01X1894822Y1107756D02*
Y1107758D01*
G01X1894823Y1104613D02*
Y1104620D01*
G01X1894822Y1104608D02*
X1894823Y1104613D01*
G01X1894822Y1104606D02*
Y1104608D01*
G01X1893838Y1112947D02*
X1893839Y1112939D01*
G01X1893837Y1112952D02*
X1893838Y1112947D01*
G01X1893836Y1112949D02*
X1893837Y1112952D01*
G01X1893838Y1106648D02*
X1893839Y1106640D01*
G01X1893837Y1106652D02*
X1893838Y1106648D01*
G01X1893836Y1106650D02*
X1893837Y1106652D01*
G01X1893839Y1112943D02*
Y1112939D01*
G01X1893840Y1112938D02*
X1893839Y1112943D01*
G01X1893850Y1112923D02*
X1893840Y1112938D01*
G01X1893873Y1112914D02*
X1893850Y1112923D01*
G01X1893852Y1123535D02*
X1893876Y1123543D01*
G01X1893840Y1123520D02*
X1893852Y1123535D01*
G01X1893839Y1123514D02*
X1893840Y1123520D01*
G01X1893852Y1120385D02*
X1893876Y1120394D01*
G01X1893840Y1120371D02*
X1893852Y1120385D01*
G01X1893839Y1120364D02*
X1893840Y1120371D01*
G01X1893852Y1117236D02*
X1893876Y1117244D01*
G01X1893840Y1117221D02*
X1893852Y1117236D01*
G01X1893839Y1117215D02*
X1893840Y1117221D01*
G01X1893852Y1114086D02*
X1893876Y1114094D01*
G01X1893840Y1114072D02*
X1893852Y1114086D01*
G01X1893839Y1114065D02*
X1893840Y1114072D01*
G01X1893852Y1110937D02*
X1893876Y1110945D01*
G01X1893840Y1110922D02*
X1893852Y1110937D01*
G01X1893839Y1110915D02*
X1893840Y1110922D01*
G01X1893852Y1107787D02*
X1893876Y1107795D01*
G01X1893840Y1107772D02*
X1893852Y1107787D01*
G01X1893839Y1107766D02*
X1893840Y1107772D01*
G01X1893852Y1104637D02*
X1893876Y1104646D01*
G01X1893840Y1104623D02*
X1893852Y1104637D01*
G01X1893839Y1104616D02*
X1893840Y1104623D01*
G01X1894791Y1110944D02*
X1894782Y1110945D01*
G01X1894800Y1110941D02*
X1894791Y1110944D01*
G01X1894808Y1110935D02*
X1894800Y1110941D01*
G01X1894791Y1104644D02*
X1894782Y1104646D01*
G01X1894800Y1104641D02*
X1894791Y1104644D01*
G01X1894808Y1104636D02*
X1894800Y1104641D01*
G01X1894791Y1107794D02*
X1894782Y1107795D01*
G01X1894800Y1107791D02*
X1894791Y1107794D01*
G01X1894808Y1107786D02*
X1894800Y1107791D01*
G01X1894791Y1114093D02*
X1894782Y1114094D01*
G01X1894800Y1114090D02*
X1894791Y1114093D01*
G01X1894808Y1114085D02*
X1894800Y1114090D01*
G01X1894791Y1117243D02*
X1894782Y1117244D01*
G01X1894800Y1117240D02*
X1894791Y1117243D01*
G01X1894808Y1117235D02*
X1894800Y1117240D01*
G01X1894791Y1120393D02*
X1894782Y1120394D01*
G01X1894800Y1120389D02*
X1894791Y1120393D01*
G01X1894808Y1120384D02*
X1894800Y1120389D01*
G01X1894791Y1123542D02*
X1894782Y1123543D01*
G01X1894800Y1123539D02*
X1894791Y1123542D01*
G01X1894808Y1123534D02*
X1894800Y1123539D01*
G01X1893876Y1122191D02*
X1893874Y1122204D01*
G01X1893879Y1122178D02*
X1893876Y1122191D01*
G01X1893878Y1122165D02*
X1893879Y1122178D01*
G01X1893876Y1119041D02*
X1893874Y1119055D01*
G01X1893879Y1119028D02*
X1893876Y1119041D01*
G01X1893878Y1119016D02*
X1893879Y1119028D01*
G01X1893876Y1115892D02*
X1893874Y1115905D01*
G01X1893879Y1115879D02*
X1893876Y1115892D01*
G01X1893878Y1115866D02*
X1893879Y1115879D01*
G01X1893876Y1112742D02*
X1893874Y1112756D01*
G01X1893879Y1112729D02*
X1893876Y1112742D01*
G01X1893878Y1112717D02*
X1893879Y1112729D01*
G01X1893876Y1109593D02*
X1893874Y1109606D01*
G01X1893879Y1109580D02*
X1893876Y1109593D01*
G01X1893878Y1109567D02*
X1893879Y1109580D01*
G01X1893876Y1106443D02*
X1893874Y1106456D01*
G01X1893879Y1106430D02*
X1893876Y1106443D01*
G01X1893878Y1106417D02*
X1893879Y1106430D01*
G01X1893876Y1103293D02*
X1893874Y1103307D01*
G01X1893879Y1103280D02*
X1893876Y1103293D01*
G01X1893878Y1103268D02*
X1893879Y1103280D01*
G01X1894786Y1123715D02*
X1894787Y1123701D01*
G01X1894783Y1123728D02*
X1894786Y1123715D01*
G01X1894783Y1123740D02*
Y1123728D01*
G01X1894786Y1120565D02*
X1894787Y1120552D01*
G01X1894783Y1120578D02*
X1894786Y1120565D01*
G01X1894783Y1120591D02*
Y1120578D01*
G01X1894786Y1117415D02*
X1894787Y1117402D01*
G01X1894783Y1117428D02*
X1894786Y1117415D01*
G01X1894783Y1117441D02*
Y1117428D01*
G01X1894786Y1114266D02*
X1894787Y1114252D01*
G01X1894783Y1114279D02*
X1894786Y1114266D01*
G01X1894783Y1114291D02*
Y1114279D01*
G01X1894786Y1111116D02*
X1894787Y1111103D01*
G01X1894783Y1111129D02*
X1894786Y1111116D01*
G01X1894783Y1111142D02*
Y1111129D01*
G01X1894786Y1107967D02*
X1894787Y1107953D01*
G01X1894783Y1107980D02*
X1894786Y1107967D01*
G01X1894783Y1107992D02*
Y1107980D01*
G01X1894786Y1104817D02*
X1894787Y1104804D01*
G01X1894783Y1104830D02*
X1894786Y1104817D01*
G01X1894783Y1104843D02*
Y1104830D01*
G01X1893838Y1109797D02*
X1893839Y1109790D01*
G01X1893837Y1109802D02*
X1893838Y1109797D01*
G01X1893837Y1109795D02*
Y1109802D01*
G01X1893838Y1119246D02*
X1893839Y1119239D01*
G01X1893837Y1119251D02*
X1893838Y1119246D01*
G01X1893837Y1119244D02*
Y1119251D01*
G01X1894783Y1122178D02*
Y1122165D01*
G01X1894785Y1122191D02*
X1894783Y1122178D01*
G01X1894787Y1122204D02*
X1894785Y1122191D01*
G01X1894783Y1119028D02*
Y1119016D01*
G01X1894785Y1119041D02*
X1894783Y1119028D01*
G01X1894787Y1119055D02*
X1894785Y1119041D01*
G01X1894783Y1115879D02*
Y1115866D01*
G01X1894785Y1115892D02*
X1894783Y1115879D01*
G01X1894787Y1115905D02*
X1894785Y1115892D01*
G01X1894783Y1112729D02*
Y1112717D01*
G01X1894785Y1112742D02*
X1894783Y1112729D01*
G01X1894787Y1112756D02*
X1894785Y1112742D01*
G01X1894783Y1109580D02*
Y1109567D01*
G01X1894785Y1109593D02*
X1894783Y1109580D01*
G01X1894787Y1109606D02*
X1894785Y1109593D01*
G01X1894783Y1106430D02*
Y1106417D01*
G01X1894785Y1106443D02*
X1894783Y1106430D01*
G01X1894787Y1106456D02*
X1894785Y1106443D01*
G01X1894783Y1103280D02*
Y1103268D01*
G01X1894785Y1103293D02*
X1894783Y1103280D01*
G01X1894787Y1103307D02*
X1894785Y1103293D01*
G01X1893838Y1103498D02*
X1893839Y1103491D01*
G01X1893837Y1103503D02*
X1893838Y1103498D01*
G01X1893837Y1103496D02*
Y1103503D01*
G01X1893878Y1103460D02*
Y1103454D01*
G01X1893877Y1103463D02*
X1893878Y1103460D01*
G01X1893876Y1103465D02*
X1893877Y1103463D01*
G01X1893878Y1106609D02*
Y1106603D01*
G01X1893877Y1106613D02*
X1893878Y1106609D01*
G01X1893876Y1106614D02*
X1893877Y1106613D01*
G01X1893878Y1109759D02*
Y1109753D01*
G01X1893877Y1109763D02*
X1893878Y1109759D01*
G01X1893876Y1109764D02*
X1893877Y1109763D01*
G01X1893878Y1112909D02*
Y1112902D01*
G01X1893877Y1112912D02*
X1893878Y1112909D01*
G01X1893876Y1112913D02*
X1893877Y1112912D01*
G01X1893878Y1116058D02*
Y1116052D01*
G01X1893877Y1116062D02*
X1893878Y1116058D01*
G01X1893876Y1116063D02*
X1893877Y1116062D01*
G01X1893878Y1119208D02*
Y1119202D01*
G01X1893877Y1119211D02*
X1893878Y1119208D01*
G01X1893876Y1119213D02*
X1893877Y1119211D01*
G01X1893878Y1122357D02*
Y1122351D01*
G01X1893877Y1122361D02*
X1893878Y1122357D01*
G01X1893876Y1122362D02*
X1893877Y1122361D01*
G01X1908215Y1086791D02*
X1908219Y1086890D01*
G01X1908209Y1086719D02*
X1908215Y1086791D01*
G01X1908211Y1086693D02*
X1908209Y1086719D01*
G01X1908215Y1091791D02*
X1908219Y1091890D01*
G01X1908209Y1091719D02*
X1908215Y1091791D01*
G01X1908211Y1091693D02*
X1908209Y1091719D01*
G01X1908215Y1096791D02*
X1908219Y1096890D01*
G01X1908209Y1096719D02*
X1908215Y1096791D01*
G01X1908211Y1096693D02*
X1908209Y1096719D01*
G01X1908215Y1101791D02*
X1908219Y1101890D01*
G01X1908209Y1101719D02*
X1908215Y1101791D01*
G01X1908211Y1101693D02*
X1908209Y1101719D01*
G01X1908215Y1126791D02*
X1908219Y1126890D01*
G01X1908209Y1126719D02*
X1908215Y1126791D01*
G01X1908211Y1126693D02*
X1908209Y1126719D01*
G01X1893838Y1116096D02*
X1893839Y1116089D01*
G01X1893837Y1116101D02*
X1893838Y1116096D01*
G01Y1116092D02*
X1893837Y1116101D01*
G01X1893879Y1123728D02*
X1893878Y1123740D01*
G01X1893876Y1123715D02*
X1893879Y1123728D01*
G01X1893876Y1123701D02*
Y1123715D01*
G01X1893879Y1120578D02*
X1893878Y1120591D01*
G01X1893876Y1120565D02*
X1893879Y1120578D01*
G01X1893876Y1120552D02*
Y1120565D01*
G01X1893879Y1117429D02*
X1893878Y1117441D01*
G01X1893876Y1117416D02*
X1893879Y1117429D01*
G01X1893876Y1117402D02*
Y1117416D01*
G01X1893879Y1114279D02*
X1893878Y1114291D01*
G01X1893876Y1114266D02*
X1893879Y1114279D01*
G01X1893876Y1114252D02*
Y1114266D01*
G01X1893879Y1111130D02*
X1893878Y1111142D01*
G01X1893876Y1111117D02*
X1893879Y1111130D01*
G01X1893876Y1111103D02*
Y1111117D01*
G01X1893879Y1107980D02*
X1893878Y1107992D01*
G01X1893876Y1107967D02*
X1893879Y1107980D01*
G01X1893876Y1107953D02*
Y1107967D01*
G01X1893879Y1104830D02*
X1893878Y1104843D01*
G01X1893876Y1104817D02*
X1893879Y1104830D01*
G01X1893876Y1104804D02*
Y1104817D01*
G01X1907265Y1130313D02*
Y1130315D01*
G01X1907264Y1130308D02*
X1907265Y1130313D01*
G01X1907264Y1130299D02*
Y1130308D01*
G01X1907265Y1125313D02*
Y1125315D01*
G01X1907264Y1125308D02*
X1907265Y1125313D01*
G01X1907264Y1125299D02*
Y1125308D01*
G01X1907265Y1100313D02*
Y1100315D01*
G01X1907264Y1100308D02*
X1907265Y1100313D01*
G01X1907264Y1100299D02*
Y1100308D01*
G01X1907265Y1095313D02*
Y1095315D01*
G01X1907264Y1095308D02*
X1907265Y1095313D01*
G01X1907264Y1095299D02*
Y1095308D01*
G01X1907265Y1090313D02*
Y1090315D01*
G01X1907264Y1090308D02*
X1907265Y1090313D01*
G01X1907264Y1090299D02*
Y1090308D01*
G01X1907265Y1085313D02*
Y1085315D01*
G01X1907264Y1085308D02*
X1907265Y1085313D01*
G01X1907264Y1085299D02*
Y1085308D01*
G01X1893838Y1122396D02*
X1893839Y1122388D01*
G01X1893837Y1122400D02*
X1893838Y1122396D01*
G01X1893837Y1122393D02*
Y1122400D01*
G01X1908248Y1086660D02*
Y1086667D01*
G01X1908249Y1086656D02*
X1908248Y1086660D01*
G01X1908250Y1086654D02*
X1908249Y1086656D01*
G01X1908248Y1091660D02*
Y1091667D01*
G01X1908249Y1091656D02*
X1908248Y1091660D01*
G01X1908250Y1091654D02*
X1908249Y1091656D01*
G01X1908248Y1096660D02*
Y1096667D01*
G01X1908249Y1096656D02*
X1908248Y1096660D01*
G01X1908250Y1096654D02*
X1908249Y1096656D01*
G01X1908248Y1101660D02*
Y1101667D01*
G01X1908249Y1101656D02*
X1908248Y1101660D01*
G01X1908250Y1101654D02*
X1908249Y1101656D01*
G01X1908248Y1126660D02*
Y1126667D01*
G01X1908249Y1126656D02*
X1908248Y1126660D01*
G01X1908250Y1126654D02*
X1908249Y1126656D01*
G01X1893861Y1106617D02*
X1893876Y1106614D01*
G01X1893850Y1106624D02*
X1893861Y1106617D01*
G01X1893838Y1106643D02*
X1893850Y1106624D01*
G01X1893861Y1116066D02*
X1893876Y1116063D01*
G01X1893850Y1116073D02*
X1893861Y1116066D01*
G01X1893838Y1116091D02*
X1893850Y1116073D01*
G01X1893861Y1109767D02*
X1893876Y1109764D01*
G01X1893849Y1109774D02*
X1893861Y1109767D01*
G01X1893837Y1109794D02*
X1893849Y1109774D01*
G01X1893861Y1119215D02*
X1893876Y1119213D01*
G01X1893849Y1119223D02*
X1893861Y1119215D01*
G01X1893837Y1119243D02*
X1893849Y1119223D01*
G01X1894823Y1103498D02*
Y1103491D01*
G01X1894822Y1103503D02*
X1894823Y1103498D01*
G01X1894821Y1103504D02*
X1894822Y1103503D01*
G01X1894823Y1106648D02*
Y1106640D01*
G01X1894822Y1106652D02*
X1894823Y1106648D01*
G01X1894821Y1106654D02*
X1894822Y1106652D01*
G01X1894823Y1109797D02*
Y1109790D01*
G01X1894822Y1109802D02*
X1894823Y1109797D01*
G01X1894821Y1109803D02*
X1894822Y1109802D01*
G01X1894823Y1112947D02*
Y1112939D01*
G01X1894822Y1112952D02*
X1894823Y1112947D01*
G01X1894821Y1112953D02*
X1894822Y1112952D01*
G01X1894823Y1116096D02*
Y1116089D01*
G01X1894822Y1116101D02*
X1894823Y1116096D01*
G01X1894821Y1116102D02*
X1894822Y1116101D01*
G01X1894823Y1119246D02*
Y1119239D01*
G01X1894822Y1119251D02*
X1894823Y1119246D01*
G01X1894821Y1119252D02*
X1894822Y1119251D01*
G01X1894823Y1122396D02*
Y1122388D01*
G01X1894822Y1122400D02*
X1894823Y1122396D01*
G01X1894821Y1122402D02*
X1894822Y1122400D01*
G01X1893861Y1122365D02*
X1893876Y1122362D01*
G01X1893848Y1122373D02*
X1893861Y1122365D01*
G01X1893837Y1122393D02*
X1893848Y1122373D01*
G01X1893861Y1103468D02*
X1893876Y1103465D01*
G01X1893848Y1103476D02*
X1893861Y1103468D01*
G01X1893837Y1103496D02*
X1893848Y1103476D01*
G01X1894822Y1104627D02*
X1894823Y1104620D01*
G01X1894820Y1104633D02*
X1894822Y1104627D01*
G01X1894817Y1104639D02*
X1894820Y1104633D01*
G01X1894822Y1107776D02*
X1894823Y1107770D01*
G01X1894820Y1107783D02*
X1894822Y1107776D01*
G01X1894817Y1107789D02*
X1894820Y1107783D01*
G01X1894822Y1110926D02*
X1894823Y1110919D01*
G01X1894820Y1110932D02*
X1894822Y1110926D01*
G01X1894817Y1110938D02*
X1894820Y1110932D01*
G01X1894822Y1114076D02*
X1894823Y1114069D01*
G01X1894820Y1114082D02*
X1894822Y1114076D01*
G01X1894817Y1114088D02*
X1894820Y1114082D01*
G01X1894822Y1117225D02*
X1894823Y1117219D01*
G01X1894820Y1117231D02*
X1894822Y1117225D01*
G01X1894817Y1117237D02*
X1894820Y1117231D01*
G01X1894822Y1120375D02*
X1894823Y1120368D01*
G01X1894820Y1120381D02*
X1894822Y1120375D01*
G01X1894817Y1120387D02*
X1894820Y1120381D01*
G01X1894822Y1123524D02*
X1894823Y1123518D01*
G01X1894820Y1123531D02*
X1894822Y1123524D01*
G01X1894817Y1123537D02*
X1894820Y1123531D01*
G01X1894784Y1103459D02*
Y1103454D01*
G01X1894783Y1103463D02*
X1894784Y1103459D01*
G01X1894782Y1103465D02*
X1894783Y1103463D01*
G01X1894784Y1106609D02*
Y1106603D01*
G01X1894783Y1106613D02*
X1894784Y1106609D01*
G01X1894782Y1106614D02*
X1894783Y1106613D01*
G01X1894784Y1109759D02*
Y1109753D01*
G01X1894783Y1109763D02*
X1894784Y1109759D01*
G01X1894782Y1109764D02*
X1894783Y1109763D01*
G01X1894784Y1112908D02*
Y1112902D01*
G01X1894783Y1112912D02*
X1894784Y1112908D01*
G01X1894782Y1112913D02*
X1894783Y1112912D01*
G01X1894784Y1116058D02*
Y1116052D01*
G01X1894783Y1116062D02*
X1894784Y1116058D01*
G01X1894782Y1116063D02*
X1894783Y1116062D01*
G01X1894784Y1122357D02*
Y1122351D01*
G01X1894783Y1122361D02*
X1894784Y1122357D01*
G01X1894782Y1122362D02*
X1894783Y1122361D01*
G01X1907264Y1086700D02*
Y1086709D01*
G01X1907265Y1086695D02*
X1907264Y1086700D01*
G01X1907265Y1086693D02*
Y1086695D01*
G01X1907264Y1091700D02*
Y1091709D01*
G01X1907265Y1091695D02*
X1907264Y1091700D01*
G01X1907265Y1091693D02*
Y1091695D01*
G01X1907264Y1096700D02*
Y1096709D01*
G01X1907265Y1096695D02*
X1907264Y1096700D01*
G01X1907265Y1096693D02*
Y1096695D01*
G01X1907264Y1101700D02*
Y1101709D01*
G01X1907265Y1101695D02*
X1907264Y1101700D01*
G01X1907265Y1101693D02*
Y1101695D01*
G01X1907264Y1126700D02*
Y1126709D01*
G01X1907265Y1126695D02*
X1907264Y1126700D01*
G01X1907265Y1126693D02*
Y1126695D01*
G01X1908240Y1086837D02*
X1908248Y1086811D01*
G01X1908230Y1086863D02*
X1908240Y1086837D01*
G01X1908219Y1086890D02*
X1908230Y1086863D01*
G01X1908240Y1091837D02*
X1908248Y1091811D01*
G01X1908230Y1091863D02*
X1908240Y1091837D01*
G01X1908219Y1091890D02*
X1908230Y1091863D01*
G01X1908240Y1096837D02*
X1908248Y1096811D01*
G01X1908230Y1096863D02*
X1908240Y1096837D01*
G01X1908219Y1096890D02*
X1908230Y1096863D01*
G01X1908240Y1101837D02*
X1908248Y1101811D01*
G01X1908230Y1101863D02*
X1908240Y1101837D01*
G01X1908219Y1101890D02*
X1908230Y1101863D01*
G01X1893856Y1112919D02*
X1893876Y1112913D01*
G01X1893843Y1112931D02*
X1893856Y1112919D01*
G01X1893836Y1112949D02*
X1893843Y1112931D01*
G01X1908231Y1086688D02*
X1908211Y1086693D01*
G01X1908245Y1086674D02*
X1908231Y1086688D01*
G01X1908250Y1086654D02*
X1908245Y1086674D01*
G01X1908231Y1091688D02*
X1908211Y1091693D01*
G01X1908245Y1091674D02*
X1908231Y1091688D01*
G01X1908250Y1091654D02*
X1908245Y1091674D01*
G01X1908231Y1096688D02*
X1908211Y1096693D01*
G01X1908245Y1096674D02*
X1908231Y1096688D01*
G01X1908250Y1096654D02*
X1908245Y1096674D01*
G01X1908231Y1101688D02*
X1908211Y1101693D01*
G01X1908245Y1101674D02*
X1908231Y1101688D01*
G01X1908250Y1101654D02*
X1908245Y1101674D01*
G01X1908231Y1126688D02*
X1908211Y1126693D01*
G01X1908245Y1126674D02*
X1908231Y1126688D01*
G01X1908250Y1126654D02*
X1908245Y1126674D01*
G01X1894815Y1110927D02*
X1894808Y1110935D01*
G01X1894820Y1110917D02*
X1894815Y1110927D01*
G01X1894822Y1110906D02*
X1894820Y1110917D01*
G01X1894815Y1104628D02*
X1894808Y1104636D01*
G01X1894820Y1104617D02*
X1894815Y1104628D01*
G01X1894822Y1104606D02*
X1894820Y1104617D01*
G01X1894815Y1107777D02*
X1894808Y1107786D01*
G01X1894820Y1107767D02*
X1894815Y1107777D01*
G01X1894822Y1107756D02*
X1894820Y1107767D01*
G01X1894815Y1114076D02*
X1894808Y1114085D01*
G01X1894820Y1114066D02*
X1894815Y1114076D01*
G01X1894822Y1114055D02*
X1894820Y1114066D01*
G01X1894815Y1117226D02*
X1894808Y1117235D01*
G01X1894820Y1117216D02*
X1894815Y1117226D01*
G01X1894822Y1117205D02*
X1894820Y1117216D01*
G01X1894815Y1120376D02*
X1894808Y1120384D01*
G01X1894820Y1120365D02*
X1894815Y1120376D01*
G01X1894822Y1120354D02*
X1894820Y1120365D01*
G01X1894815Y1123525D02*
X1894808Y1123534D01*
G01X1894820Y1123515D02*
X1894815Y1123525D01*
G01X1894822Y1123504D02*
X1894820Y1123515D01*
G01X1908240Y1126837D02*
X1908248Y1126811D01*
G01X1908230Y1126863D02*
X1908240Y1126837D01*
G01X1908219Y1126890D02*
X1908230Y1126863D01*
G01X1894782Y1119213D02*
X1894785Y1119202D01*
G01X1894822Y1104609D02*
X1894823Y1104620D01*
G01X1894822Y1107758D02*
X1894823Y1107769D01*
G01X1894822Y1110908D02*
X1894823Y1110919D01*
G01X1894822Y1114057D02*
X1894823Y1114069D01*
G01X1894822Y1117207D02*
X1894823Y1117218D01*
G01X1894822Y1120357D02*
X1894823Y1120368D01*
G01X1894822Y1123506D02*
X1894823Y1123517D01*
G01X1908248Y1086667D02*
Y1086676D01*
G01Y1091667D02*
Y1091676D01*
G01Y1096667D02*
Y1096676D01*
G01Y1101667D02*
Y1101676D01*
G01Y1126667D02*
Y1126676D01*
G01X1909429Y1086693D02*
Y1085315D01*
G01Y1091693D02*
Y1090315D01*
G01Y1096693D02*
Y1095315D01*
G01Y1101693D02*
Y1100315D01*
G01Y1126693D02*
Y1125315D01*
G01Y1131693D02*
Y1130315D01*
G01X1908858Y1124547D02*
Y1102461D01*
G01X1908248Y1129823D02*
Y1132185D01*
G01Y1124823D02*
Y1127185D01*
G01Y1099823D02*
Y1102185D01*
G01Y1094823D02*
Y1097185D01*
G01Y1089823D02*
Y1092185D01*
G01Y1084823D02*
Y1087185D01*
G01Y1091667D02*
Y1091811D01*
G01Y1086667D02*
Y1086811D01*
G01Y1101667D02*
Y1101811D01*
G01Y1096667D02*
Y1096811D01*
G01Y1126667D02*
Y1126811D01*
G01X1907677Y1123366D02*
Y1103642D01*
G01X1907264Y1087185D02*
Y1084823D01*
G01Y1092185D02*
Y1089823D01*
G01Y1097185D02*
Y1094823D01*
G01Y1102185D02*
Y1099823D01*
G01Y1127185D02*
Y1124823D01*
G01Y1132185D02*
Y1129823D01*
G01X1904921Y1201004D02*
Y1124547D01*
G01X1903740Y1199823D02*
Y1123366D01*
G01X1895276Y1204744D02*
Y1125709D01*
G01X1894823Y1122205D02*
Y1123701D01*
G01Y1119055D02*
Y1120551D01*
G01Y1115906D02*
Y1117402D01*
G01Y1112756D02*
Y1114252D01*
G01Y1109606D02*
Y1111102D01*
G01Y1106457D02*
Y1107953D01*
G01Y1103307D02*
Y1104803D01*
G01X1894783Y1106603D02*
Y1106456D01*
G01Y1103454D02*
Y1103307D01*
G01Y1104804D02*
Y1104657D01*
G01Y1109753D02*
Y1109606D01*
G01Y1111103D02*
Y1110956D01*
G01Y1107953D02*
Y1107807D01*
G01Y1116052D02*
Y1115905D01*
G01Y1112902D02*
Y1112756D01*
G01Y1114252D02*
Y1114106D01*
G01Y1119202D02*
Y1119055D01*
G01Y1120552D02*
Y1120405D01*
G01Y1117402D02*
Y1117256D01*
G01Y1122351D02*
Y1122204D01*
G01Y1123701D02*
Y1123555D01*
G01X1893878Y1122204D02*
Y1122351D01*
G01Y1123555D02*
Y1123702D01*
G01Y1119054D02*
Y1119202D01*
G01Y1120405D02*
Y1120552D01*
G01Y1117256D02*
Y1117402D01*
G01Y1115905D02*
Y1116052D01*
G01Y1112755D02*
Y1112902D01*
G01Y1114106D02*
Y1114253D01*
G01Y1109606D02*
Y1109753D01*
G01Y1110956D02*
Y1111103D01*
G01Y1107807D02*
Y1107954D01*
G01Y1106456D02*
Y1106603D01*
G01Y1103306D02*
Y1103454D01*
G01Y1104657D02*
Y1104804D01*
G01X1893839Y1104803D02*
Y1103307D01*
G01Y1111102D02*
Y1109606D01*
G01Y1107953D02*
Y1106457D01*
G01Y1114252D02*
Y1112756D01*
G01Y1120551D02*
Y1119055D01*
G01Y1117402D02*
Y1115906D01*
G01Y1123701D02*
Y1122205D01*
G01X1892657Y1107795D02*
Y1106614D01*
G01Y1104646D02*
Y1103465D01*
G01Y1110945D02*
Y1109764D01*
G01Y1117244D02*
Y1116063D01*
G01Y1114094D02*
Y1112913D01*
G01Y1120394D02*
Y1119213D01*
G01Y1123543D02*
Y1122362D01*
G01X1892323Y1125709D02*
Y1101299D01*
G01X1891929D02*
Y1125709D01*
G01X1888898Y1122362D02*
Y1123543D01*
G01Y1119213D02*
Y1120394D01*
G01Y1116063D02*
Y1117244D01*
G01Y1112913D02*
Y1114094D01*
G01Y1109764D02*
Y1110945D01*
G01Y1106614D02*
Y1107795D01*
G01Y1103465D02*
Y1104646D01*
G01X1894823Y1122388D02*
X1894822Y1122399D01*
G01X1894823Y1119239D02*
X1894822Y1119250D01*
G01X1894823Y1116089D02*
X1894822Y1116100D01*
G01X1894823Y1112939D02*
X1894822Y1112950D01*
G01X1894823Y1109790D02*
X1894822Y1109801D01*
G01X1894823Y1106640D02*
X1894822Y1106651D01*
G01X1894823Y1103491D02*
X1894822Y1103502D01*
G01X1907677Y1103642D02*
X1908858Y1102461D01*
G01X1903740Y1103642D02*
X1904921Y1102461D01*
G01X1893725Y1122402D02*
X1893837Y1122393D01*
G01X1907677Y1123366D02*
X1908858Y1124547D01*
G01X1903740Y1123366D02*
X1904921Y1124547D01*
G01X1893836Y1112949D02*
X1893725Y1112953D01*
G01X1893836Y1106650D02*
X1893725Y1106654D01*
G01X1893836Y1116099D02*
X1893725Y1116102D01*
G01X1912598Y1130315D02*
X1907265D01*
G01X1907264Y1129823D02*
X1908248D01*
G01Y1127185D02*
X1907264D01*
G01X1907265Y1126693D02*
X1912598D01*
G01Y1126654D02*
X1908250D01*
G01X1895276Y1125709D02*
X1891929D01*
G01X1912598Y1125315D02*
X1907265D01*
G01X1907264Y1124823D02*
X1908248D01*
G01X1904921Y1124547D02*
X1908858D01*
G01X1894783Y1123740D02*
X1893878D01*
G01X1894823Y1123701D02*
X1893839D01*
G01X1894782Y1123543D02*
X1888898D01*
G01Y1123504D02*
X1894822D01*
G01X1903740Y1123366D02*
X1907677D01*
G01X1894821Y1122402D02*
X1888898D01*
G01X1894782Y1122362D02*
X1888898D01*
G01X1893839Y1122205D02*
X1894823D01*
G01X1893878Y1122165D02*
X1894783D01*
G01Y1120591D02*
X1893878D01*
G01X1894823Y1120551D02*
X1893839D01*
G01X1894782Y1120394D02*
X1888898D01*
G01Y1120354D02*
X1894822D01*
G01X1894821Y1119252D02*
X1888898D01*
G01X1894782Y1119213D02*
X1888898D01*
G01X1893839Y1119055D02*
X1894823D01*
G01X1893878Y1119016D02*
X1894783D01*
G01Y1117441D02*
X1893878D01*
G01X1894823Y1117402D02*
X1893839D01*
G01X1894782Y1117244D02*
X1888898D01*
G01Y1117205D02*
X1894822D01*
G01X1893091Y1116102D02*
X1892657D01*
G01X1894821D02*
X1888898D01*
G01X1894782Y1116063D02*
X1888898D01*
G01X1893839Y1115906D02*
X1894823D01*
G01X1893878Y1115866D02*
X1894783D01*
G01Y1114291D02*
X1893878D01*
G01X1894823Y1114252D02*
X1893839D01*
G01X1894782Y1114094D02*
X1888898D01*
G01Y1114055D02*
X1894822D01*
G01X1893091Y1112953D02*
X1892657D01*
G01X1894821D02*
X1888898D01*
G01X1894782Y1112913D02*
X1888898D01*
G01X1893839Y1112756D02*
X1894823D01*
G01X1893878Y1112717D02*
X1894783D01*
G01Y1111142D02*
X1893878D01*
G01X1894823Y1111102D02*
X1893839D01*
G01X1894782Y1110945D02*
X1888898D01*
G01Y1110906D02*
X1894822D01*
G01X1894821Y1109803D02*
X1888898D01*
G01X1894782Y1109764D02*
X1888898D01*
G01X1893839Y1109606D02*
X1894823D01*
G01X1893878Y1109567D02*
X1894783D01*
G01Y1107992D02*
X1893878D01*
G01X1894823Y1107953D02*
X1893839D01*
G01X1894782Y1107795D02*
X1888898D01*
G01Y1107756D02*
X1894822D01*
G01X1893091Y1106654D02*
X1892657D01*
G01X1894821D02*
X1888898D01*
G01X1894782Y1106614D02*
X1888898D01*
G01X1893839Y1106457D02*
X1894823D01*
G01X1893878Y1106417D02*
X1894783D01*
G01Y1104843D02*
X1893878D01*
G01X1894823Y1104803D02*
X1893839D01*
G01X1894782Y1104646D02*
X1888898D01*
G01Y1104606D02*
X1894822D01*
G01X1907677Y1103642D02*
X1903740D01*
G01X1894821Y1103504D02*
X1888898D01*
G01X1894782Y1103465D02*
X1888898D01*
G01X1893839Y1103307D02*
X1894823D01*
G01X1893878Y1103268D02*
X1894783D01*
G01X1908858Y1102461D02*
X1904921D01*
G01X1908248Y1102185D02*
X1907264D01*
G01X1907265Y1101693D02*
X1912598D01*
G01Y1101654D02*
X1908250D01*
G01X1895276Y1101299D02*
X1891929D01*
G01X1912598Y1100315D02*
X1907265D01*
G01X1907264Y1099823D02*
X1908248D01*
G01Y1097185D02*
X1907264D01*
G01X1907265Y1096693D02*
X1912598D01*
G01Y1096654D02*
X1908250D01*
G01X1912598Y1095315D02*
X1907265D01*
G01X1907264Y1094823D02*
X1908248D01*
G01Y1092185D02*
X1907264D01*
G01X1907265Y1091693D02*
X1912598D01*
G01Y1091654D02*
X1908250D01*
G01X1912598Y1090315D02*
X1907265D01*
G01X1907264Y1089823D02*
X1908248D01*
G01Y1087185D02*
X1907264D01*
G01X1907265Y1086693D02*
X1912598D01*
G01Y1086654D02*
X1908250D01*
G01X1912598Y1085315D02*
X1907265D01*
G01X1907264Y1084823D02*
X1908248D01*
G01Y1130119D02*
X1907264Y1130118D01*
G01Y1126889D02*
X1908219Y1126890D01*
G01X1908248Y1125119D02*
X1907264Y1125118D01*
G01Y1101889D02*
X1908219Y1101890D01*
G01X1908248Y1100119D02*
X1907264Y1100118D01*
G01Y1096889D02*
X1908219Y1096890D01*
G01X1908248Y1095119D02*
X1907264Y1095118D01*
G01Y1091889D02*
X1908219Y1091890D01*
G01X1908248Y1090119D02*
X1907264Y1090118D01*
G01Y1086889D02*
X1908219Y1086890D01*
G01X1908248Y1085119D02*
X1907264Y1085118D01*
G01X1908248Y1175308D02*
Y1175299D01*
G01X1908249Y1175313D02*
X1908248Y1175308D01*
G01X1908251Y1175315D02*
X1908249Y1175313D01*
G01X1908248Y1170308D02*
Y1170299D01*
G01X1908249Y1170313D02*
X1908248Y1170308D01*
G01X1908251Y1170315D02*
X1908249Y1170313D01*
G01X1908248Y1165308D02*
Y1165299D01*
G01X1908249Y1165313D02*
X1908248Y1165308D01*
G01X1908251Y1165315D02*
X1908249Y1165313D01*
G01X1908248Y1160308D02*
Y1160299D01*
G01X1908249Y1160313D02*
X1908248Y1160308D01*
G01X1908251Y1160315D02*
X1908249Y1160313D01*
G01X1908248Y1155308D02*
Y1155299D01*
G01X1908249Y1155313D02*
X1908248Y1155308D01*
G01X1908251Y1155315D02*
X1908249Y1155313D01*
G01X1908248Y1150308D02*
Y1150299D01*
G01X1908249Y1150313D02*
X1908248Y1150308D01*
G01X1908251Y1150315D02*
X1908249Y1150313D01*
G01X1908248Y1145308D02*
Y1145299D01*
G01X1908249Y1145313D02*
X1908248Y1145308D01*
G01X1908251Y1145315D02*
X1908249Y1145313D01*
G01X1908248Y1140308D02*
Y1140299D01*
G01X1908249Y1140313D02*
X1908248Y1140308D01*
G01X1908251Y1140315D02*
X1908249Y1140313D01*
G01X1908248Y1135308D02*
Y1135299D01*
G01X1908249Y1135313D02*
X1908248Y1135308D01*
G01X1908251Y1135315D02*
X1908249Y1135313D01*
G01X1908246Y1131669D02*
X1908248Y1131663D01*
G01X1908235Y1131685D02*
X1908246Y1131669D01*
G01X1908211Y1131693D02*
X1908235Y1131685D01*
G01Y1136685D02*
X1908246Y1136669D01*
G01X1908211Y1136693D02*
X1908235Y1136685D01*
G01Y1141685D02*
X1908246Y1141669D01*
G01X1908211Y1141693D02*
X1908235Y1141685D01*
G01Y1146685D02*
X1908246Y1146669D01*
G01X1908211Y1146693D02*
X1908235Y1146685D01*
G01Y1151685D02*
X1908246Y1151669D01*
G01X1908211Y1151693D02*
X1908235Y1151685D01*
G01Y1156685D02*
X1908246Y1156669D01*
G01X1908211Y1156693D02*
X1908235Y1156685D01*
G01Y1161685D02*
X1908246Y1161669D01*
G01X1908211Y1161693D02*
X1908235Y1161685D01*
G01Y1166685D02*
X1908246Y1166669D01*
G01X1908211Y1166693D02*
X1908235Y1166685D01*
G01Y1171685D02*
X1908246Y1171669D01*
G01X1908211Y1171693D02*
X1908235Y1171685D01*
G01Y1176685D02*
X1908246Y1176669D01*
G01X1908211Y1176693D02*
X1908235Y1176685D01*
G01X1908215Y1131791D02*
X1908219Y1131890D01*
G01X1908209Y1131719D02*
X1908215Y1131791D01*
G01X1908211Y1131693D02*
X1908209Y1131719D01*
G01X1908215Y1136791D02*
X1908219Y1136890D01*
G01X1908209Y1136719D02*
X1908215Y1136791D01*
G01X1908211Y1136693D02*
X1908209Y1136719D01*
G01X1908215Y1141791D02*
X1908219Y1141890D01*
G01X1908209Y1141719D02*
X1908215Y1141791D01*
G01X1908211Y1141693D02*
X1908209Y1141719D01*
G01X1908215Y1146791D02*
X1908219Y1146890D01*
G01X1908209Y1146719D02*
X1908215Y1146791D01*
G01X1908211Y1146693D02*
X1908209Y1146719D01*
G01X1908215Y1151791D02*
X1908219Y1151890D01*
G01X1908209Y1151719D02*
X1908215Y1151791D01*
G01X1908211Y1151693D02*
X1908209Y1151719D01*
G01X1908215Y1156791D02*
X1908219Y1156890D01*
G01X1908209Y1156719D02*
X1908215Y1156791D01*
G01X1908211Y1156693D02*
X1908209Y1156719D01*
G01X1908215Y1161791D02*
X1908219Y1161890D01*
G01X1908209Y1161719D02*
X1908215Y1161791D01*
G01X1908211Y1161693D02*
X1908209Y1161719D01*
G01X1908215Y1166791D02*
X1908219Y1166890D01*
G01X1908209Y1166719D02*
X1908215Y1166791D01*
G01X1908211Y1166693D02*
X1908209Y1166719D01*
G01X1908215Y1171791D02*
X1908219Y1171890D01*
G01X1908209Y1171719D02*
X1908215Y1171791D01*
G01X1908211Y1171693D02*
X1908209Y1171719D01*
G01X1908215Y1176791D02*
X1908219Y1176890D01*
G01X1908209Y1176719D02*
X1908215Y1176791D01*
G01X1908211Y1176693D02*
X1908209Y1176719D01*
G01X1907265Y1175313D02*
Y1175315D01*
G01X1907264Y1175308D02*
X1907265Y1175313D01*
G01X1907264Y1175299D02*
Y1175308D01*
G01X1907265Y1170313D02*
Y1170315D01*
G01X1907264Y1170308D02*
X1907265Y1170313D01*
G01X1907264Y1170299D02*
Y1170308D01*
G01X1907265Y1165313D02*
Y1165315D01*
G01X1907264Y1165308D02*
X1907265Y1165313D01*
G01X1907264Y1165299D02*
Y1165308D01*
G01X1907265Y1160313D02*
Y1160315D01*
G01X1907264Y1160308D02*
X1907265Y1160313D01*
G01X1907264Y1160299D02*
Y1160308D01*
G01X1907265Y1155313D02*
Y1155315D01*
G01X1907264Y1155308D02*
X1907265Y1155313D01*
G01X1907264Y1155299D02*
Y1155308D01*
G01X1907265Y1150313D02*
Y1150315D01*
G01X1907264Y1150308D02*
X1907265Y1150313D01*
G01X1907264Y1150299D02*
Y1150308D01*
G01X1907265Y1145313D02*
Y1145315D01*
G01X1907264Y1145308D02*
X1907265Y1145313D01*
G01X1907264Y1145299D02*
Y1145308D01*
G01X1907265Y1140313D02*
Y1140315D01*
G01X1907264Y1140308D02*
X1907265Y1140313D01*
G01X1907264Y1140299D02*
Y1140308D01*
G01X1907265Y1135313D02*
Y1135315D01*
G01X1907264Y1135308D02*
X1907265Y1135313D01*
G01X1907264Y1135299D02*
Y1135308D01*
G01X1908248Y1131660D02*
Y1131667D01*
G01X1908249Y1131656D02*
X1908248Y1131660D01*
G01X1908250Y1131654D02*
X1908249Y1131656D01*
G01X1908248Y1136660D02*
Y1136667D01*
G01X1908249Y1136656D02*
X1908248Y1136660D01*
G01X1908250Y1136654D02*
X1908249Y1136656D01*
G01X1908248Y1141660D02*
Y1141667D01*
G01X1908249Y1141656D02*
X1908248Y1141660D01*
G01X1908250Y1141654D02*
X1908249Y1141656D01*
G01X1908248Y1146660D02*
Y1146667D01*
G01X1908249Y1146656D02*
X1908248Y1146660D01*
G01X1908250Y1146654D02*
X1908249Y1146656D01*
G01X1908248Y1151660D02*
Y1151667D01*
G01X1908249Y1151656D02*
X1908248Y1151660D01*
G01X1908250Y1151654D02*
X1908249Y1151656D01*
G01X1908248Y1156660D02*
Y1156667D01*
G01X1908249Y1156656D02*
X1908248Y1156660D01*
G01X1908250Y1156654D02*
X1908249Y1156656D01*
G01X1908248Y1161660D02*
Y1161667D01*
G01X1908249Y1161656D02*
X1908248Y1161660D01*
G01X1908250Y1161654D02*
X1908249Y1161656D01*
G01X1908248Y1166660D02*
Y1166667D01*
G01X1908249Y1166656D02*
X1908248Y1166660D01*
G01X1908250Y1166654D02*
X1908249Y1166656D01*
G01X1908248Y1171660D02*
Y1171667D01*
G01X1908249Y1171656D02*
X1908248Y1171660D01*
G01X1908250Y1171654D02*
X1908249Y1171656D01*
G01X1908248Y1176660D02*
Y1176667D01*
G01X1908249Y1176656D02*
X1908248Y1176660D01*
G01X1908250Y1176654D02*
X1908249Y1176656D01*
G01X1908231Y1131688D02*
X1908211Y1131693D01*
G01X1908245Y1131674D02*
X1908231Y1131688D01*
G01X1908250Y1131654D02*
X1908245Y1131674D01*
G01X1907264Y1131700D02*
Y1131709D01*
G01X1907265Y1131695D02*
X1907264Y1131700D01*
G01X1907265Y1131693D02*
Y1131695D01*
G01X1907264Y1136700D02*
Y1136709D01*
G01X1907265Y1136695D02*
X1907264Y1136700D01*
G01X1907265Y1136693D02*
Y1136695D01*
G01X1907264Y1141700D02*
Y1141709D01*
G01X1907265Y1141695D02*
X1907264Y1141700D01*
G01X1907265Y1141693D02*
Y1141695D01*
G01X1907264Y1146700D02*
Y1146709D01*
G01X1907265Y1146695D02*
X1907264Y1146700D01*
G01X1907265Y1146693D02*
Y1146695D01*
G01X1907264Y1151700D02*
Y1151709D01*
G01X1907265Y1151695D02*
X1907264Y1151700D01*
G01X1907265Y1151693D02*
Y1151695D01*
G01X1907264Y1156700D02*
Y1156709D01*
G01X1907265Y1156695D02*
X1907264Y1156700D01*
G01X1907265Y1156693D02*
Y1156695D01*
G01X1907264Y1161700D02*
Y1161709D01*
G01X1907265Y1161695D02*
X1907264Y1161700D01*
G01X1907265Y1161693D02*
Y1161695D01*
G01X1907264Y1166700D02*
Y1166709D01*
G01X1907265Y1166695D02*
X1907264Y1166700D01*
G01X1907265Y1166693D02*
Y1166695D01*
G01X1907264Y1171700D02*
Y1171709D01*
G01X1907265Y1171695D02*
X1907264Y1171700D01*
G01X1907265Y1171693D02*
Y1171695D01*
G01X1907264Y1176700D02*
Y1176709D01*
G01X1907265Y1176695D02*
X1907264Y1176700D01*
G01X1907265Y1176693D02*
Y1176695D01*
G01X1908240Y1131837D02*
X1908248Y1131811D01*
G01X1908230Y1131863D02*
X1908240Y1131837D01*
G01X1908219Y1131890D02*
X1908230Y1131863D01*
G01X1908240Y1136837D02*
X1908248Y1136811D01*
G01X1908230Y1136863D02*
X1908240Y1136837D01*
G01X1908219Y1136890D02*
X1908230Y1136863D01*
G01X1908240Y1141837D02*
X1908248Y1141811D01*
G01X1908230Y1141863D02*
X1908240Y1141837D01*
G01X1908219Y1141890D02*
X1908230Y1141863D01*
G01X1908240Y1146837D02*
X1908248Y1146811D01*
G01X1908230Y1146863D02*
X1908240Y1146837D01*
G01X1908219Y1146890D02*
X1908230Y1146863D01*
G01X1908240Y1151837D02*
X1908248Y1151811D01*
G01X1908230Y1151863D02*
X1908240Y1151837D01*
G01X1908219Y1151890D02*
X1908230Y1151863D01*
G01X1908240Y1156837D02*
X1908248Y1156811D01*
G01X1908230Y1156863D02*
X1908240Y1156837D01*
G01X1908219Y1156890D02*
X1908230Y1156863D01*
G01X1908240Y1161837D02*
X1908248Y1161811D01*
G01X1908230Y1161863D02*
X1908240Y1161837D01*
G01X1908219Y1161890D02*
X1908230Y1161863D01*
G01X1908240Y1166837D02*
X1908248Y1166811D01*
G01X1908230Y1166863D02*
X1908240Y1166837D01*
G01X1908219Y1166890D02*
X1908230Y1166863D01*
G01X1908240Y1171837D02*
X1908248Y1171811D01*
G01X1908230Y1171863D02*
X1908240Y1171837D01*
G01X1908219Y1171890D02*
X1908230Y1171863D01*
G01X1908240Y1176837D02*
X1908248Y1176811D01*
G01X1908230Y1176863D02*
X1908240Y1176837D01*
G01X1908219Y1176890D02*
X1908230Y1176863D01*
G01X1908231Y1136688D02*
X1908211Y1136693D01*
G01X1908245Y1136674D02*
X1908231Y1136688D01*
G01X1908250Y1136654D02*
X1908245Y1136674D01*
G01X1908231Y1141688D02*
X1908211Y1141693D01*
G01X1908245Y1141674D02*
X1908231Y1141688D01*
G01X1908250Y1141654D02*
X1908245Y1141674D01*
G01X1908231Y1146688D02*
X1908211Y1146693D01*
G01X1908245Y1146674D02*
X1908231Y1146688D01*
G01X1908250Y1146654D02*
X1908245Y1146674D01*
G01X1908231Y1151688D02*
X1908211Y1151693D01*
G01X1908245Y1151674D02*
X1908231Y1151688D01*
G01X1908250Y1151654D02*
X1908245Y1151674D01*
G01X1908231Y1156688D02*
X1908211Y1156693D01*
G01X1908245Y1156674D02*
X1908231Y1156688D01*
G01X1908250Y1156654D02*
X1908245Y1156674D01*
G01X1908231Y1161688D02*
X1908211Y1161693D01*
G01X1908245Y1161674D02*
X1908231Y1161688D01*
G01X1908250Y1161654D02*
X1908245Y1161674D01*
G01X1908231Y1166688D02*
X1908211Y1166693D01*
G01X1908245Y1166674D02*
X1908231Y1166688D01*
G01X1908250Y1166654D02*
X1908245Y1166674D01*
G01X1908231Y1171688D02*
X1908211Y1171693D01*
G01X1908245Y1171674D02*
X1908231Y1171688D01*
G01X1908250Y1171654D02*
X1908245Y1171674D01*
G01X1908231Y1176688D02*
X1908211Y1176693D01*
G01X1908245Y1176674D02*
X1908231Y1176688D01*
G01X1908250Y1176654D02*
X1908245Y1176674D01*
G01X1908248Y1131667D02*
Y1131676D01*
G01Y1136667D02*
Y1136676D01*
G01Y1141667D02*
Y1141676D01*
G01Y1146667D02*
Y1146676D01*
G01Y1151667D02*
Y1151676D01*
G01Y1156667D02*
Y1156676D01*
G01Y1161667D02*
Y1161676D01*
G01Y1166667D02*
Y1166676D01*
G01Y1171667D02*
Y1171676D01*
G01Y1176667D02*
Y1176676D01*
G01X1909429Y1136693D02*
Y1135315D01*
G01Y1141693D02*
Y1140315D01*
G01Y1146693D02*
Y1145315D01*
G01Y1151693D02*
Y1150315D01*
G01Y1156693D02*
Y1155315D01*
G01Y1161693D02*
Y1160315D01*
G01Y1166693D02*
Y1165315D01*
G01Y1171693D02*
Y1170315D01*
G01Y1176693D02*
Y1175315D01*
G01X1908248Y1174823D02*
Y1177185D01*
G01Y1169823D02*
Y1172185D01*
G01Y1164823D02*
Y1167185D01*
G01Y1159823D02*
Y1162185D01*
G01Y1154823D02*
Y1157185D01*
G01Y1149823D02*
Y1152185D01*
G01Y1144823D02*
Y1147185D01*
G01Y1139823D02*
Y1142185D01*
G01Y1134823D02*
Y1137185D01*
G01Y1131667D02*
Y1131811D01*
G01Y1141667D02*
Y1141811D01*
G01Y1136667D02*
Y1136811D01*
G01Y1151667D02*
Y1151811D01*
G01Y1146667D02*
Y1146811D01*
G01Y1161667D02*
Y1161811D01*
G01Y1156667D02*
Y1156811D01*
G01Y1171667D02*
Y1171811D01*
G01Y1166667D02*
Y1166811D01*
G01Y1176667D02*
Y1176811D01*
G01X1907264Y1137185D02*
Y1134823D01*
G01Y1142185D02*
Y1139823D01*
G01Y1147185D02*
Y1144823D01*
G01Y1152185D02*
Y1149823D01*
G01Y1157185D02*
Y1154823D01*
G01Y1162185D02*
Y1159823D01*
G01Y1167185D02*
Y1164823D01*
G01Y1172185D02*
Y1169823D01*
G01Y1177185D02*
Y1174823D01*
G01X1908248Y1177185D02*
X1907264D01*
G01X1907265Y1176693D02*
X1912598D01*
G01Y1176654D02*
X1908250D01*
G01X1912598Y1175315D02*
X1907265D01*
G01X1907264Y1174823D02*
X1908248D01*
G01Y1172185D02*
X1907264D01*
G01X1907265Y1171693D02*
X1912598D01*
G01Y1171654D02*
X1908250D01*
G01X1912598Y1170315D02*
X1907265D01*
G01X1907264Y1169823D02*
X1908248D01*
G01Y1167185D02*
X1907264D01*
G01X1907265Y1166693D02*
X1912598D01*
G01Y1166654D02*
X1908250D01*
G01X1912598Y1165315D02*
X1907265D01*
G01X1907264Y1164823D02*
X1908248D01*
G01Y1162185D02*
X1907264D01*
G01X1907265Y1161693D02*
X1912598D01*
G01Y1161654D02*
X1908250D01*
G01X1912598Y1160315D02*
X1907265D01*
G01X1907264Y1159823D02*
X1908248D01*
G01Y1157185D02*
X1907264D01*
G01X1907265Y1156693D02*
X1912598D01*
G01Y1156654D02*
X1908250D01*
G01X1912598Y1155315D02*
X1907265D01*
G01X1907264Y1154823D02*
X1908248D01*
G01X1907264Y1176889D02*
X1908219Y1176890D01*
G01X1908248Y1175119D02*
X1907264Y1175118D01*
G01Y1171889D02*
X1908219Y1171890D01*
G01X1908248Y1170119D02*
X1907264Y1170118D01*
G01Y1166889D02*
X1908219Y1166890D01*
G01X1908248Y1165119D02*
X1907264Y1165118D01*
G01Y1161889D02*
X1908219Y1161890D01*
G01X1908248Y1160119D02*
X1907264Y1160118D01*
G01Y1156889D02*
X1908219Y1156890D01*
G01X1908248Y1155119D02*
X1907264Y1155118D01*
G01X1908248Y1152185D02*
X1907264D01*
G01X1907265Y1151693D02*
X1912598D01*
G01Y1151654D02*
X1908250D01*
G01X1912598Y1150315D02*
X1907265D01*
G01X1907264Y1149823D02*
X1908248D01*
G01Y1147185D02*
X1907264D01*
G01X1907265Y1146693D02*
X1912598D01*
G01Y1146654D02*
X1908250D01*
G01X1912598Y1145315D02*
X1907265D01*
G01X1907264Y1144823D02*
X1908248D01*
G01Y1142185D02*
X1907264D01*
G01X1907265Y1141693D02*
X1912598D01*
G01Y1141654D02*
X1908250D01*
G01X1912598Y1140315D02*
X1907265D01*
G01X1907264Y1139823D02*
X1908248D01*
G01Y1137185D02*
X1907264D01*
G01X1907265Y1136693D02*
X1912598D01*
G01Y1136654D02*
X1908250D01*
G01X1912598Y1135315D02*
X1907265D01*
G01X1907264Y1134823D02*
X1908248D01*
G01Y1132185D02*
X1907264D01*
G01X1907265Y1131693D02*
X1912598D01*
G01Y1131654D02*
X1908250D01*
G01X1907264Y1151889D02*
X1908219Y1151890D01*
G01X1908248Y1150119D02*
X1907264Y1150118D01*
G01Y1146889D02*
X1908219Y1146890D01*
G01X1908248Y1145119D02*
X1907264Y1145118D01*
G01Y1141889D02*
X1908219Y1141890D01*
G01X1908248Y1140119D02*
X1907264Y1140118D01*
G01Y1136889D02*
X1908219Y1136890D01*
G01X1908248Y1135119D02*
X1907264Y1135118D01*
G01Y1131889D02*
X1908219Y1131890D01*
G01X1908248Y1195308D02*
Y1195299D01*
G01X1908249Y1195313D02*
X1908248Y1195308D01*
G01X1908251Y1195315D02*
X1908249Y1195313D01*
G01X1908248Y1190308D02*
Y1190299D01*
G01X1908249Y1190313D02*
X1908248Y1190308D01*
G01X1908251Y1190315D02*
X1908249Y1190313D01*
G01X1908248Y1185308D02*
Y1185299D01*
G01X1908249Y1185313D02*
X1908248Y1185308D01*
G01X1908251Y1185315D02*
X1908249Y1185313D01*
G01X1908248Y1180308D02*
Y1180299D01*
G01X1908249Y1180313D02*
X1908248Y1180308D01*
G01X1908251Y1180315D02*
X1908249Y1180313D01*
G01X1908235Y1181685D02*
X1908246Y1181669D01*
G01X1908211Y1181693D02*
X1908235Y1181685D01*
G01Y1186685D02*
X1908246Y1186669D01*
G01X1908211Y1186693D02*
X1908235Y1186685D01*
G01Y1191685D02*
X1908246Y1191669D01*
G01X1908211Y1191693D02*
X1908235Y1191685D01*
G01Y1196685D02*
X1908246Y1196669D01*
G01X1908211Y1196693D02*
X1908235Y1196685D01*
G01X1908215Y1181791D02*
X1908219Y1181890D01*
G01X1908209Y1181719D02*
X1908215Y1181791D01*
G01X1908211Y1181693D02*
X1908209Y1181719D01*
G01X1908215Y1186791D02*
X1908219Y1186890D01*
G01X1908209Y1186719D02*
X1908215Y1186791D01*
G01X1908211Y1186693D02*
X1908209Y1186719D01*
G01X1908215Y1191791D02*
X1908219Y1191890D01*
G01X1908209Y1191719D02*
X1908215Y1191791D01*
G01X1908211Y1191693D02*
X1908209Y1191719D01*
G01X1908215Y1196791D02*
X1908219Y1196890D01*
G01X1908209Y1196719D02*
X1908215Y1196791D01*
G01X1908211Y1196693D02*
X1908209Y1196719D01*
G01X1907265Y1195313D02*
Y1195315D01*
G01X1907264Y1195308D02*
X1907265Y1195313D01*
G01X1907264Y1195299D02*
Y1195308D01*
G01X1907265Y1190313D02*
Y1190315D01*
G01X1907264Y1190308D02*
X1907265Y1190313D01*
G01X1907264Y1190299D02*
Y1190308D01*
G01X1907265Y1185313D02*
Y1185315D01*
G01X1907264Y1185308D02*
X1907265Y1185313D01*
G01X1907264Y1185299D02*
Y1185308D01*
G01X1907265Y1180313D02*
Y1180315D01*
G01X1907264Y1180308D02*
X1907265Y1180313D01*
G01X1907264Y1180299D02*
Y1180308D01*
G01X1908248Y1181660D02*
Y1181667D01*
G01X1908249Y1181656D02*
X1908248Y1181660D01*
G01X1908250Y1181654D02*
X1908249Y1181656D01*
G01X1908248Y1186660D02*
Y1186667D01*
G01X1908249Y1186656D02*
X1908248Y1186660D01*
G01X1908250Y1186654D02*
X1908249Y1186656D01*
G01X1908248Y1191660D02*
Y1191667D01*
G01X1908249Y1191656D02*
X1908248Y1191660D01*
G01X1908250Y1191654D02*
X1908249Y1191656D01*
G01X1908248Y1196660D02*
Y1196667D01*
G01X1908249Y1196656D02*
X1908248Y1196660D01*
G01X1908250Y1196654D02*
X1908249Y1196656D01*
G01X1907264Y1181700D02*
Y1181709D01*
G01X1907265Y1181695D02*
X1907264Y1181700D01*
G01X1907265Y1181693D02*
Y1181695D01*
G01X1907264Y1186700D02*
Y1186709D01*
G01X1907265Y1186695D02*
X1907264Y1186700D01*
G01X1907265Y1186693D02*
Y1186695D01*
G01X1907264Y1191700D02*
Y1191709D01*
G01X1907265Y1191695D02*
X1907264Y1191700D01*
G01X1907265Y1191693D02*
Y1191695D01*
G01X1907264Y1196700D02*
Y1196709D01*
G01X1907265Y1196695D02*
X1907264Y1196700D01*
G01X1907265Y1196693D02*
Y1196695D01*
G01X1908240Y1181837D02*
X1908248Y1181811D01*
G01X1908230Y1181863D02*
X1908240Y1181837D01*
G01X1908219Y1181890D02*
X1908230Y1181863D01*
G01X1908240Y1186837D02*
X1908248Y1186811D01*
G01X1908230Y1186863D02*
X1908240Y1186837D01*
G01X1908219Y1186890D02*
X1908230Y1186863D01*
G01X1908240Y1191837D02*
X1908248Y1191811D01*
G01X1908230Y1191863D02*
X1908240Y1191837D01*
G01X1908219Y1191890D02*
X1908230Y1191863D01*
G01X1908240Y1196837D02*
X1908248Y1196811D01*
G01X1908230Y1196863D02*
X1908240Y1196837D01*
G01X1908219Y1196890D02*
X1908230Y1196863D01*
G01X1908231Y1181688D02*
X1908211Y1181693D01*
G01X1908245Y1181674D02*
X1908231Y1181688D01*
G01X1908250Y1181654D02*
X1908245Y1181674D01*
G01X1908231Y1186688D02*
X1908211Y1186693D01*
G01X1908245Y1186674D02*
X1908231Y1186688D01*
G01X1908250Y1186654D02*
X1908245Y1186674D01*
G01X1908231Y1191688D02*
X1908211Y1191693D01*
G01X1908245Y1191674D02*
X1908231Y1191688D01*
G01X1908250Y1191654D02*
X1908245Y1191674D01*
G01X1908231Y1196688D02*
X1908211Y1196693D01*
G01X1908245Y1196674D02*
X1908231Y1196688D01*
G01X1908250Y1196654D02*
X1908245Y1196674D01*
G01X1906693Y1222185D02*
G03X1906102Y1222776I-591J0D01*
G01X1899409D02*
G03X1898819Y1222185I1J-591D01*
G01X1901575Y1221004D02*
G03Y1219035I0J-985D01*
G01X1903937D02*
G03Y1221004I0J985D01*
G01X1893898Y1223563D02*
G03X1891929Y1221594I0J-1969D01*
G01X1900197Y1213091D02*
G03X1899016Y1211909I0J-1181D01*
G01X1906496D02*
G03X1905315Y1213091I-1181J1D01*
G01X1904646Y1207815D02*
G03I-1890J0D01*
G01X1905118D02*
G03I-2362J0D01*
G01X1901575Y1208406D02*
X1899265Y1212635D01*
G01X1903937Y1206713D02*
X1905241Y1204744D01*
G01X1897047Y1201004D02*
X1898228Y1199823D01*
G01X1891929Y1205846D02*
X1895276Y1202500D01*
G01X1908248Y1181667D02*
Y1181676D01*
G01Y1186667D02*
Y1186676D01*
G01Y1191667D02*
Y1191676D01*
G01Y1196667D02*
Y1196676D01*
G01X1909429Y1181693D02*
Y1180315D01*
G01Y1186693D02*
Y1185315D01*
G01Y1191693D02*
Y1190315D01*
G01Y1196693D02*
Y1195315D01*
G01X1908248Y1194823D02*
Y1197185D01*
G01Y1189823D02*
Y1192185D01*
G01Y1184823D02*
Y1187185D01*
G01Y1179823D02*
Y1182185D01*
G01Y1181667D02*
Y1181811D01*
G01Y1191667D02*
Y1191811D01*
G01Y1186667D02*
Y1186811D01*
G01Y1196667D02*
Y1196811D01*
G01X1907264Y1182185D02*
Y1179823D01*
G01Y1187185D02*
Y1184823D01*
G01Y1192185D02*
Y1189823D01*
G01Y1197185D02*
Y1194823D01*
G01X1906693Y1216083D02*
Y1222185D01*
G01X1906496Y1211909D02*
Y1203366D01*
G01X1903937Y1208406D02*
Y1206713D01*
G01X1901575D02*
Y1208406D01*
G01X1899016Y1203366D02*
Y1211909D01*
G01X1898819Y1216083D02*
Y1222185D01*
G01X1891929Y1221594D02*
Y1205846D01*
G01X1906247Y1212635D02*
X1903937Y1208406D01*
G01X1900271Y1204744D02*
X1901575Y1206713D01*
G01X1911614Y1223563D02*
X1893898D01*
G01X1906102Y1222776D02*
X1899409D01*
G01X1903937Y1221004D02*
X1901575D01*
G01Y1219035D02*
X1903937D01*
G01X1906693Y1217657D02*
X1898819D01*
G01Y1216083D02*
X1906693D01*
G01X1913583Y1213130D02*
X1891929D01*
G01X1900197Y1213091D02*
X1905315D01*
G01X1901575Y1208406D02*
X1903937D01*
G01X1901575Y1206713D02*
X1903937D01*
G01X1895276Y1204744D02*
X1909646D01*
G01X1895276Y1203366D02*
X1899016D01*
G01X1909646D02*
X1906496D01*
G01X1895276Y1202500D02*
X1910236D01*
G01X1897047Y1201004D02*
X1904921D01*
G01X1898228Y1199823D02*
X1903740D01*
G01X1908248Y1197185D02*
X1907264D01*
G01X1907265Y1196693D02*
X1912598D01*
G01Y1196654D02*
X1908250D01*
G01X1912598Y1195315D02*
X1907265D01*
G01X1907264Y1194823D02*
X1908248D01*
G01Y1192185D02*
X1907264D01*
G01X1907265Y1191693D02*
X1912598D01*
G01Y1191654D02*
X1908250D01*
G01X1912598Y1190315D02*
X1907265D01*
G01X1907264Y1189823D02*
X1908248D01*
G01Y1187185D02*
X1907264D01*
G01X1907265Y1186693D02*
X1912598D01*
G01Y1186654D02*
X1908250D01*
G01X1912598Y1185315D02*
X1907265D01*
G01X1907264Y1184823D02*
X1908248D01*
G01Y1182185D02*
X1907264D01*
G01X1907265Y1181693D02*
X1912598D01*
G01Y1181654D02*
X1908250D01*
G01X1912598Y1180315D02*
X1907265D01*
G01X1907264Y1179823D02*
X1908248D01*
G01X1907264Y1196889D02*
X1908219Y1196890D01*
G01X1908248Y1195119D02*
X1907264Y1195118D01*
G01Y1191889D02*
X1908219Y1191890D01*
G01X1908248Y1190119D02*
X1907264Y1190118D01*
G01Y1186889D02*
X1908219Y1186890D01*
G01X1908248Y1185119D02*
X1907264Y1185118D01*
G01Y1181889D02*
X1908219Y1181890D01*
G01X1908248Y1180119D02*
X1907264Y1180118D01*
G01X1903740Y1199823D02*
X1904921Y1201004D01*
G01X1863976Y1274016D02*
G03X1862795I-590J0D01*
G01X1863976D02*
G03X1862795I-590J0D01*
G01X1864764D02*
Y1280315D01*
G01Y1274016D02*
Y1280315D01*
G01X1863976Y1274016D02*
X1864764D01*
G01X1863976D02*
X1864764D01*
G01X1862795Y1280315D02*
G03X1863976I590J0D01*
G01X1862795D02*
G03X1863976I590J0D01*
G01X1864764D02*
X1863976D01*
G01X1864764D02*
X1863976D01*
G01X1895276Y1382677D02*
G03Y1374803I0J-3937D01*
G01X1864567D02*
G03Y1382677I0J3937D01*
G01X1930906D02*
X1895276D01*
G01D02*
G03Y1374803I0J-3937D01*
G01X1864567D02*
G03Y1382677I0J3937D01*
G01X1930906D02*
X1895276D01*
G01X1922083Y-335933D02*
X2311846D01*
G01X1919843Y-152756D02*
G03X1934843Y-137756I0J15000D01*
G01Y-11811D02*
Y-137756D01*
G01X1919843Y-152756D02*
G03X1934843Y-137756I0J15000D01*
G01Y-11811D02*
Y-137756D01*
G01Y-11811D02*
G03X1930906Y-7874I-3937J0D01*
G01X1911220D02*
X1930906D01*
G01X1934843Y3937D02*
Y1370866D01*
G01X1930906Y0D02*
G03X1934843Y3937I0J3937D01*
G01Y-11811D02*
G03X1930906Y-7874I-3937J0D01*
G01X1911220D02*
X1930906D01*
G01Y0D02*
G03X1934843Y3937I0J3937D01*
G01Y1370866D02*
Y3937D01*
G01X1911614Y137933D02*
G03X1913583Y139902I0J1969D01*
G01D02*
Y155650D01*
G01X1910236Y296988D02*
Y158996D01*
G01X1913583Y155650D02*
X1910236Y158996D01*
G01X1912598Y194803D02*
Y196181D01*
G01Y189803D02*
Y191181D01*
G01Y184803D02*
Y186181D01*
G01Y179803D02*
Y181181D01*
G01Y174803D02*
Y176181D01*
G01Y169803D02*
Y171181D01*
G01Y164803D02*
Y166181D01*
G01Y259803D02*
Y261181D01*
G01Y254803D02*
Y256181D01*
G01Y249803D02*
Y251181D01*
G01Y244803D02*
Y246181D01*
G01Y239803D02*
Y241181D01*
G01Y234803D02*
Y236181D01*
G01Y229803D02*
Y231181D01*
G01Y224803D02*
Y226181D01*
G01Y219803D02*
Y221181D01*
G01X1913583Y300335D02*
X1910236Y296988D01*
G01X1913583Y300335D02*
Y316083D01*
G01X1912598Y289803D02*
Y291181D01*
G01Y284803D02*
Y286181D01*
G01Y279803D02*
Y281181D01*
G01Y274803D02*
Y276181D01*
G01Y269803D02*
Y271181D01*
G01Y264803D02*
Y266181D01*
G01X1913583Y316083D02*
G03X1911614Y318051I-1969J-1D01*
G01Y590689D02*
G03X1913583Y592657I0J1969D01*
G01D02*
Y608406D01*
G01X1912598Y647559D02*
Y648937D01*
G01Y642559D02*
Y643937D01*
G01Y637559D02*
Y638937D01*
G01Y632559D02*
Y633937D01*
G01Y627559D02*
Y628937D01*
G01Y622559D02*
Y623937D01*
G01Y617559D02*
Y618937D01*
G01X1910236Y749744D02*
Y611752D01*
G01D02*
X1913583Y608406D01*
G01X1912598Y692559D02*
Y693937D01*
G01Y687559D02*
Y688937D01*
G01Y682559D02*
Y683937D01*
G01Y677559D02*
Y678937D01*
G01Y672559D02*
Y673937D01*
G01Y742559D02*
Y743937D01*
G01Y737559D02*
Y738937D01*
G01Y732559D02*
Y733937D01*
G01Y727559D02*
Y728937D01*
G01Y722559D02*
Y723937D01*
G01Y717559D02*
Y718937D01*
G01Y712559D02*
Y713937D01*
G01Y707559D02*
Y708937D01*
G01Y702559D02*
Y703937D01*
G01Y697559D02*
Y698937D01*
G01X1913583Y768839D02*
G03X1911614Y770807I-1969J-1D01*
G01X1913583Y753091D02*
Y768839D01*
G01Y753091D02*
X1910236Y749744D01*
G01X1911614Y1043445D02*
G03X1913583Y1045413I0J1969D01*
G01D02*
Y1061161D01*
G01X1912598Y1080315D02*
Y1081693D01*
G01Y1075315D02*
Y1076693D01*
G01Y1070315D02*
Y1071693D01*
G01X1910236Y1202500D02*
Y1064508D01*
G01D02*
X1913583Y1061161D01*
G01X1912598Y1130315D02*
Y1131693D01*
G01Y1125315D02*
Y1126693D01*
G01Y1100315D02*
Y1101693D01*
G01Y1095315D02*
Y1096693D01*
G01Y1090315D02*
Y1091693D01*
G01Y1085315D02*
Y1086693D01*
G01Y1175315D02*
Y1176693D01*
G01Y1170315D02*
Y1171693D01*
G01Y1165315D02*
Y1166693D01*
G01Y1160315D02*
Y1161693D01*
G01Y1155315D02*
Y1156693D01*
G01Y1150315D02*
Y1151693D01*
G01Y1145315D02*
Y1146693D01*
G01Y1140315D02*
Y1141693D01*
G01Y1135315D02*
Y1136693D01*
G01X1913583Y1221594D02*
G03X1911614Y1223563I-1969J0D01*
G01X1913583Y1205846D02*
Y1221594D01*
G01X1912598Y1195315D02*
Y1196693D01*
G01Y1190315D02*
Y1191693D01*
G01Y1185315D02*
Y1186693D01*
G01Y1180315D02*
Y1181693D01*
G01X1913583Y1205846D02*
X1910236Y1202500D01*
G01X1934843Y1370866D02*
G03X1930906Y1374803I-3937J0D01*
G01X1934843Y1370866D02*
G03X1930906Y1374803I-3937J0D01*
G01Y1382677D02*
G03X1934843Y1386614I0J3937D01*
G01D02*
Y1643268D01*
G01X1930906Y1382677D02*
G03X1934843Y1386614I0J3937D01*
G01D02*
Y1643268D01*
G01Y1647205D02*
Y1727663D01*
G01Y1643268D02*
G03X1919843Y1658268I-15000J0D01*
G01X1934843Y1643268D02*
G03X1919843Y1658268I-15000J0D01*
G01X2006475Y-322537D02*
Y-66631D01*
G01Y-322537D02*
X2951357D01*
G01Y-262273D02*
X2006475D01*
G01Y-217147D02*
X2537702D01*
G01X2006475Y-126895D02*
X2951357D01*
G01X2006475Y-172021D02*
X2951357D01*
G01X2006475Y-66631D02*
X2951357D01*
G01X2077921Y-335933D02*
Y-354870D01*
G01Y1841823D02*
Y1822886D01*
G01X2123697D02*
X2631571D01*
G01X2195451Y-262273D02*
Y-66752D01*
G01X2296644Y-335933D02*
Y-354870D01*
G01X2311846Y-335933D02*
X2962280D01*
G01X2297590Y1841823D02*
Y1822886D01*
G01X2517260Y-335933D02*
Y-354870D01*
G01X2534034Y-171829D02*
Y-261959D01*
G01X2537702Y-217147D02*
X2951357D01*
G01X2517260Y1841823D02*
Y1822886D01*
G01X2631571D02*
X2962279D01*
G01X2723010Y-171829D02*
Y-261959D01*
G01X2736929Y-335933D02*
Y-354870D01*
G01Y1841823D02*
Y1822886D01*
G01X2951357Y-322537D02*
Y-66752D01*
G01X2962279Y1822886D02*
Y-335933D01*
G01X2962280Y-191248D02*
Y-335933D01*
G01X2962279Y-120051D02*
X2981216D01*
G01X2962279Y95831D02*
X2981216D01*
G01X2962279Y311713D02*
X2981216D01*
G01X2962279Y527595D02*
X2981216D01*
G01X2962279Y743477D02*
X2981216D01*
G01X2962279Y959358D02*
X2981216D01*
G01X2962279Y1175240D02*
X2981216D01*
G01X2962279Y1391122D02*
X2981216D01*
G01X2962090Y1607004D02*
X2981027D01*
G01X2962279Y1822886D02*
Y1728398D01*
G01X2981216Y1841823D02*
Y-354870D01*
M02*
